FILE_TYPE=PINLIST;
{ Packager-XL run on 14-Sep-2023 AT 16:11:04 }
TIME=' COMPILATION ON 14-Sep-2023 AT 16:11:04';
primitive '74CBTLV3126PW-74CBTLV3126PW,SMLF,IC,AL003126K08';body '74CBTLV3126PW';
    '2A':'(5)';BIDI;
    '3B':'(8)';BIDI;
    '1OE':'(1)';IN;
    '2OE':'(4)';OUT;
    '1B':'(3)';BIDI;
    '2B':'(6)';BIDI;
    '1A':'(2)';
    'GND':'(7)';
    '3A':'(9)';BIDI;
    '3OE':'(10)';BIDI;
    '4B':'(11)';BIDI;
    '4A':'(12)';BIDI;
    '4OE':'(13)';BIDI;
    'VCC':'(14)';BIDI;
end_primitive;
primitive '74LV4052PW-74LV4052PW,SMLF,IC,ALLV4052K19';body '74LV4052PW';
    '2Y0':'(1)';BIDI;
    '2Y2':'(2)';BIDI;
    '2Z':'(3)';BIDI;
    '2Y3':'(4)';BIDI;
    '2Y1':'(5)';BIDI;
    'E_N':'(6)';BIDI;
    'VEE':'(7)';
    'GND':'(8)';
    'S1':'(9)';BIDI;
    'S0':'(10)';BIDI;
    '1Y3':'(11)';BIDI;
    '1Y0':'(12)';BIDI;
    '1Z':'(13)';BIDI;
    '1Y1':'(14)';BIDI;
    '1Y2':'(15)';BIDI;
    'VCC':'(16)';
end_primitive;
primitive '74LVC1G07GV-74LVC1G07GV,SMLF,IC,AL1G0007001';body '74LVC1G07GV';
    'VCC':'(5)';
    'A':'(2)';IN;
    'GND':'(3)';
    'Y':'(4)';OUT;
    'NC1':'(1)';OUT;
end_primitive;
primitive '74LVC1G08W57-74LVC1G08W5-7,SMLF,IC,AL1G0008020';body '74LVC1G08W57';
    'A':'(1)';IN;
    'B':'(2)';IN;
    'GND':'(3)';
    'Y':'(4)';OUT;
    'VCC':'(5)';
end_primitive;
primitive '74LVC1G126SE7-74LVC1G126SE-7,SMLF,IC,AL1G0126009';body '74LVC1G126SE7';
    'A':'(2)';IN;
    'Y':'(4)';OUT;
    'VCC':'(5)';
    'GND':'(3)';
    'OE':'(1)';IN;
end_primitive;
primitive '74LVC1G17GW-74LVC1G17GW,SMLF,IC,AL1G0017K01';body '74LVC1G17GW';
    'VCC':'(5)';
    'A':'(2)';IN;
    'GND':'(3)';
    'Y':'(4)';OUT;
    'NC':'(1)';OUT;
end_primitive;
primitive '74LVC1G32GW_SMLF-74LVC1G32GW,IC,ALVC1G32007';body '74LVC1G32GW';
    'I0':'(1)';IN;
    'I1':'(2)';IN;
    'O':'(4)';OUT;
    'VCC':'(5)';
    'GND':'(3)';
end_primitive;
primitive '74LVC1G66GV-74LVC1G66GV,SMLF,IC,AL001G66000';body '74LVC1G66GV';
    'Y':'(1)';BIDI;
    'Z':'(2)';BIDI;
    'GND':'(3)';
    'E':'(4)';IN;
    'VCC':'(5)';
end_primitive;
primitive '74LVC2G07DW7-74LVC2G07DW-7,SMLF,EMPTY,AL002G07003';body '74LVC2G07DW7';
    '1A':'(1)';IN;
    '2A':'(3)';IN;
    '1Y':'(6)';OUT;
    '2Y':'(4)';OUT;
    'GND':'(2)';
    'VCC':'(5)';
end_primitive;
primitive '74LVC2G07DW7-74LVC2G07DW-7,SMLF,IC,AL002G07003';body '74LVC2G07DW7';
    '1A':'(1)';IN;
    '2A':'(3)';IN;
    '1Y':'(6)';OUT;
    '2Y':'(4)';OUT;
    'GND':'(2)';
    'VCC':'(5)';
end_primitive;
primitive '74LVC2G08DP-74LVC2G08DP,SMLF,EMPTY,ALVC2G08K01';body '74LVC2G08DP';
    'VCC':'(8,0)';$S;
    'GND':'(4,0)';$S;
    '1A':'(1,0)';$S;IN;
    '1B':'(2,0)';$S;IN;
    '1Y':'(7,0)';$S;OUT;
    '2A':'(0,5)';$S;IN;
    '2B':'(0,6)';$S;IN;
    '2Y':'(0,3)';$S;OUT;
end_primitive;
primitive '74LVC2G17GW-74LVC2G17GW,SMLF,IC,AL2G0017005';body '74LVC2G17GW';
    'VCC':'(5)';
    'B1':'(4)';OUT;
    'GND':'(2)';
    'A0':'(1)';IN;
    'A1':'(3)';IN;
    'B0':'(6)';OUT;
end_primitive;
primitive '9FGL0251DKILFT-9FGL0251DKILFT,SMLF,IC,AL000251002';body '9FGL0251DKILFT';
    'XIN||CLKIN_25':'(1)';IN;
    'X2':'(2)';OUT;
    'VDDXTAL3.3':'(3)';
    'VSADR||REF3.3':'(4)';BIDI;
    'GNDREF':'(5)';
    'GNDDIG':'(6)';
    'VDDDIG3.3':'(7)';
    'SCLK_3.3':'(8)';IN;
    'SDATA_3.3':'(9)';BIDI;
    'GND_10':'(10)';
    'VDD3.3_11':'(11)';
    'VOE0#':'(12)';IN;
    'DIF0':'(13)';OUT;
    'DIF0#':'(14)';OUT;
    'GNDA':'(15)';
    'VDDA3.3':'(16)';
    'DIF1':'(17)';OUT;
    'DIF1#':'(18)';OUT;
    'VOE1#':'(19)';IN;
    'VDD3.3_20':'(20)';
    'GND_21':'(21)';
    '^CKPWRGD_PD#':'(22)';IN;
    '^VSS_EN_TRI':'(23)';IN;
    'GNDXTAL':'(24)';
    'TH_GND':'(25)';
end_primitive;
primitive '9ZXL0451EKILFT-9ZXL0451EKILFT,SMLF,IC,AL000451003';body '9ZXL0451EKILFT';
    'DIF_IN':'(3)';IN;
    'DIF_IN#':'(4)';IN;
    'VDDR':'(2)';
    'VDD3':'(25)';
    'VDD4':'(29)';
    'FBOUT_NC':'(9)';OUT;
    'VOE0#':'(15)';IN;
    'VOE3#':'(26)';IN;
    'SMBDAT':'(6)';BIDI;
    'NC1':'(11)';OUT;
    'FBOUT_NC#':'(8)';OUT;
    'SMBCLK':'(7)';IN;
    'VDD2':'(21)';
    '^CKPWRGD_PD#':'(1)';IN;
    'DIF0#':'(14)';OUT;
    'DIF0':'(13)';OUT;
    'VOE1#':'(18)';IN;
    'DIF1#':'(20)';OUT;
    'DIF2':'(22)';OUT;
    'VOE2#':'(24)';IN;
    'DIF2#':'(23)';OUT;
    'DIF3#':'(28)';OUT;
    'NC0':'(10)';OUT;
    'VDDA':'(31)';
    'VDD1':'(16)';
    '^HIBW_BYPM_LOBW#':'(32)';IN;
    'EPAD_GND':'(33)';
    'DIF1':'(19)';OUT;
    'DIF3':'(27)';OUT;
    'VDD0':'(12)';
    'NC3':'(30)';OUT;
    'NC2':'(17)';OUT;
    'VSADR0_TRI':'(5)';IN;
end_primitive;
primitive 'ADC128D818CIMTXNOPB-ADC128D818CIMTX/NOPB,SMLF,IC,AA';body 'ADC128D818CIMTXNOPB';
    'VREF':'(1)';IN;
    'V+':'(5)';
    'A0':'(7)';IN;
    'A1':'(8)';IN;
    'IN7':'(9)';IN;
    'IN6':'(10)';IN;
    'IN5':'(11)';IN;
    'IN4':'(12)';IN;
    'IN3':'(13)';IN;
    'IN2':'(14)';IN;
    'IN1':'(15)';IN;
    'IN0':'(16)';IN;
    'SDA':'(2)';BIDI;
    'SCL':'(3)';IN;
    'GND':'(4)';
    'INT#':'(6)';OUT;
end_primitive;
primitive 'AP331AWG7-AP331AWG-7,SMLF,EMPTY,AL000331011';body 'AP331AWG7';
    'IN+':'(3)';IN;
    'IN-':'(1)';IN;
    'OUTPUT':'(4)';OUT;
    'VCC':'(5)';
    'GND':'(2)';
end_primitive;
primitive 'AP331AWG7-AP331AWG-7,SMLF,IC,AL000331011';body 'AP331AWG7';
    'IN+':'(3)';IN;
    'IN-':'(1)';IN;
    'OUTPUT':'(4)';OUT;
    'VCC':'(5)';
    'GND':'(2)';
end_primitive;
primitive 'APX80929SAG7-APX809-29SAG-7,SMLF,IC,AL080929000';body 'APX80929SAG7';
    'VCC':'(3)';
    'RESET_L':'(2)';OUT;
    'GND':'(1)';
end_primitive;
primitive 'BAT547F-BAT547F,SMLF,IC,BC0BAT54Z53';body 'BAT547F';
    '1':'(1)';BIDI;
    '3':'(3)';BIDI;
end_primitive;
primitive 'BSS138DW7F-BSS138DW-7-F,SMLF,IC,BAM01380032';body 'BSS138DW7F';
    'G1':'(2)';BIDI;
    'G2':'(5)';BIDI;
    'S1':'(1)';BIDI;
    'S2':'(4)';BIDI;
    'D1':'(6)';BIDI;
    'D2':'(3)';BIDI;
end_primitive;
primitive 'CONN10_HBC1051L300D8H-CONN10_HBC1051-L300D-8H,THLFA';body 'CONN10_HBC1051L300D8H';
    '1':'(1)';BIDI;
    '2':'(2)';BIDI;
    '3':'(3)';BIDI;
    '4':'(4)';BIDI;
    '5':'(5)';BIDI;
    '6':'(6)';BIDI;
    '7':'(7)';BIDI;
    '9':'(9)';BIDI;
    '8':'(8)';BIDI;
    '10':'(10)';BIDI;
end_primitive;
primitive 'CONN112_10137002101LF-CONN112_10137002-101LF,THLF,A';body 'CONN112_10137002101LF';
    'A8':'(A8,0)';$S;BIDI;
    'A7':'(A7,0)';$S;BIDI;
    'A6':'(A6,0)';$S;BIDI;
    'A5':'(A5,0)';$S;BIDI;
    'B8':'(B8,0)';$S;BIDI;
    'B7':'(B7,0)';$S;BIDI;
    'B6':'(B6,0)';$S;BIDI;
    'B5':'(B5,0)';$S;BIDI;
    'C8':'(C8,0)';$S;BIDI;
    'C7':'(C7,0)';$S;BIDI;
    'C6':'(C6,0)';$S;BIDI;
    'C5':'(C5,0)';$S;BIDI;
    'D8':'(D8,0)';$S;BIDI;
    'D7':'(D7,0)';$S;BIDI;
    'D6':'(D6,0)';$S;BIDI;
    'D5':'(D5,0)';$S;BIDI;
    'E8':'(E8,0)';$S;BIDI;
    'E7':'(E7,0)';$S;BIDI;
    'E6':'(E6,0)';$S;BIDI;
    'E5':'(E5,0)';$S;BIDI;
    'F8':'(F8,0)';$S;BIDI;
    'F7':'(F7,0)';$S;BIDI;
    'F6':'(F6,0)';$S;BIDI;
    'F5':'(F5,0)';$S;BIDI;
    'G8':'(G8,0)';$S;BIDI;
    'G7':'(G7,0)';$S;BIDI;
    'G6':'(G6,0)';$S;BIDI;
    'G5':'(G5,0)';$S;BIDI;
    'H8':'(H8,0)';$S;BIDI;
    'H7':'(H7,0)';$S;BIDI;
    'H6':'(H6,0)';$S;BIDI;
    'H5':'(H5,0)';$S;BIDI;
    'I8':'(I8,0)';$S;BIDI;
    'I7':'(I7,0)';$S;BIDI;
    'I6':'(I6,0)';$S;BIDI;
    'I5':'(I5,0)';$S;BIDI;
    'J8':'(J8,0)';$S;BIDI;
    'J7':'(J7,0)';$S;BIDI;
    'J6':'(J6,0)';$S;BIDI;
    'J5':'(J5,0)';$S;BIDI;
    'K8':'(K8,0)';$S;BIDI;
    'K7':'(K7,0)';$S;BIDI;
    'K6':'(K6,0)';$S;BIDI;
    'K5':'(K5,0)';$S;BIDI;
    'L8':'(L8,0)';$S;BIDI;
    'L7':'(L7,0)';$S;BIDI;
    'L6':'(L6,0)';$S;BIDI;
    'L5':'(L5,0)';$S;BIDI;
    'M5':'(M5,0)';$S;BIDI;
    'N5':'(N5,0)';$S;BIDI;
    'M6':'(M6,0)';$S;BIDI;
    'N6':'(N6,0)';$S;BIDI;
    'M7':'(M7,0)';$S;BIDI;
    'N7':'(N7,0)';$S;BIDI;
    'M8':'(M8,0)';$S;BIDI;
    'N8':'(N8,0)';$S;BIDI;
    'A4':'(0,A4)';$S;BIDI;
    'A3':'(0,A3)';$S;BIDI;
    'A2':'(0,A2)';$S;BIDI;
    'A1':'(0,A1)';$S;BIDI;
    'B4':'(0,B4)';$S;BIDI;
    'B3':'(0,B3)';$S;BIDI;
    'B2':'(0,B2)';$S;BIDI;
    'B1':'(0,B1)';$S;BIDI;
    'C4':'(0,C4)';$S;BIDI;
    'C3':'(0,C3)';$S;BIDI;
    'C2':'(0,C2)';$S;BIDI;
    'C1':'(0,C1)';$S;BIDI;
    'D4':'(0,D4)';$S;BIDI;
    'D3':'(0,D3)';$S;BIDI;
    'D2':'(0,D2)';$S;BIDI;
    'D1':'(0,D1)';$S;BIDI;
    'E4':'(0,E4)';$S;BIDI;
    'E3':'(0,E3)';$S;BIDI;
    'E2':'(0,E2)';$S;BIDI;
    'E1':'(0,E1)';$S;BIDI;
    'F4':'(0,F4)';$S;BIDI;
    'F3':'(0,F3)';$S;BIDI;
    'F2':'(0,F2)';$S;BIDI;
    'F1':'(0,F1)';$S;BIDI;
    'G4':'(0,G4)';$S;BIDI;
    'G3':'(0,G3)';$S;BIDI;
    'G2':'(0,G2)';$S;BIDI;
    'G1':'(0,G1)';$S;BIDI;
    'H4':'(0,H4)';$S;BIDI;
    'H3':'(0,H3)';$S;BIDI;
    'H2':'(0,H2)';$S;BIDI;
    'H1':'(0,H1)';$S;BIDI;
    'I4':'(0,I4)';$S;BIDI;
    'I3':'(0,I3)';$S;BIDI;
    'I2':'(0,I2)';$S;BIDI;
    'I1':'(0,I1)';$S;BIDI;
    'J4':'(0,J4)';$S;BIDI;
    'J3':'(0,J3)';$S;BIDI;
    'J2':'(0,J2)';$S;BIDI;
    'J1':'(0,J1)';$S;BIDI;
    'K4':'(0,K4)';$S;BIDI;
    'K3':'(0,K3)';$S;BIDI;
    'K2':'(0,K2)';$S;BIDI;
    'K1':'(0,K1)';$S;BIDI;
    'L4':'(0,L4)';$S;BIDI;
    'L3':'(0,L3)';$S;BIDI;
    'L2':'(0,L2)';$S;BIDI;
    'L1':'(0,L1)';$S;BIDI;
    'M1':'(0,M1)';$S;BIDI;
    'N1':'(0,N1)';$S;BIDI;
    'M2':'(0,M2)';$S;BIDI;
    'N2':'(0,N2)';$S;BIDI;
    'M3':'(0,M3)';$S;BIDI;
    'N3':'(0,N3)';$S;BIDI;
    'M4':'(0,M4)';$S;BIDI;
    'N4':'(0,N4)';$S;BIDI;
end_primitive;
primitive 'CONN160_10131762101LF-CONN160_10131762-101LF,THLF,A';body 'CONN160_10131762101LF';
    'A8':'(A8,0)';$S;BIDI;
    'A7':'(A7,0)';$S;BIDI;
    'A6':'(A6,0)';$S;BIDI;
    'A5':'(A5,0)';$S;BIDI;
    'B8':'(B8,0)';$S;BIDI;
    'B7':'(B7,0)';$S;BIDI;
    'B6':'(B6,0)';$S;BIDI;
    'B5':'(B5,0)';$S;BIDI;
    'C8':'(C8,0)';$S;BIDI;
    'C7':'(C7,0)';$S;BIDI;
    'C6':'(C6,0)';$S;BIDI;
    'C5':'(C5,0)';$S;BIDI;
    'D8':'(D8,0)';$S;BIDI;
    'D7':'(D7,0)';$S;BIDI;
    'D6':'(D6,0)';$S;BIDI;
    'D5':'(D5,0)';$S;BIDI;
    'E8':'(E8,0)';$S;BIDI;
    'E7':'(E7,0)';$S;BIDI;
    'E6':'(E6,0)';$S;BIDI;
    'E5':'(E5,0)';$S;BIDI;
    'F8':'(F8,0)';$S;BIDI;
    'F7':'(F7,0)';$S;BIDI;
    'F6':'(F6,0)';$S;BIDI;
    'F5':'(F5,0)';$S;BIDI;
    'G8':'(G8,0)';$S;BIDI;
    'G7':'(G7,0)';$S;BIDI;
    'G6':'(G6,0)';$S;BIDI;
    'G5':'(G5,0)';$S;BIDI;
    'H8':'(H8,0)';$S;BIDI;
    'H7':'(H7,0)';$S;BIDI;
    'H6':'(H6,0)';$S;BIDI;
    'H5':'(H5,0)';$S;BIDI;
    'I8':'(I8,0)';$S;BIDI;
    'I7':'(I7,0)';$S;BIDI;
    'I6':'(I6,0)';$S;BIDI;
    'I5':'(I5,0)';$S;BIDI;
    'J8':'(J8,0)';$S;BIDI;
    'J7':'(J7,0)';$S;BIDI;
    'J6':'(J6,0)';$S;BIDI;
    'J5':'(J5,0)';$S;BIDI;
    'K8':'(K8,0)';$S;BIDI;
    'K7':'(K7,0)';$S;BIDI;
    'K6':'(K6,0)';$S;BIDI;
    'K5':'(K5,0)';$S;BIDI;
    'L8':'(L8,0)';$S;BIDI;
    'L7':'(L7,0)';$S;BIDI;
    'L6':'(L6,0)';$S;BIDI;
    'L5':'(L5,0)';$S;BIDI;
    'M5':'(M5,0)';$S;BIDI;
    'N5':'(N5,0)';$S;BIDI;
    'M6':'(M6,0)';$S;BIDI;
    'N6':'(N6,0)';$S;BIDI;
    'M7':'(M7,0)';$S;BIDI;
    'N7':'(N7,0)';$S;BIDI;
    'M8':'(M8,0)';$S;BIDI;
    'N8':'(N8,0)';$S;BIDI;
    'O5':'(O5,0)';$S;BIDI;
    'P5':'(P5,0)';$S;BIDI;
    'Q5':'(Q5,0)';$S;BIDI;
    'R5':'(R5,0)';$S;BIDI;
    'S5':'(S5,0)';$S;BIDI;
    'T5':'(T5,0)';$S;BIDI;
    'O6':'(O6,0)';$S;BIDI;
    'P6':'(P6,0)';$S;BIDI;
    'Q6':'(Q6,0)';$S;BIDI;
    'R6':'(R6,0)';$S;BIDI;
    'S6':'(S6,0)';$S;BIDI;
    'T6':'(T6,0)';$S;BIDI;
    'O7':'(O7,0)';$S;BIDI;
    'P7':'(P7,0)';$S;BIDI;
    'Q7':'(Q7,0)';$S;BIDI;
    'R7':'(R7,0)';$S;BIDI;
    'S7':'(S7,0)';$S;BIDI;
    'T7':'(T7,0)';$S;BIDI;
    'O8':'(O8,0)';$S;BIDI;
    'P8':'(P8,0)';$S;BIDI;
    'Q8':'(Q8,0)';$S;BIDI;
    'R8':'(R8,0)';$S;BIDI;
    'S8':'(S8,0)';$S;BIDI;
    'T8':'(T8,0)';$S;BIDI;
    'A4':'(0,A4)';$S;BIDI;
    'A3':'(0,A3)';$S;BIDI;
    'A2':'(0,A2)';$S;BIDI;
    'A1':'(0,A1)';$S;BIDI;
    'B4':'(0,B4)';$S;BIDI;
    'B3':'(0,B3)';$S;BIDI;
    'B2':'(0,B2)';$S;BIDI;
    'B1':'(0,B1)';$S;BIDI;
    'C4':'(0,C4)';$S;BIDI;
    'C3':'(0,C3)';$S;BIDI;
    'C2':'(0,C2)';$S;BIDI;
    'C1':'(0,C1)';$S;BIDI;
    'D4':'(0,D4)';$S;BIDI;
    'D3':'(0,D3)';$S;BIDI;
    'D2':'(0,D2)';$S;BIDI;
    'D1':'(0,D1)';$S;BIDI;
    'E4':'(0,E4)';$S;BIDI;
    'E3':'(0,E3)';$S;BIDI;
    'E2':'(0,E2)';$S;BIDI;
    'E1':'(0,E1)';$S;BIDI;
    'F4':'(0,F4)';$S;BIDI;
    'F3':'(0,F3)';$S;BIDI;
    'F2':'(0,F2)';$S;BIDI;
    'F1':'(0,F1)';$S;BIDI;
    'G4':'(0,G4)';$S;BIDI;
    'G3':'(0,G3)';$S;BIDI;
    'G2':'(0,G2)';$S;BIDI;
    'G1':'(0,G1)';$S;BIDI;
    'H4':'(0,H4)';$S;BIDI;
    'H3':'(0,H3)';$S;BIDI;
    'H2':'(0,H2)';$S;BIDI;
    'H1':'(0,H1)';$S;BIDI;
    'I4':'(0,I4)';$S;BIDI;
    'I3':'(0,I3)';$S;BIDI;
    'I2':'(0,I2)';$S;BIDI;
    'I1':'(0,I1)';$S;BIDI;
    'J4':'(0,J4)';$S;BIDI;
    'J3':'(0,J3)';$S;BIDI;
    'J2':'(0,J2)';$S;BIDI;
    'J1':'(0,J1)';$S;BIDI;
    'K4':'(0,K4)';$S;BIDI;
    'K3':'(0,K3)';$S;BIDI;
    'K2':'(0,K2)';$S;BIDI;
    'K1':'(0,K1)';$S;BIDI;
    'L4':'(0,L4)';$S;BIDI;
    'L3':'(0,L3)';$S;BIDI;
    'L2':'(0,L2)';$S;BIDI;
    'L1':'(0,L1)';$S;BIDI;
    'M1':'(0,M1)';$S;BIDI;
    'N1':'(0,N1)';$S;BIDI;
    'M2':'(0,M2)';$S;BIDI;
    'N2':'(0,N2)';$S;BIDI;
    'M3':'(0,M3)';$S;BIDI;
    'N3':'(0,N3)';$S;BIDI;
    'M4':'(0,M4)';$S;BIDI;
    'N4':'(0,N4)';$S;BIDI;
    'O1':'(0,O1)';$S;BIDI;
    'P1':'(0,P1)';$S;BIDI;
    'Q1':'(0,Q1)';$S;BIDI;
    'R1':'(0,R1)';$S;BIDI;
    'S1':'(0,S1)';$S;BIDI;
    'T1':'(0,T1)';$S;BIDI;
    'O2':'(0,O2)';$S;BIDI;
    'P2':'(0,P2)';$S;BIDI;
    'Q2':'(0,Q2)';$S;BIDI;
    'R2':'(0,R2)';$S;BIDI;
    'S2':'(0,S2)';$S;BIDI;
    'T2':'(0,T2)';$S;BIDI;
    'O3':'(0,O3)';$S;BIDI;
    'P3':'(0,P3)';$S;BIDI;
    'Q3':'(0,Q3)';$S;BIDI;
    'R3':'(0,R3)';$S;BIDI;
    'S3':'(0,S3)';$S;BIDI;
    'T3':'(0,T3)';$S;BIDI;
    'O4':'(0,O4)';$S;BIDI;
    'P4':'(0,P4)';$S;BIDI;
    'Q4':'(0,Q4)';$S;BIDI;
    'R4':'(0,R4)';$S;BIDI;
    'S4':'(0,S4)';$S;BIDI;
    'T4':'(0,T4)';$S;BIDI;
end_primitive;
primitive 'CONN1_10165288101LF-CONN1_10165288-101LF,THLF,IO,DA';body 'CONN1_10165288101LF';
    'NC1':'(SCR_H1)';BIDI;
end_primitive;
primitive 'CONN2_AAABAT029Y19-CONN2_AAA-BAT-029-Y19,THLF,IO,DA';body 'CONN2_AAABAT029Y19';
    '1':'(1)';
    '2':'(2)';
end_primitive;
primitive 'CONN3_210HP1030BR1-CONN3_210-HP1-030BR1,THLF,IO,DFA';body 'CONN3_210HP1030BR1';
    '3':'(3)';BIDI;
    '2':'(2)';BIDI;
    '1':'(1)';BIDI;
end_primitive;
primitive 'CONN4_HFK1040L0P1L7H-CONN4_HFK1040-L0P1L-7H,THLF,IA';body 'CONN4_HFK1040L0P1L7H';
    '4':'(4)';BIDI;
    '3':'(3)';BIDI;
    '2':'(2)';BIDI;
    '1':'(1)';BIDI;
end_primitive;
primitive 'CONN60_101062636003K02LF-CONN60_10106263-6003K02LFA';body 'CONN60_101062636003K02LF';
    'A2':'(A2)';BIDI;
    'B2':'(B2)';BIDI;
    'C2':'(C2)';BIDI;
    'D2':'(D2)';BIDI;
    'P1_1':'(P1_1)';
    'P1_2':'(P1_2)';
    'P1_3':'(P1_3)';
    'P1_4':'(P1_4)';
    'P1_5':'(P1_5)';
    'P1_6':'(P1_6)';
    'P1_7':'(P1_7)';
    'P1_8':'(P1_8)';
    'P2_1':'(P2_1)';
    'P2_2':'(P2_2)';
    'P2_3':'(P2_3)';
    'P2_4':'(P2_4)';
    'P2_5':'(P2_5)';
    'P2_6':'(P2_6)';
    'P2_7':'(P2_7)';
    'P2_8':'(P2_8)';
    'P4_1':'(P4_1)';
    'P4_2':'(P4_2)';
    'P4_3':'(P4_3)';
    'P4_4':'(P4_4)';
    'P4_5':'(P4_5)';
    'P4_6':'(P4_6)';
    'P4_7':'(P4_7)';
    'P4_8':'(P4_8)';
    'A1':'(A1)';BIDI;
    'B1':'(B1)';BIDI;
    'C1':'(C1)';BIDI;
    'D1':'(D1)';BIDI;
    'P5_1':'(P5_1)';
    'P5_2':'(P5_2)';
    'P5_3':'(P5_3)';
    'P5_4':'(P5_4)';
    'P5_5':'(P5_5)';
    'P5_6':'(P5_6)';
    'P5_7':'(P5_7)';
    'P5_8':'(P5_8)';
    'P3_1':'(P3_1)';
    'P3_2':'(P3_2)';
    'P3_3':'(P3_3)';
    'P3_4':'(P3_4)';
    'P3_5':'(P3_5)';
    'P3_6':'(P3_6)';
    'P3_7':'(P3_7)';
    'P3_8':'(P3_8)';
    'P6_1':'(P6_1)';
    'P6_2':'(P6_2)';
    'P6_3':'(P6_3)';
    'P6_4':'(P6_4)';
    'P6_5':'(P6_5)';
    'P6_6':'(P6_6)';
    'P6_7':'(P6_7)';
    'P6_8':'(P6_8)';
    'A3':'(A3)';BIDI;
    'B3':'(B3)';BIDI;
    'C3':'(C3)';BIDI;
    'D3':'(D3)';BIDI;
end_primitive;
primitive 'CONN6_HBC1031L200D8H-CONN6_HBC1031-L200D-8H,THLF,IA';body 'CONN6_HBC1031L200D8H';
    '1':'(1)';BIDI;
    '2':'(2)';BIDI;
    '3':'(3)';BIDI;
    '4':'(4)';BIDI;
    '5':'(5)';BIDI;
    '6':'(6)';BIDI;
end_primitive;
primitive 'CONN8_HBB1081L200D8H-CONN8_HBB1081-L200D-8H,THLF,IA';body 'CONN8_HBB1081L200D8H';
    '1':'(1)';BIDI;
    '2':'(2)';BIDI;
    '3':'(3)';BIDI;
    '4':'(4)';BIDI;
    '5':'(5)';BIDI;
    '6':'(6)';BIDI;
    '7':'(7)';BIDI;
    '8':'(8)';BIDI;
end_primitive;
primitive 'CYUSB330468LTXI-CYUSB3304-68LTXI,SMLF,IC,AJ0330400A';body 'CYUSB330468LTXI';
    'DS1_DP':'(60,0)';$S;BIDI;
    'DS1_DM':'(59,0)';$S;BIDI;
    'DS1_RXP':'(51,0)';$S;IN;
    'DS1_RXM':'(50,0)';$S;IN;
    'DS1_TXP':'(47,0)';$S;OUT;
    'DS1_TXM':'(48,0)';$S;OUT;
    'DS2_DP':'(62,0)';$S;BIDI;
    'DS2_DM':'(63,0)';$S;BIDI;
    'DS2_RXP':'(45,0)';$S;IN;
    'DS2_RXM':'(44,0)';$S;IN;
    'DS2_TXP':'(41,0)';$S;OUT;
    'DS2_TXM':'(42,0)';$S;OUT;
    'DS3_DP':'(65,0)';$S;BIDI;
    'DS3_DM':'(64,0)';$S;BIDI;
    'DS3_RXP':'(35,0)';$S;IN;
    'DS3_RXM':'(36,0)';$S;IN;
    'DS3_TXP':'(38,0)';$S;OUT;
    'DS3_TXM':'(39,0)';$S;OUT;
    'DS4_DP':'(67,0)';$S;BIDI;
    'DS4_DM':'(68,0)';$S;BIDI;
    'DS4_RXP':'(15,0)';$S;IN;
    'DS4_RXM':'(14,0)';$S;IN;
    'DS4_TXP':'(11,0)';$S;OUT;
    'DS4_TXM':'(12,0)';$S;OUT;
    'VBUS_DS':'(18,0)';$S;
    'I2C_CLK':'(32,0)';$S;BIDI;
    'I2C_DATA':'(33,0)';$S;BIDI;
    'SUSPEND':'(20,0)';$S;BIDI;
    'XTL_IN':'(55,0)';$S;IN;
    'XTL_OUT':'(54,0)';$S;OUT;
    'MODE_SEL0':'(23,0)';$S;IN;
    'MODE_SEL1':'(24,0)';$S;IN;
    'GND':'(40,0)';$S;
    'VBUS_US':'(17,0)';$S;
    'US_DP':'(57,0)';$S;BIDI;
    'US_DM':'(58,0)';$S;BIDI;
    'US_RXP':'(9,0)';$S;IN;
    'US_RXM':'(8,0)';$S;IN;
    'US_TXP':'(6,0)';$S;OUT;
    'US_TXM':'(5,0)';$S;OUT;
    'RREF_SS':'(26,0)';$S;BIDI;
    'RREF_USB2':'(2,0)';$S;BIDI;
    'NC_25':'(25,0)';$S;OUT;
    'PWR_EN':'(29,0)';$S;BIDI;
    'OVRCURR':'(30,0)';$S;IN;
    'RESET#':'(31,0)';$S;IN;
    'RESERVED2':'(22,0)';$S;BIDI;
    'RESERVED1':'(21,0)';$S;BIDI;
    'EPAD':'(TH,0)';$S;
    'DVDD12_1':'(0,1)';$S;
    'DVDD12_2':'(0,3)';$S;
    'VDD_EFUSE':'(0,19)';$S;
    'DVDD12_3':'(0,27)';$S;
    'DVDD12_8':'(0,43)';$S;
    'DVDD12_4':'(0,49)';$S;
    'AVDD12_6':'(0,53)';$S;
    'DVDD12_5':'(0,7)';$S;
    'DVDD12_6':'(0,13)';$S;
    'DVDD12_7':'(0,37)';$S;
    'AVDD33_1':'(0,4)';$S;
    'AVDD33_2':'(0,56)';$S;
    'AVDD33_3':'(0,61)';$S;
    'AVDD33_4':'(0,66)';$S;
    'VDD_IO':'(0,28)';$S;
    'AVDD12_1':'(0,10)';$S;
    'AVDD12_2':'(0,16)';$S;
    'AVDD12_3':'(0,34)';$S;
    'AVDD12_4':'(0,46)';$S;
    'AVDD12_5':'(0,52)';$S;
end_primitive;
primitive 'DIODE_TVS-SMF14A,SMLF,IC,BCSMF14AZ01';body 'DIODE_TVS';
    'A':'(A)';IN;
    'C':'(C)';OUT;
end_primitive;
primitive 'DS125BR111RTWR-DS125BR111RTWR,SMLF,IC,AL000125003';body 'DS125BR111RTWR';
    'EQB0||AD3':'(1)';IN;
    'EQB1||AD2':'(2)';IN;
    'ENSMB':'(3)';IN;
    'SDA||VODA_DB':'(4)';BIDI;
    'SCL||VODB_DB':'(5)';BIDI;
    'PWDN':'(6)';IN;
    'OUTA+':'(7)';OUT;
    'OUTA-':'(8)';OUT;
    'EQA1||AD1':'(9)';IN;
    'EQA0||AD0':'(10)';IN;
    'INB+':'(11)';IN;
    'INB-':'(12)';IN;
    'RES':'(13)';IN;
    'SD_TH':'(14)';IN;
    'VIN':'(15)';
    'VDD_SEL':'(16)';IN;
    'VOD_SEL||READEN#':'(17)';IN;
    'RXDET||DONE#':'(18)';BIDI;
    'OUTB-':'(19)';OUT;
    'OUTB+':'(20)';OUT;
    'VDD_21':'(21)';
    'VDD_22':'(22)';
    'INA-':'(23)';IN;
    'INA+':'(24)';IN;
    'TH_GND':'(25)';
end_primitive;
primitive 'GENOA_SP5-SOCKET6096_13568-001,SMLF,IO,DGA^6000030';body 'GENOA_SP5';
    'MA_ALERT_L':'(AR74,0,0,0,0,0,0,0,0,0,0,0,0,0,0,0,0,0,0,0,0,0,0,0,0,0,0,0,0,~
0,0,0,0,0,0,0,0,0,0,0)';$S;IN;
    'MA_RESET_L':'(AT74,0,0,0,0,0,0,0,0,0,0,0,0,0,0,0,0,0,0,0,0,0,0,0,0,0,0,0,0,~
0,0,0,0,0,0,0,0,0,0,0)';$S;OUT;
    'MAB_DQS_L5':'(CE73,0,0,0,0,0,0,0,0,0,0,0,0,0,0,0,0,0,0,0,0,0,0,0,0,0,0,0,0,~
0,0,0,0,0,0,0,0,0,0,0)';$S;BIDI;
    'MAB_DQS_H1':'(CK74,0,0,0,0,0,0,0,0,0,0,0,0,0,0,0,0,0,0,0,0,0,0,0,0,0,0,0,0,~
0,0,0,0,0,0,0,0,0,0,0)';$S;BIDI;
    'MAB_DATA29':'(DE73,0,0,0,0,0,0,0,0,0,0,0,0,0,0,0,0,0,0,0,0,0,0,0,0,0,0,0,0,~
0,0,0,0,0,0,0,0,0,0,0)';$S;BIDI;
    'MAB_DATA18':'(CR74,0,0,0,0,0,0,0,0,0,0,0,0,0,0,0,0,0,0,0,0,0,0,0,0,0,0,0,0,~
0,0,0,0,0,0,0,0,0,0,0)';$S;BIDI;
    'MAB_DATA3':'(CD72,0,0,0,0,0,0,0,0,0,0,0,0,0,0,0,0,0,0,0,0,0,0,0,0,0,0,0,0,0~
,0,0,0,0,0,0,0,0,0,0)';$S;BIDI;
    'MAA_DQS_H7':'(AA73,0,0,0,0,0,0,0,0,0,0,0,0,0,0,0,0,0,0,0,0,0,0,0,0,0,0,0,0,~
0,0,0,0,0,0,0,0,0,0,0)';$S;BIDI;
    'MAA_DATA4':'(J74,0,0,0,0,0,0,0,0,0,0,0,0,0,0,0,0,0,0,0,0,0,0,0,0,0,0,0,0,0,~
0,0,0,0,0,0,0,0,0,0)';$S;BIDI;
    'MAA1_CS_L0':'(AU74,0,0,0,0,0,0,0,0,0,0,0,0,0,0,0,0,0,0,0,0,0,0,0,0,0,0,0,0,~
0,0,0,0,0,0,0,0,0,0,0)';$S;OUT;
    'MAA0_CS_L1':'(AW73,0,0,0,0,0,0,0,0,0,0,0,0,0,0,0,0,0,0,0,0,0,0,0,0,0,0,0,0,~
0,0,0,0,0,0,0,0,0,0,0)';$S;OUT;
    'MAB_DQS_L6':'(CL73,0,0,0,0,0,0,0,0,0,0,0,0,0,0,0,0,0,0,0,0,0,0,0,0,0,0,0,0,~
0,0,0,0,0,0,0,0,0,0,0)';$S;BIDI;
    'MAB_DQS_H2':'(CT74,0,0,0,0,0,0,0,0,0,0,0,0,0,0,0,0,0,0,0,0,0,0,0,0,0,0,0,0,~
0,0,0,0,0,0,0,0,0,0,0)';$S;BIDI;
    'MAB_DATA19':'(CT72,0,0,0,0,0,0,0,0,0,0,0,0,0,0,0,0,0,0,0,0,0,0,0,0,0,0,0,0,~
0,0,0,0,0,0,0,0,0,0,0)';$S;BIDI;
    'MAB_DATA4':'(CF74,0,0,0,0,0,0,0,0,0,0,0,0,0,0,0,0,0,0,0,0,0,0,0,0,0,0,0,0,0~
,0,0,0,0,0,0,0,0,0,0)';$S;BIDI;
    'MAA_DQS_H8':'(AG73,0,0,0,0,0,0,0,0,0,0,0,0,0,0,0,0,0,0,0,0,0,0,0,0,0,0,0,0,~
0,0,0,0,0,0,0,0,0,0,0)';$S;BIDI;
    'MAA_DATA30':'(AH74,0,0,0,0,0,0,0,0,0,0,0,0,0,0,0,0,0,0,0,0,0,0,0,0,0,0,0,0,~
0,0,0,0,0,0,0,0,0,0,0)';$S;BIDI;
    'MAA_DATA5':'(K72,0,0,0,0,0,0,0,0,0,0,0,0,0,0,0,0,0,0,0,0,0,0,0,0,0,0,0,0,0,~
0,0,0,0,0,0,0,0,0,0)';$S;BIDI;
    'MAA1_CS_L1':'(AV72,0,0,0,0,0,0,0,0,0,0,0,0,0,0,0,0,0,0,0,0,0,0,0,0,0,0,0,0,~
0,0,0,0,0,0,0,0,0,0,0)';$S;OUT;
    'MAB_DQS_L7':'(CU73,0,0,0,0,0,0,0,0,0,0,0,0,0,0,0,0,0,0,0,0,0,0,0,0,0,0,0,0,~
0,0,0,0,0,0,0,0,0,0,0)';$S;BIDI;
    'MAB_DQS_H3':'(DB74,0,0,0,0,0,0,0,0,0,0,0,0,0,0,0,0,0,0,0,0,0,0,0,0,0,0,0,0,~
0,0,0,0,0,0,0,0,0,0,0)';$S;BIDI;
    'MAB_DATA5':'(CG73,0,0,0,0,0,0,0,0,0,0,0,0,0,0,0,0,0,0,0,0,0,0,0,0,0,0,0,0,0~
,0,0,0,0,0,0,0,0,0,0)';$S;BIDI;
    'MAA_DQS_H9':'(AN73,0,0,0,0,0,0,0,0,0,0,0,0,0,0,0,0,0,0,0,0,0,0,0,0,0,0,0,0,~
0,0,0,0,0,0,0,0,0,0,0)';$S;BIDI;
    'MAA_DATA31':'(AJ73,0,0,0,0,0,0,0,0,0,0,0,0,0,0,0,0,0,0,0,0,0,0,0,0,0,0,0,0,~
0,0,0,0,0,0,0,0,0,0,0)';$S;BIDI;
    'MAA_DATA20':'(AA74,0,0,0,0,0,0,0,0,0,0,0,0,0,0,0,0,0,0,0,0,0,0,0,0,0,0,0,0,~
0,0,0,0,0,0,0,0,0,0,0)';$S;BIDI;
    'MAA_DATA6':'(K74,0,0,0,0,0,0,0,0,0,0,0,0,0,0,0,0,0,0,0,0,0,0,0,0,0,0,0,0,0,~
0,0,0,0,0,0,0,0,0,0)';$S;BIDI;
    'MAA_CHECK0':'(AJ74,0,0,0,0,0,0,0,0,0,0,0,0,0,0,0,0,0,0,0,0,0,0,0,0,0,0,0,0,~
0,0,0,0,0,0,0,0,0,0,0)';$S;BIDI;
    'MAB_DQS_L8':'(DC73,0,0,0,0,0,0,0,0,0,0,0,0,0,0,0,0,0,0,0,0,0,0,0,0,0,0,0,0,~
0,0,0,0,0,0,0,0,0,0,0)';$S;BIDI;
    'MAB_DQS_H4':'(BY72,0,0,0,0,0,0,0,0,0,0,0,0,0,0,0,0,0,0,0,0,0,0,0,0,0,0,0,0,~
0,0,0,0,0,0,0,0,0,0,0)';$S;BIDI;
    'MAB_DATA6':'(CG74,0,0,0,0,0,0,0,0,0,0,0,0,0,0,0,0,0,0,0,0,0,0,0,0,0,0,0,0,0~
,0,0,0,0,0,0,0,0,0,0)';$S;BIDI;
    'MAA_DATA21':'(AB72,0,0,0,0,0,0,0,0,0,0,0,0,0,0,0,0,0,0,0,0,0,0,0,0,0,0,0,0,~
0,0,0,0,0,0,0,0,0,0,0)';$S;BIDI;
    'MAA_DATA10':'(M74,0,0,0,0,0,0,0,0,0,0,0,0,0,0,0,0,0,0,0,0,0,0,0,0,0,0,0,0,0~
,0,0,0,0,0,0,0,0,0,0)';$S;BIDI;
    'MAA_DATA7':'(L73,0,0,0,0,0,0,0,0,0,0,0,0,0,0,0,0,0,0,0,0,0,0,0,0,0,0,0,0,0,~
0,0,0,0,0,0,0,0,0,0)';$S;BIDI;
    'MAA_CHECK1':'(AK72,0,0,0,0,0,0,0,0,0,0,0,0,0,0,0,0,0,0,0,0,0,0,0,0,0,0,0,0,~
0,0,0,0,0,0,0,0,0,0,0)';$S;BIDI;
    'MAB_DQS_L9':'(BW74,0,0,0,0,0,0,0,0,0,0,0,0,0,0,0,0,0,0,0,0,0,0,0,0,0,0,0,0,~
0,0,0,0,0,0,0,0,0,0,0)';$S;BIDI;
    'MAB_DQS_H5':'(CF72,0,0,0,0,0,0,0,0,0,0,0,0,0,0,0,0,0,0,0,0,0,0,0,0,0,0,0,0,~
0,0,0,0,0,0,0,0,0,0,0)';$S;BIDI;
    'MAB_DATA7':'(CH72,0,0,0,0,0,0,0,0,0,0,0,0,0,0,0,0,0,0,0,0,0,0,0,0,0,0,0,0,0~
,0,0,0,0,0,0,0,0,0,0)';$S;BIDI;
    'MAA_DATA22':'(AB74,0,0,0,0,0,0,0,0,0,0,0,0,0,0,0,0,0,0,0,0,0,0,0,0,0,0,0,0,~
0,0,0,0,0,0,0,0,0,0,0)';$S;BIDI;
    'MAA_DATA11':'(N73,0,0,0,0,0,0,0,0,0,0,0,0,0,0,0,0,0,0,0,0,0,0,0,0,0,0,0,0,0~
,0,0,0,0,0,0,0,0,0,0)';$S;BIDI;
    'MAA_DATA8':'(L74,0,0,0,0,0,0,0,0,0,0,0,0,0,0,0,0,0,0,0,0,0,0,0,0,0,0,0,0,0,~
0,0,0,0,0,0,0,0,0,0)';$S;BIDI;
    'MAA_CHECK2':'(AK74,0,0,0,0,0,0,0,0,0,0,0,0,0,0,0,0,0,0,0,0,0,0,0,0,0,0,0,0,~
0,0,0,0,0,0,0,0,0,0,0)';$S;BIDI;
    'MAB_DQS_H6':'(CM72,0,0,0,0,0,0,0,0,0,0,0,0,0,0,0,0,0,0,0,0,0,0,0,0,0,0,0,0,~
0,0,0,0,0,0,0,0,0,0,0)';$S;BIDI;
    'MAB_DATA8':'(CH74,0,0,0,0,0,0,0,0,0,0,0,0,0,0,0,0,0,0,0,0,0,0,0,0,0,0,0,0,0~
,0,0,0,0,0,0,0,0,0,0)';$S;BIDI;
    'MAB0_CS_L0':'(BM72,0,0,0,0,0,0,0,0,0,0,0,0,0,0,0,0,0,0,0,0,0,0,0,0,0,0,0,0,~
0,0,0,0,0,0,0,0,0,0,0)';$S;OUT;
    'MAA_DATA23':'(AC73,0,0,0,0,0,0,0,0,0,0,0,0,0,0,0,0,0,0,0,0,0,0,0,0,0,0,0,0,~
0,0,0,0,0,0,0,0,0,0,0)';$S;BIDI;
    'MAA_DATA12':'(R74,0,0,0,0,0,0,0,0,0,0,0,0,0,0,0,0,0,0,0,0,0,0,0,0,0,0,0,0,0~
,0,0,0,0,0,0,0,0,0,0)';$S;BIDI;
    'MAA_DATA9':'(M72,0,0,0,0,0,0,0,0,0,0,0,0,0,0,0,0,0,0,0,0,0,0,0,0,0,0,0,0,0,~
0,0,0,0,0,0,0,0,0,0)';$S;BIDI;
    'MAA_CHECK3':'(AL73,0,0,0,0,0,0,0,0,0,0,0,0,0,0,0,0,0,0,0,0,0,0,0,0,0,0,0,0,~
0,0,0,0,0,0,0,0,0,0,0)';$S;BIDI;
    'MAB_DQS_H7':'(CV72,0,0,0,0,0,0,0,0,0,0,0,0,0,0,0,0,0,0,0,0,0,0,0,0,0,0,0,0,~
0,0,0,0,0,0,0,0,0,0,0)';$S;BIDI;
    'MAB_DATA9':'(CJ73,0,0,0,0,0,0,0,0,0,0,0,0,0,0,0,0,0,0,0,0,0,0,0,0,0,0,0,0,0~
,0,0,0,0,0,0,0,0,0,0)';$S;BIDI;
    'MAB1_CS_L0':'(BL73,0,0,0,0,0,0,0,0,0,0,0,0,0,0,0,0,0,0,0,0,0,0,0,0,0,0,0,0,~
0,0,0,0,0,0,0,0,0,0,0)';$S;OUT;
    'MAB0_CS_L1':'(BN74,0,0,0,0,0,0,0,0,0,0,0,0,0,0,0,0,0,0,0,0,0,0,0,0,0,0,0,0,~
0,0,0,0,0,0,0,0,0,0,0)';$S;OUT;
    'MAA_DQS_L0':'(H74,0,0,0,0,0,0,0,0,0,0,0,0,0,0,0,0,0,0,0,0,0,0,0,0,0,0,0,0,0~
,0,0,0,0,0,0,0,0,0,0)';$S;BIDI;
    'MAA_DATA24':'(AC74,0,0,0,0,0,0,0,0,0,0,0,0,0,0,0,0,0,0,0,0,0,0,0,0,0,0,0,0,~
0,0,0,0,0,0,0,0,0,0,0)';$S;BIDI;
    'MAA_DATA13':'(T72,0,0,0,0,0,0,0,0,0,0,0,0,0,0,0,0,0,0,0,0,0,0,0,0,0,0,0,0,0~
,0,0,0,0,0,0,0,0,0,0)';$S;BIDI;
    'MAA_CHECK4':'(AN74,0,0,0,0,0,0,0,0,0,0,0,0,0,0,0,0,0,0,0,0,0,0,0,0,0,0,0,0,~
0,0,0,0,0,0,0,0,0,0,0)';$S;BIDI;
    'MAB_DQS_H8':'(DD72,0,0,0,0,0,0,0,0,0,0,0,0,0,0,0,0,0,0,0,0,0,0,0,0,0,0,0,0,~
0,0,0,0,0,0,0,0,0,0,0)';$S;BIDI;
    'MAB_DATA30':'(DE74,0,0,0,0,0,0,0,0,0,0,0,0,0,0,0,0,0,0,0,0,0,0,0,0,0,0,0,0,~
0,0,0,0,0,0,0,0,0,0,0)';$S;BIDI;
    'MAB1_CS_L1':'(BM74,0,0,0,0,0,0,0,0,0,0,0,0,0,0,0,0,0,0,0,0,0,0,0,0,0,0,0,0,~
0,0,0,0,0,0,0,0,0,0,0)';$S;OUT;
    'MAA_DQS_L1':'(P74,0,0,0,0,0,0,0,0,0,0,0,0,0,0,0,0,0,0,0,0,0,0,0,0,0,0,0,0,0~
,0,0,0,0,0,0,0,0,0,0)';$S;BIDI;
    'MAA_DATA25':'(AD72,0,0,0,0,0,0,0,0,0,0,0,0,0,0,0,0,0,0,0,0,0,0,0,0,0,0,0,0,~
0,0,0,0,0,0,0,0,0,0,0)';$S;BIDI;
    'MAA_DATA14':'(T74,0,0,0,0,0,0,0,0,0,0,0,0,0,0,0,0,0,0,0,0,0,0,0,0,0,0,0,0,0~
,0,0,0,0,0,0,0,0,0,0)';$S;BIDI;
    'MAA_CHECK5':'(AP72,0,0,0,0,0,0,0,0,0,0,0,0,0,0,0,0,0,0,0,0,0,0,0,0,0,0,0,0,~
0,0,0,0,0,0,0,0,0,0,0)';$S;BIDI;
    'MAB_DATA31':'(DF74,0,0,0,0,0,0,0,0,0,0,0,0,0,0,0,0,0,0,0,0,0,0,0,0,0,0,0,0,~
0,0,0,0,0,0,0,0,0,0,0)';$S;BIDI;
    'MAB_DATA20':'(CV74,0,0,0,0,0,0,0,0,0,0,0,0,0,0,0,0,0,0,0,0,0,0,0,0,0,0,0,0,~
0,0,0,0,0,0,0,0,0,0,0)';$S;BIDI;
    'MAB_CHECK0':'(BY74,0,0,0,0,0,0,0,0,0,0,0,0,0,0,0,0,0,0,0,0,0,0,0,0,0,0,0,0,~
0,0,0,0,0,0,0,0,0,0,0)';$S;BIDI;
    'MAA_DQS_L2':'(Y74,0,0,0,0,0,0,0,0,0,0,0,0,0,0,0,0,0,0,0,0,0,0,0,0,0,0,0,0,0~
,0,0,0,0,0,0,0,0,0,0)';$S;BIDI;
    'MAA_DATA26':'(AD74,0,0,0,0,0,0,0,0,0,0,0,0,0,0,0,0,0,0,0,0,0,0,0,0,0,0,0,0,~
0,0,0,0,0,0,0,0,0,0,0)';$S;BIDI;
    'MAA_DATA15':'(U73,0,0,0,0,0,0,0,0,0,0,0,0,0,0,0,0,0,0,0,0,0,0,0,0,0,0,0,0,0~
,0,0,0,0,0,0,0,0,0,0)';$S;BIDI;
    'MAA_CHECK6':'(AP74,0,0,0,0,0,0,0,0,0,0,0,0,0,0,0,0,0,0,0,0,0,0,0,0,0,0,0,0,~
0,0,0,0,0,0,0,0,0,0,0)';$S;BIDI;
    'MAA0_RSP_L':'(BN73,0,0,0,0,0,0,0,0,0,0,0,0,0,0,0,0,0,0,0,0,0,0,0,0,0,0,0,0,~
0,0,0,0,0,0,0,0,0,0,0)';$S;IN;
    'MAB_DATA21':'(CW73,0,0,0,0,0,0,0,0,0,0,0,0,0,0,0,0,0,0,0,0,0,0,0,0,0,0,0,0,~
0,0,0,0,0,0,0,0,0,0,0)';$S;BIDI;
    'MAB_DATA10':'(CJ74,0,0,0,0,0,0,0,0,0,0,0,0,0,0,0,0,0,0,0,0,0,0,0,0,0,0,0,0,~
0,0,0,0,0,0,0,0,0,0,0)';$S;BIDI;
    'MAB_CHECK1':'(CA73,0,0,0,0,0,0,0,0,0,0,0,0,0,0,0,0,0,0,0,0,0,0,0,0,0,0,0,0,~
0,0,0,0,0,0,0,0,0,0,0)';$S;BIDI;
    'MAA_DQS_L3':'(AF74,0,0,0,0,0,0,0,0,0,0,0,0,0,0,0,0,0,0,0,0,0,0,0,0,0,0,0,0,~
0,0,0,0,0,0,0,0,0,0,0)';$S;BIDI;
    'MAA_DATA27':'(AE73,0,0,0,0,0,0,0,0,0,0,0,0,0,0,0,0,0,0,0,0,0,0,0,0,0,0,0,0,~
0,0,0,0,0,0,0,0,0,0,0)';$S;BIDI;
    'MAA_DATA16':'(U74,0,0,0,0,0,0,0,0,0,0,0,0,0,0,0,0,0,0,0,0,0,0,0,0,0,0,0,0,0~
,0,0,0,0,0,0,0,0,0,0)';$S;BIDI;
    'MAA_CHECK7':'(AR73,0,0,0,0,0,0,0,0,0,0,0,0,0,0,0,0,0,0,0,0,0,0,0,0,0,0,0,0,~
0,0,0,0,0,0,0,0,0,0,0)';$S;BIDI;
    'MAA_CA0':'(AW74,0,0,0,0,0,0,0,0,0,0,0,0,0,0,0,0,0,0,0,0,0,0,0,0,0,0,0,0,0,0~
,0,0,0,0,0,0,0,0,0)';$S;OUT;
    'MAA1_RSP_L':'(BP72,0,0,0,0,0,0,0,0,0,0,0,0,0,0,0,0,0,0,0,0,0,0,0,0,0,0,0,0,~
0,0,0,0,0,0,0,0,0,0,0)';$S;IN;
    'MAB_DATA22':'(CW74,0,0,0,0,0,0,0,0,0,0,0,0,0,0,0,0,0,0,0,0,0,0,0,0,0,0,0,0,~
0,0,0,0,0,0,0,0,0,0,0)';$S;BIDI;
    'MAB_DATA11':'(CK72,0,0,0,0,0,0,0,0,0,0,0,0,0,0,0,0,0,0,0,0,0,0,0,0,0,0,0,0,~
0,0,0,0,0,0,0,0,0,0,0)';$S;BIDI;
    'MAB_CHECK2':'(CA74,0,0,0,0,0,0,0,0,0,0,0,0,0,0,0,0,0,0,0,0,0,0,0,0,0,0,0,0,~
0,0,0,0,0,0,0,0,0,0,0)';$S;BIDI;
    'MAB_CA0':'(BG73,0,0,0,0,0,0,0,0,0,0,0,0,0,0,0,0,0,0,0,0,0,0,0,0,0,0,0,0,0,0~
,0,0,0,0,0,0,0,0,0)';$S;OUT;
    'MAA_DQS_L4':'(AM74,0,0,0,0,0,0,0,0,0,0,0,0,0,0,0,0,0,0,0,0,0,0,0,0,0,0,0,0,~
0,0,0,0,0,0,0,0,0,0,0)';$S;BIDI;
    'MAA_DQS_H0':'(G74,0,0,0,0,0,0,0,0,0,0,0,0,0,0,0,0,0,0,0,0,0,0,0,0,0,0,0,0,0~
,0,0,0,0,0,0,0,0,0,0)';$S;BIDI;
    'MAA_DATA28':'(AG74,0,0,0,0,0,0,0,0,0,0,0,0,0,0,0,0,0,0,0,0,0,0,0,0,0,0,0,0,~
0,0,0,0,0,0,0,0,0,0,0)';$S;BIDI;
    'MAA_DATA17':'(V72,0,0,0,0,0,0,0,0,0,0,0,0,0,0,0,0,0,0,0,0,0,0,0,0,0,0,0,0,0~
,0,0,0,0,0,0,0,0,0,0)';$S;BIDI;
    'MAA_CA1':'(AY74,0,0,0,0,0,0,0,0,0,0,0,0,0,0,0,0,0,0,0,0,0,0,0,0,0,0,0,0,0,0~
,0,0,0,0,0,0,0,0,0)';$S;OUT;
    'MAB_DATA23':'(CY72,0,0,0,0,0,0,0,0,0,0,0,0,0,0,0,0,0,0,0,0,0,0,0,0,0,0,0,0,~
0,0,0,0,0,0,0,0,0,0,0)';$S;BIDI;
    'MAB_DATA12':'(CM74,0,0,0,0,0,0,0,0,0,0,0,0,0,0,0,0,0,0,0,0,0,0,0,0,0,0,0,0,~
0,0,0,0,0,0,0,0,0,0,0)';$S;BIDI;
    'MAB_CHECK3':'(CB72,0,0,0,0,0,0,0,0,0,0,0,0,0,0,0,0,0,0,0,0,0,0,0,0,0,0,0,0,~
0,0,0,0,0,0,0,0,0,0,0)';$S;BIDI;
    'MAB_CA1':'(BH72,0,0,0,0,0,0,0,0,0,0,0,0,0,0,0,0,0,0,0,0,0,0,0,0,0,0,0,0,0,0~
,0,0,0,0,0,0,0,0,0)';$S;OUT;
    'MAA_DQS_L5':'(H72,0,0,0,0,0,0,0,0,0,0,0,0,0,0,0,0,0,0,0,0,0,0,0,0,0,0,0,0,0~
,0,0,0,0,0,0,0,0,0,0)';$S;BIDI;
    'MAA_DQS_H1':'(N74,0,0,0,0,0,0,0,0,0,0,0,0,0,0,0,0,0,0,0,0,0,0,0,0,0,0,0,0,0~
,0,0,0,0,0,0,0,0,0,0)';$S;BIDI;
    'MAA_DATA29':'(AH72,0,0,0,0,0,0,0,0,0,0,0,0,0,0,0,0,0,0,0,0,0,0,0,0,0,0,0,0,~
0,0,0,0,0,0,0,0,0,0,0)';$S;BIDI;
    'MAA_DATA18':'(V74,0,0,0,0,0,0,0,0,0,0,0,0,0,0,0,0,0,0,0,0,0,0,0,0,0,0,0,0,0~
,0,0,0,0,0,0,0,0,0,0)';$S;BIDI;
    'MAA_CA2':'(AY72,0,0,0,0,0,0,0,0,0,0,0,0,0,0,0,0,0,0,0,0,0,0,0,0,0,0,0,0,0,0~
,0,0,0,0,0,0,0,0,0)';$S;OUT;
    'MAB_DQS_L0':'(CE74,0,0,0,0,0,0,0,0,0,0,0,0,0,0,0,0,0,0,0,0,0,0,0,0,0,0,0,0,~
0,0,0,0,0,0,0,0,0,0,0)';$S;BIDI;
    'MAB_DATA24':'(CY74,0,0,0,0,0,0,0,0,0,0,0,0,0,0,0,0,0,0,0,0,0,0,0,0,0,0,0,0,~
0,0,0,0,0,0,0,0,0,0,0)';$S;BIDI;
    'MAB_DATA13':'(CN73,0,0,0,0,0,0,0,0,0,0,0,0,0,0,0,0,0,0,0,0,0,0,0,0,0,0,0,0,~
0,0,0,0,0,0,0,0,0,0,0)';$S;BIDI;
    'MAB_CHECK4':'(BT74,0,0,0,0,0,0,0,0,0,0,0,0,0,0,0,0,0,0,0,0,0,0,0,0,0,0,0,0,~
0,0,0,0,0,0,0,0,0,0,0)';$S;BIDI;
    'MAB_CA2':'(BH74,0,0,0,0,0,0,0,0,0,0,0,0,0,0,0,0,0,0,0,0,0,0,0,0,0,0,0,0,0,0~
,0,0,0,0,0,0,0,0,0)';$S;OUT;
    'MAA_DQS_L6':'(P72,0,0,0,0,0,0,0,0,0,0,0,0,0,0,0,0,0,0,0,0,0,0,0,0,0,0,0,0,0~
,0,0,0,0,0,0,0,0,0,0)';$S;BIDI;
    'MAA_DQS_H2':'(W74,0,0,0,0,0,0,0,0,0,0,0,0,0,0,0,0,0,0,0,0,0,0,0,0,0,0,0,0,0~
,0,0,0,0,0,0,0,0,0,0)';$S;BIDI;
    'MAA_DATA19':'(W73,0,0,0,0,0,0,0,0,0,0,0,0,0,0,0,0,0,0,0,0,0,0,0,0,0,0,0,0,0~
,0,0,0,0,0,0,0,0,0,0)';$S;BIDI;
    'MAA_CA3':'(BA73,0,0,0,0,0,0,0,0,0,0,0,0,0,0,0,0,0,0,0,0,0,0,0,0,0,0,0,0,0,0~
,0,0,0,0,0,0,0,0,0)';$S;OUT;
    'MAB_DQS_L1':'(CL74,0,0,0,0,0,0,0,0,0,0,0,0,0,0,0,0,0,0,0,0,0,0,0,0,0,0,0,0,~
0,0,0,0,0,0,0,0,0,0,0)';$S;BIDI;
    'MAB_DATA25':'(DA73,0,0,0,0,0,0,0,0,0,0,0,0,0,0,0,0,0,0,0,0,0,0,0,0,0,0,0,0,~
0,0,0,0,0,0,0,0,0,0,0)';$S;BIDI;
    'MAB_DATA14':'(CN74,0,0,0,0,0,0,0,0,0,0,0,0,0,0,0,0,0,0,0,0,0,0,0,0,0,0,0,0,~
0,0,0,0,0,0,0,0,0,0,0)';$S;BIDI;
    'MAB_CHECK5':'(BU73,0,0,0,0,0,0,0,0,0,0,0,0,0,0,0,0,0,0,0,0,0,0,0,0,0,0,0,0,~
0,0,0,0,0,0,0,0,0,0,0)';$S;BIDI;
    'MAB_CA3':'(BJ74,0,0,0,0,0,0,0,0,0,0,0,0,0,0,0,0,0,0,0,0,0,0,0,0,0,0,0,0,0,0~
,0,0,0,0,0,0,0,0,0)';$S;OUT;
    'MAA_DQS_L7':'(Y72,0,0,0,0,0,0,0,0,0,0,0,0,0,0,0,0,0,0,0,0,0,0,0,0,0,0,0,0,0~
,0,0,0,0,0,0,0,0,0,0)';$S;BIDI;
    'MAA_DQS_H3':'(AE74,0,0,0,0,0,0,0,0,0,0,0,0,0,0,0,0,0,0,0,0,0,0,0,0,0,0,0,0,~
0,0,0,0,0,0,0,0,0,0,0)';$S;BIDI;
    'MAA_DATA0':'(E74,0,0,0,0,0,0,0,0,0,0,0,0,0,0,0,0,0,0,0,0,0,0,0,0,0,0,0,0,0,~
0,0,0,0,0,0,0,0,0,0)';$S;BIDI;
    'MAA_CA4':'(BA74,0,0,0,0,0,0,0,0,0,0,0,0,0,0,0,0,0,0,0,0,0,0,0,0,0,0,0,0,0,0~
,0,0,0,0,0,0,0,0,0)';$S;OUT;
    'MAB_DQS_L2':'(CU74,0,0,0,0,0,0,0,0,0,0,0,0,0,0,0,0,0,0,0,0,0,0,0,0,0,0,0,0,~
0,0,0,0,0,0,0,0,0,0,0)';$S;BIDI;
    'MAB_DATA26':'(DA74,0,0,0,0,0,0,0,0,0,0,0,0,0,0,0,0,0,0,0,0,0,0,0,0,0,0,0,0,~
0,0,0,0,0,0,0,0,0,0,0)';$S;BIDI;
    'MAB_DATA15':'(CP72,0,0,0,0,0,0,0,0,0,0,0,0,0,0,0,0,0,0,0,0,0,0,0,0,0,0,0,0,~
0,0,0,0,0,0,0,0,0,0,0)';$S;BIDI;
    'MAB_DATA0':'(CB74,0,0,0,0,0,0,0,0,0,0,0,0,0,0,0,0,0,0,0,0,0,0,0,0,0,0,0,0,0~
,0,0,0,0,0,0,0,0,0,0)';$S;BIDI;
    'MAB_CHECK6':'(BU74,0,0,0,0,0,0,0,0,0,0,0,0,0,0,0,0,0,0,0,0,0,0,0,0,0,0,0,0,~
0,0,0,0,0,0,0,0,0,0,0)';$S;BIDI;
    'MAB_CA4':'(BJ73,0,0,0,0,0,0,0,0,0,0,0,0,0,0,0,0,0,0,0,0,0,0,0,0,0,0,0,0,0,0~
,0,0,0,0,0,0,0,0,0)';$S;OUT;
    'MAB0_RSP_L':'(BP74,0,0,0,0,0,0,0,0,0,0,0,0,0,0,0,0,0,0,0,0,0,0,0,0,0,0,0,0,~
0,0,0,0,0,0,0,0,0,0,0)';$S;IN;
    'MAA_DQS_L8':'(AF72,0,0,0,0,0,0,0,0,0,0,0,0,0,0,0,0,0,0,0,0,0,0,0,0,0,0,0,0,~
0,0,0,0,0,0,0,0,0,0,0)';$S;BIDI;
    'MAA_DQS_H4':'(AL74,0,0,0,0,0,0,0,0,0,0,0,0,0,0,0,0,0,0,0,0,0,0,0,0,0,0,0,0,~
0,0,0,0,0,0,0,0,0,0,0)';$S;BIDI;
    'MAA_DATA1':'(F72,0,0,0,0,0,0,0,0,0,0,0,0,0,0,0,0,0,0,0,0,0,0,0,0,0,0,0,0,0,~
0,0,0,0,0,0,0,0,0,0)';$S;BIDI;
    'MAA_CA5':'(BB74,0,0,0,0,0,0,0,0,0,0,0,0,0,0,0,0,0,0,0,0,0,0,0,0,0,0,0,0,0,0~
,0,0,0,0,0,0,0,0,0)';$S;OUT;
    'MAB_DQS_L3':'(DC74,0,0,0,0,0,0,0,0,0,0,0,0,0,0,0,0,0,0,0,0,0,0,0,0,0,0,0,0,~
0,0,0,0,0,0,0,0,0,0,0)';$S;BIDI;
    'MAB_DATA27':'(DB72,0,0,0,0,0,0,0,0,0,0,0,0,0,0,0,0,0,0,0,0,0,0,0,0,0,0,0,0,~
0,0,0,0,0,0,0,0,0,0,0)';$S;BIDI;
    'MAB_DATA16':'(CP74,0,0,0,0,0,0,0,0,0,0,0,0,0,0,0,0,0,0,0,0,0,0,0,0,0,0,0,0,~
0,0,0,0,0,0,0,0,0,0,0)';$S;BIDI;
    'MAB_DATA1':'(CC73,0,0,0,0,0,0,0,0,0,0,0,0,0,0,0,0,0,0,0,0,0,0,0,0,0,0,0,0,0~
,0,0,0,0,0,0,0,0,0,0)';$S;BIDI;
    'MAB_CHECK7':'(BV72,0,0,0,0,0,0,0,0,0,0,0,0,0,0,0,0,0,0,0,0,0,0,0,0,0,0,0,0,~
0,0,0,0,0,0,0,0,0,0,0)';$S;BIDI;
    'MAB_CA5':'(BK72,0,0,0,0,0,0,0,0,0,0,0,0,0,0,0,0,0,0,0,0,0,0,0,0,0,0,0,0,0,0~
,0,0,0,0,0,0,0,0,0)';$S;OUT;
    'MAB1_RSP_L':'(BR74,0,0,0,0,0,0,0,0,0,0,0,0,0,0,0,0,0,0,0,0,0,0,0,0,0,0,0,0,~
0,0,0,0,0,0,0,0,0,0,0)';$S;IN;
    'MAA_DQS_L9':'(AM72,0,0,0,0,0,0,0,0,0,0,0,0,0,0,0,0,0,0,0,0,0,0,0,0,0,0,0,0,~
0,0,0,0,0,0,0,0,0,0,0)';$S;BIDI;
    'MAA_DQS_H5':'(J73,0,0,0,0,0,0,0,0,0,0,0,0,0,0,0,0,0,0,0,0,0,0,0,0,0,0,0,0,0~
,0,0,0,0,0,0,0,0,0,0)';$S;BIDI;
    'MAA_DATA2':'(F74,0,0,0,0,0,0,0,0,0,0,0,0,0,0,0,0,0,0,0,0,0,0,0,0,0,0,0,0,0,~
0,0,0,0,0,0,0,0,0,0)';$S;BIDI;
    'MAA_CA6':'(BB72,0,0,0,0,0,0,0,0,0,0,0,0,0,0,0,0,0,0,0,0,0,0,0,0,0,0,0,0,0,0~
,0,0,0,0,0,0,0,0,0)';$S;OUT;
    'MAB_DQS_L4':'(BW73,0,0,0,0,0,0,0,0,0,0,0,0,0,0,0,0,0,0,0,0,0,0,0,0,0,0,0,0,~
0,0,0,0,0,0,0,0,0,0,0)';$S;BIDI;
    'MAB_DQS_H0':'(CD74,0,0,0,0,0,0,0,0,0,0,0,0,0,0,0,0,0,0,0,0,0,0,0,0,0,0,0,0,~
0,0,0,0,0,0,0,0,0,0,0)';$S;BIDI;
    'MAB_DATA28':'(DD74,0,0,0,0,0,0,0,0,0,0,0,0,0,0,0,0,0,0,0,0,0,0,0,0,0,0,0,0,~
0,0,0,0,0,0,0,0,0,0,0)';$S;BIDI;
    'MAB_DATA17':'(CR73,0,0,0,0,0,0,0,0,0,0,0,0,0,0,0,0,0,0,0,0,0,0,0,0,0,0,0,0,~
0,0,0,0,0,0,0,0,0,0,0)';$S;BIDI;
    'MAB_DATA2':'(CC74,0,0,0,0,0,0,0,0,0,0,0,0,0,0,0,0,0,0,0,0,0,0,0,0,0,0,0,0,0~
,0,0,0,0,0,0,0,0,0,0)';$S;BIDI;
    'MAB_CA6':'(BK74,0,0,0,0,0,0,0,0,0,0,0,0,0,0,0,0,0,0,0,0,0,0,0,0,0,0,0,0,0,0~
,0,0,0,0,0,0,0,0,0)';$S;OUT;
    'MAA_DQS_H6':'(R73,0,0,0,0,0,0,0,0,0,0,0,0,0,0,0,0,0,0,0,0,0,0,0,0,0,0,0,0,0~
,0,0,0,0,0,0,0,0,0,0)';$S;BIDI;
    'MAA_DATA3':'(G73,0,0,0,0,0,0,0,0,0,0,0,0,0,0,0,0,0,0,0,0,0,0,0,0,0,0,0,0,0,~
0,0,0,0,0,0,0,0,0,0)';$S;BIDI;
    'MAA0_CS_L0':'(AV74,0,0,0,0,0,0,0,0,0,0,0,0,0,0,0,0,0,0,0,0,0,0,0,0,0,0,0,0,~
0,0,0,0,0,0,0,0,0,0,0)';$S;OUT;
    'MAA_PAR':'(BC73,0,0,0,0,0,0,0,0,0,0,0,0,0,0,0,0,0,0,0,0,0,0,0,0,0,0,0,0,0,0~
,0,0,0,0,0,0,0,0,0)';$S;OUT;
    'MAB_PAR':'(BL74,0,0,0,0,0,0,0,0,0,0,0,0,0,0,0,0,0,0,0,0,0,0,0,0,0,0,0,0,0,0~
,0,0,0,0,0,0,0,0,0)';$S;OUT;
    'MA0_CLK_H':'(BC74,0,0,0,0,0,0,0,0,0,0,0,0,0,0,0,0,0,0,0,0,0,0,0,0,0,0,0,0,0~
,0,0,0,0,0,0,0,0,0,0)';$S;OUT;
    'MAB_DQS_H9':'(BV74,0,0,0,0,0,0,0,0,0,0,0,0,0,0,0,0,0,0,0,0,0,0,0,0,0,0,0,0,~
0,0,0,0,0,0,0,0,0,0,0)';$S;BIDI;
    'MA1_CLK_H':'(BF74,0,0,0,0,0,0,0,0,0,0,0,0,0,0,0,0,0,0,0,0,0,0,0,0,0,0,0,0,0~
,0,0,0,0,0,0,0,0,0,0)';$S;OUT;
    'MA0_CLK_L':'(BD74,0,0,0,0,0,0,0,0,0,0,0,0,0,0,0,0,0,0,0,0,0,0,0,0,0,0,0,0,0~
,0,0,0,0,0,0,0,0,0,0)';$S;OUT;
    'MA1_CLK_L':'(BG74,0,0,0,0,0,0,0,0,0,0,0,0,0,0,0,0,0,0,0,0,0,0,0,0,0,0,0,0,0~
,0,0,0,0,0,0,0,0,0,0)';$S;OUT;
    'TEST39A':'(BF72,0,0,0,0,0,0,0,0,0,0,0,0,0,0,0,0,0,0,0,0,0,0,0,0,0,0,0,0,0,0~
,0,0,0,0,0,0,0,0,0)';$S;OUT;
    'TEST40':'(C60,0,0,0,0,0,0,0,0,0,0,0,0,0,0,0,0,0,0,0,0,0,0,0,0,0,0,0,0,0,0,0~
,0,0,0,0,0,0,0,0)';$S;OUT;
    'MB_ALERT_L':'(0,AT62,0,0,0,0,0,0,0,0,0,0,0,0,0,0,0,0,0,0,0,0,0,0,0,0,0,0,0,~
0,0,0,0,0,0,0,0,0,0,0)';$S;IN;
    'MB_RESET_L':'(0,AU62,0,0,0,0,0,0,0,0,0,0,0,0,0,0,0,0,0,0,0,0,0,0,0,0,0,0,0,~
0,0,0,0,0,0,0,0,0,0,0)';$S;OUT;
    'MBB_DQS_L9':'(0,BW64,0,0,0,0,0,0,0,0,0,0,0,0,0,0,0,0,0,0,0,0,0,0,0,0,0,0,0,~
0,0,0,0,0,0,0,0,0,0,0)';$S;BIDI;
    'MBB_DQS_H5':'(0,CF62,0,0,0,0,0,0,0,0,0,0,0,0,0,0,0,0,0,0,0,0,0,0,0,0,0,0,0,~
0,0,0,0,0,0,0,0,0,0,0)';$S;BIDI;
    'MBA_DATA22':'(0,AB63,0,0,0,0,0,0,0,0,0,0,0,0,0,0,0,0,0,0,0,0,0,0,0,0,0,0,0,~
0,0,0,0,0,0,0,0,0,0,0)';$S;BIDI;
    'MBA_DATA11':'(0,N62,0,0,0,0,0,0,0,0,0,0,0,0,0,0,0,0,0,0,0,0,0,0,0,0,0,0,0,0~
,0,0,0,0,0,0,0,0,0,0)';$S;BIDI;
    'MBA_CHECK2':'(0,AK63,0,0,0,0,0,0,0,0,0,0,0,0,0,0,0,0,0,0,0,0,0,0,0,0,0,0,0,~
0,0,0,0,0,0,0,0,0,0,0)';$S;BIDI;
    'MBB_DQS_H6':'(0,CM62,0,0,0,0,0,0,0,0,0,0,0,0,0,0,0,0,0,0,0,0,0,0,0,0,0,0,0,~
0,0,0,0,0,0,0,0,0,0,0)';$S;BIDI;
    'MBA_DATA23':'(0,AC62,0,0,0,0,0,0,0,0,0,0,0,0,0,0,0,0,0,0,0,0,0,0,0,0,0,0,0,~
0,0,0,0,0,0,0,0,0,0,0)';$S;BIDI;
    'MBA_DATA12':'(0,R64,0,0,0,0,0,0,0,0,0,0,0,0,0,0,0,0,0,0,0,0,0,0,0,0,0,0,0,0~
,0,0,0,0,0,0,0,0,0,0)';$S;BIDI;
    'MBA_CHECK3':'(0,AL62,0,0,0,0,0,0,0,0,0,0,0,0,0,0,0,0,0,0,0,0,0,0,0,0,0,0,0,~
0,0,0,0,0,0,0,0,0,0,0)';$S;BIDI;
    'MBB_DQS_H7':'(0,CV62,0,0,0,0,0,0,0,0,0,0,0,0,0,0,0,0,0,0,0,0,0,0,0,0,0,0,0,~
0,0,0,0,0,0,0,0,0,0,0)';$S;BIDI;
    'MBB0_CS_L0':'(0,BM62,0,0,0,0,0,0,0,0,0,0,0,0,0,0,0,0,0,0,0,0,0,0,0,0,0,0,0,~
0,0,0,0,0,0,0,0,0,0,0)';$S;OUT;
    'MBA_DQS_L0':'(0,H63,0,0,0,0,0,0,0,0,0,0,0,0,0,0,0,0,0,0,0,0,0,0,0,0,0,0,0,0~
,0,0,0,0,0,0,0,0,0,0)';$S;BIDI;
    'MBA_DATA13':'(0,T62,0,0,0,0,0,0,0,0,0,0,0,0,0,0,0,0,0,0,0,0,0,0,0,0,0,0,0,0~
,0,0,0,0,0,0,0,0,0,0)';$S;BIDI;
    'MBA_DATA0':'(0,E64,0,0,0,0,0,0,0,0,0,0,0,0,0,0,0,0,0,0,0,0,0,0,0,0,0,0,0,0,~
0,0,0,0,0,0,0,0,0,0)';$S;BIDI;
    'MBA_CHECK4':'(0,AN64,0,0,0,0,0,0,0,0,0,0,0,0,0,0,0,0,0,0,0,0,0,0,0,0,0,0,0,~
0,0,0,0,0,0,0,0,0,0,0)';$S;BIDI;
    'MBB_DQS_H8':'(0,DD62,0,0,0,0,0,0,0,0,0,0,0,0,0,0,0,0,0,0,0,0,0,0,0,0,0,0,0,~
0,0,0,0,0,0,0,0,0,0,0)';$S;BIDI;
    'MBB_DATA30':'(0,DE64,0,0,0,0,0,0,0,0,0,0,0,0,0,0,0,0,0,0,0,0,0,0,0,0,0,0,0,~
0,0,0,0,0,0,0,0,0,0,0)';$S;BIDI;
    'MBB_DATA0':'(0,CB63,0,0,0,0,0,0,0,0,0,0,0,0,0,0,0,0,0,0,0,0,0,0,0,0,0,0,0,0~
,0,0,0,0,0,0,0,0,0,0)';$S;BIDI;
    'MBB1_CS_L0':'(0,BL62,0,0,0,0,0,0,0,0,0,0,0,0,0,0,0,0,0,0,0,0,0,0,0,0,0,0,0,~
0,0,0,0,0,0,0,0,0,0,0)';$S;OUT;
    'MBB0_CS_L1':'(0,BN64,0,0,0,0,0,0,0,0,0,0,0,0,0,0,0,0,0,0,0,0,0,0,0,0,0,0,0,~
0,0,0,0,0,0,0,0,0,0,0)';$S;OUT;
    'MBA_DQS_L1':'(0,P63,0,0,0,0,0,0,0,0,0,0,0,0,0,0,0,0,0,0,0,0,0,0,0,0,0,0,0,0~
,0,0,0,0,0,0,0,0,0,0)';$S;BIDI;
    'MBA_DATA25':'(0,AD62,0,0,0,0,0,0,0,0,0,0,0,0,0,0,0,0,0,0,0,0,0,0,0,0,0,0,0,~
0,0,0,0,0,0,0,0,0,0,0)';$S;BIDI;
    'MBA_DATA14':'(0,T63,0,0,0,0,0,0,0,0,0,0,0,0,0,0,0,0,0,0,0,0,0,0,0,0,0,0,0,0~
,0,0,0,0,0,0,0,0,0,0)';$S;BIDI;
    'MBA_DATA1':'(0,F62,0,0,0,0,0,0,0,0,0,0,0,0,0,0,0,0,0,0,0,0,0,0,0,0,0,0,0,0,~
0,0,0,0,0,0,0,0,0,0)';$S;BIDI;
    'MBA_CHECK5':'(0,AP62,0,0,0,0,0,0,0,0,0,0,0,0,0,0,0,0,0,0,0,0,0,0,0,0,0,0,0,~
0,0,0,0,0,0,0,0,0,0,0)';$S;BIDI;
    'MBB_DATA31':'(0,DF62,0,0,0,0,0,0,0,0,0,0,0,0,0,0,0,0,0,0,0,0,0,0,0,0,0,0,0,~
0,0,0,0,0,0,0,0,0,0,0)';$S;BIDI;
    'MBB_DATA1':'(0,CC62,0,0,0,0,0,0,0,0,0,0,0,0,0,0,0,0,0,0,0,0,0,0,0,0,0,0,0,0~
,0,0,0,0,0,0,0,0,0,0)';$S;BIDI;
    'MBB_CHECK0':'(0,BY63,0,0,0,0,0,0,0,0,0,0,0,0,0,0,0,0,0,0,0,0,0,0,0,0,0,0,0,~
0,0,0,0,0,0,0,0,0,0,0)';$S;BIDI;
    'MBB1_CS_L1':'(0,BM63,0,0,0,0,0,0,0,0,0,0,0,0,0,0,0,0,0,0,0,0,0,0,0,0,0,0,0,~
0,0,0,0,0,0,0,0,0,0,0)';$S;OUT;
    'MBA_DQS_L2':'(0,Y63,0,0,0,0,0,0,0,0,0,0,0,0,0,0,0,0,0,0,0,0,0,0,0,0,0,0,0,0~
,0,0,0,0,0,0,0,0,0,0)';$S;BIDI;
    'MBA_DATA26':'(0,AD63,0,0,0,0,0,0,0,0,0,0,0,0,0,0,0,0,0,0,0,0,0,0,0,0,0,0,0,~
0,0,0,0,0,0,0,0,0,0,0)';$S;BIDI;
    'MBA_DATA15':'(0,U62,0,0,0,0,0,0,0,0,0,0,0,0,0,0,0,0,0,0,0,0,0,0,0,0,0,0,0,0~
,0,0,0,0,0,0,0,0,0,0)';$S;BIDI;
    'MBA_DATA2':'(0,F63,0,0,0,0,0,0,0,0,0,0,0,0,0,0,0,0,0,0,0,0,0,0,0,0,0,0,0,0,~
0,0,0,0,0,0,0,0,0,0)';$S;BIDI;
    'MBA_CHECK6':'(0,AP63,0,0,0,0,0,0,0,0,0,0,0,0,0,0,0,0,0,0,0,0,0,0,0,0,0,0,0,~
0,0,0,0,0,0,0,0,0,0,0)';$S;BIDI;
    'MBB_DATA21':'(0,CW62,0,0,0,0,0,0,0,0,0,0,0,0,0,0,0,0,0,0,0,0,0,0,0,0,0,0,0,~
0,0,0,0,0,0,0,0,0,0,0)';$S;BIDI;
    'MBB_DATA10':'(0,CJ64,0,0,0,0,0,0,0,0,0,0,0,0,0,0,0,0,0,0,0,0,0,0,0,0,0,0,0,~
0,0,0,0,0,0,0,0,0,0,0)';$S;BIDI;
    'MBB_DATA2':'(0,CC64,0,0,0,0,0,0,0,0,0,0,0,0,0,0,0,0,0,0,0,0,0,0,0,0,0,0,0,0~
,0,0,0,0,0,0,0,0,0,0)';$S;BIDI;
    'MBB_CHECK1':'(0,CA62,0,0,0,0,0,0,0,0,0,0,0,0,0,0,0,0,0,0,0,0,0,0,0,0,0,0,0,~
0,0,0,0,0,0,0,0,0,0,0)';$S;BIDI;
    'MBA_DQS_L3':'(0,AF63,0,0,0,0,0,0,0,0,0,0,0,0,0,0,0,0,0,0,0,0,0,0,0,0,0,0,0,~
0,0,0,0,0,0,0,0,0,0,0)';$S;BIDI;
    'MBA_DATA27':'(0,AE62,0,0,0,0,0,0,0,0,0,0,0,0,0,0,0,0,0,0,0,0,0,0,0,0,0,0,0,~
0,0,0,0,0,0,0,0,0,0,0)';$S;BIDI;
    'MBA_DATA16':'(0,U64,0,0,0,0,0,0,0,0,0,0,0,0,0,0,0,0,0,0,0,0,0,0,0,0,0,0,0,0~
,0,0,0,0,0,0,0,0,0,0)';$S;BIDI;
    'MBA_DATA3':'(0,G62,0,0,0,0,0,0,0,0,0,0,0,0,0,0,0,0,0,0,0,0,0,0,0,0,0,0,0,0,~
0,0,0,0,0,0,0,0,0,0)';$S;BIDI;
    'MBA_CHECK7':'(0,AR62,0,0,0,0,0,0,0,0,0,0,0,0,0,0,0,0,0,0,0,0,0,0,0,0,0,0,0,~
0,0,0,0,0,0,0,0,0,0,0)';$S;BIDI;
    'MBA0_RSP_L':'(0,BN62,0,0,0,0,0,0,0,0,0,0,0,0,0,0,0,0,0,0,0,0,0,0,0,0,0,0,0,~
0,0,0,0,0,0,0,0,0,0,0)';$S;IN;
    'MBB_DATA22':'(0,CW64,0,0,0,0,0,0,0,0,0,0,0,0,0,0,0,0,0,0,0,0,0,0,0,0,0,0,0,~
0,0,0,0,0,0,0,0,0,0,0)';$S;BIDI;
    'MBB_DATA11':'(0,CK62,0,0,0,0,0,0,0,0,0,0,0,0,0,0,0,0,0,0,0,0,0,0,0,0,0,0,0,~
0,0,0,0,0,0,0,0,0,0,0)';$S;BIDI;
    'MBB_DATA3':'(0,CD62,0,0,0,0,0,0,0,0,0,0,0,0,0,0,0,0,0,0,0,0,0,0,0,0,0,0,0,0~
,0,0,0,0,0,0,0,0,0,0)';$S;BIDI;
    'MBB_CHECK2':'(0,CA64,0,0,0,0,0,0,0,0,0,0,0,0,0,0,0,0,0,0,0,0,0,0,0,0,0,0,0,~
0,0,0,0,0,0,0,0,0,0,0)';$S;BIDI;
    'MBA_DQS_L4':'(0,AM63,0,0,0,0,0,0,0,0,0,0,0,0,0,0,0,0,0,0,0,0,0,0,0,0,0,0,0,~
0,0,0,0,0,0,0,0,0,0,0)';$S;BIDI;
    'MBA_DQS_H0':'(0,G64,0,0,0,0,0,0,0,0,0,0,0,0,0,0,0,0,0,0,0,0,0,0,0,0,0,0,0,0~
,0,0,0,0,0,0,0,0,0,0)';$S;BIDI;
    'MBA_DATA28':'(0,AG64,0,0,0,0,0,0,0,0,0,0,0,0,0,0,0,0,0,0,0,0,0,0,0,0,0,0,0,~
0,0,0,0,0,0,0,0,0,0,0)';$S;BIDI;
    'MBA_DATA17':'(0,V62,0,0,0,0,0,0,0,0,0,0,0,0,0,0,0,0,0,0,0,0,0,0,0,0,0,0,0,0~
,0,0,0,0,0,0,0,0,0,0)';$S;BIDI;
    'MBA_DATA4':'(0,J64,0,0,0,0,0,0,0,0,0,0,0,0,0,0,0,0,0,0,0,0,0,0,0,0,0,0,0,0,~
0,0,0,0,0,0,0,0,0,0)';$S;BIDI;
    'MBA1_RSP_L':'(0,BP62,0,0,0,0,0,0,0,0,0,0,0,0,0,0,0,0,0,0,0,0,0,0,0,0,0,0,0,~
0,0,0,0,0,0,0,0,0,0,0)';$S;IN;
    'MBB_DATA23':'(0,CY62,0,0,0,0,0,0,0,0,0,0,0,0,0,0,0,0,0,0,0,0,0,0,0,0,0,0,0,~
0,0,0,0,0,0,0,0,0,0,0)';$S;BIDI;
    'MBB_DATA12':'(0,CM63,0,0,0,0,0,0,0,0,0,0,0,0,0,0,0,0,0,0,0,0,0,0,0,0,0,0,0,~
0,0,0,0,0,0,0,0,0,0,0)';$S;BIDI;
    'MBB_DATA4':'(0,CF63,0,0,0,0,0,0,0,0,0,0,0,0,0,0,0,0,0,0,0,0,0,0,0,0,0,0,0,0~
,0,0,0,0,0,0,0,0,0,0)';$S;BIDI;
    'MBB_CHECK3':'(0,CB62,0,0,0,0,0,0,0,0,0,0,0,0,0,0,0,0,0,0,0,0,0,0,0,0,0,0,0,~
0,0,0,0,0,0,0,0,0,0,0)';$S;BIDI;
    'MBA_DQS_L5':'(0,H62,0,0,0,0,0,0,0,0,0,0,0,0,0,0,0,0,0,0,0,0,0,0,0,0,0,0,0,0~
,0,0,0,0,0,0,0,0,0,0)';$S;BIDI;
    'MBA_DQS_H1':'(0,N64,0,0,0,0,0,0,0,0,0,0,0,0,0,0,0,0,0,0,0,0,0,0,0,0,0,0,0,0~
,0,0,0,0,0,0,0,0,0,0)';$S;BIDI;
    'MBA_DATA29':'(0,AH62,0,0,0,0,0,0,0,0,0,0,0,0,0,0,0,0,0,0,0,0,0,0,0,0,0,0,0,~
0,0,0,0,0,0,0,0,0,0,0)';$S;BIDI;
    'MBA_DATA18':'(0,V63,0,0,0,0,0,0,0,0,0,0,0,0,0,0,0,0,0,0,0,0,0,0,0,0,0,0,0,0~
,0,0,0,0,0,0,0,0,0,0)';$S;BIDI;
    'MBA_DATA5':'(0,K62,0,0,0,0,0,0,0,0,0,0,0,0,0,0,0,0,0,0,0,0,0,0,0,0,0,0,0,0,~
0,0,0,0,0,0,0,0,0,0)';$S;BIDI;
    'MBB_DQS_L0':'(0,CE64,0,0,0,0,0,0,0,0,0,0,0,0,0,0,0,0,0,0,0,0,0,0,0,0,0,0,0,~
0,0,0,0,0,0,0,0,0,0,0)';$S;BIDI;
    'MBB_DATA24':'(0,CY63,0,0,0,0,0,0,0,0,0,0,0,0,0,0,0,0,0,0,0,0,0,0,0,0,0,0,0,~
0,0,0,0,0,0,0,0,0,0,0)';$S;BIDI;
    'MBB_DATA13':'(0,CN62,0,0,0,0,0,0,0,0,0,0,0,0,0,0,0,0,0,0,0,0,0,0,0,0,0,0,0,~
0,0,0,0,0,0,0,0,0,0,0)';$S;BIDI;
    'MBB_DATA5':'(0,CG62,0,0,0,0,0,0,0,0,0,0,0,0,0,0,0,0,0,0,0,0,0,0,0,0,0,0,0,0~
,0,0,0,0,0,0,0,0,0,0)';$S;BIDI;
    'MBB_CHECK4':'(0,BT63,0,0,0,0,0,0,0,0,0,0,0,0,0,0,0,0,0,0,0,0,0,0,0,0,0,0,0,~
0,0,0,0,0,0,0,0,0,0,0)';$S;BIDI;
    'MBA_DQS_L6':'(0,P62,0,0,0,0,0,0,0,0,0,0,0,0,0,0,0,0,0,0,0,0,0,0,0,0,0,0,0,0~
,0,0,0,0,0,0,0,0,0,0)';$S;BIDI;
    'MBA_DQS_H2':'(0,W64,0,0,0,0,0,0,0,0,0,0,0,0,0,0,0,0,0,0,0,0,0,0,0,0,0,0,0,0~
,0,0,0,0,0,0,0,0,0,0)';$S;BIDI;
    'MBA_DATA19':'(0,W62,0,0,0,0,0,0,0,0,0,0,0,0,0,0,0,0,0,0,0,0,0,0,0,0,0,0,0,0~
,0,0,0,0,0,0,0,0,0,0)';$S;BIDI;
    'MBA_DATA6':'(0,K63,0,0,0,0,0,0,0,0,0,0,0,0,0,0,0,0,0,0,0,0,0,0,0,0,0,0,0,0,~
0,0,0,0,0,0,0,0,0,0)';$S;BIDI;
    'MBA_CA0':'(0,AW64,0,0,0,0,0,0,0,0,0,0,0,0,0,0,0,0,0,0,0,0,0,0,0,0,0,0,0,0,0~
,0,0,0,0,0,0,0,0,0)';$S;OUT;
    'MBB_DQS_L1':'(0,CL64,0,0,0,0,0,0,0,0,0,0,0,0,0,0,0,0,0,0,0,0,0,0,0,0,0,0,0,~
0,0,0,0,0,0,0,0,0,0,0)';$S;BIDI;
    'MBB_DATA25':'(0,DA62,0,0,0,0,0,0,0,0,0,0,0,0,0,0,0,0,0,0,0,0,0,0,0,0,0,0,0,~
0,0,0,0,0,0,0,0,0,0,0)';$S;BIDI;
    'MBB_DATA14':'(0,CN64,0,0,0,0,0,0,0,0,0,0,0,0,0,0,0,0,0,0,0,0,0,0,0,0,0,0,0,~
0,0,0,0,0,0,0,0,0,0,0)';$S;BIDI;
    'MBB_DATA6':'(0,CG64,0,0,0,0,0,0,0,0,0,0,0,0,0,0,0,0,0,0,0,0,0,0,0,0,0,0,0,0~
,0,0,0,0,0,0,0,0,0,0)';$S;BIDI;
    'MBB_CHECK5':'(0,BU62,0,0,0,0,0,0,0,0,0,0,0,0,0,0,0,0,0,0,0,0,0,0,0,0,0,0,0,~
0,0,0,0,0,0,0,0,0,0,0)';$S;BIDI;
    'MBB_CA0':'(0,BG62,0,0,0,0,0,0,0,0,0,0,0,0,0,0,0,0,0,0,0,0,0,0,0,0,0,0,0,0,0~
,0,0,0,0,0,0,0,0,0)';$S;OUT;
    'MBA_DQS_L7':'(0,Y62,0,0,0,0,0,0,0,0,0,0,0,0,0,0,0,0,0,0,0,0,0,0,0,0,0,0,0,0~
,0,0,0,0,0,0,0,0,0,0)';$S;BIDI;
    'MBA_DQS_H3':'(0,AE64,0,0,0,0,0,0,0,0,0,0,0,0,0,0,0,0,0,0,0,0,0,0,0,0,0,0,0,~
0,0,0,0,0,0,0,0,0,0,0)';$S;BIDI;
    'MBA_DATA7':'(0,L62,0,0,0,0,0,0,0,0,0,0,0,0,0,0,0,0,0,0,0,0,0,0,0,0,0,0,0,0,~
0,0,0,0,0,0,0,0,0,0)';$S;BIDI;
    'MBA_CA1':'(0,AY63,0,0,0,0,0,0,0,0,0,0,0,0,0,0,0,0,0,0,0,0,0,0,0,0,0,0,0,0,0~
,0,0,0,0,0,0,0,0,0)';$S;OUT;
    'MBB_DQS_L2':'(0,CU64,0,0,0,0,0,0,0,0,0,0,0,0,0,0,0,0,0,0,0,0,0,0,0,0,0,0,0,~
0,0,0,0,0,0,0,0,0,0,0)';$S;BIDI;
    'MBB_DATA26':'(0,DA64,0,0,0,0,0,0,0,0,0,0,0,0,0,0,0,0,0,0,0,0,0,0,0,0,0,0,0,~
0,0,0,0,0,0,0,0,0,0,0)';$S;BIDI;
    'MBB_DATA15':'(0,CP62,0,0,0,0,0,0,0,0,0,0,0,0,0,0,0,0,0,0,0,0,0,0,0,0,0,0,0,~
0,0,0,0,0,0,0,0,0,0,0)';$S;BIDI;
    'MBB_DATA7':'(0,CH62,0,0,0,0,0,0,0,0,0,0,0,0,0,0,0,0,0,0,0,0,0,0,0,0,0,0,0,0~
,0,0,0,0,0,0,0,0,0,0)';$S;BIDI;
    'MBB_CHECK6':'(0,BU64,0,0,0,0,0,0,0,0,0,0,0,0,0,0,0,0,0,0,0,0,0,0,0,0,0,0,0,~
0,0,0,0,0,0,0,0,0,0,0)';$S;BIDI;
    'MBB_CA1':'(0,BH62,0,0,0,0,0,0,0,0,0,0,0,0,0,0,0,0,0,0,0,0,0,0,0,0,0,0,0,0,0~
,0,0,0,0,0,0,0,0,0)';$S;OUT;
    'MBA_DQS_L8':'(0,AF62,0,0,0,0,0,0,0,0,0,0,0,0,0,0,0,0,0,0,0,0,0,0,0,0,0,0,0,~
0,0,0,0,0,0,0,0,0,0,0)';$S;BIDI;
    'MBA_DQS_H4':'(0,AL64,0,0,0,0,0,0,0,0,0,0,0,0,0,0,0,0,0,0,0,0,0,0,0,0,0,0,0,~
0,0,0,0,0,0,0,0,0,0,0)';$S;BIDI;
    'MBA_DATA8':'(0,L64,0,0,0,0,0,0,0,0,0,0,0,0,0,0,0,0,0,0,0,0,0,0,0,0,0,0,0,0,~
0,0,0,0,0,0,0,0,0,0)';$S;BIDI;
    'MBA_CA2':'(0,AY62,0,0,0,0,0,0,0,0,0,0,0,0,0,0,0,0,0,0,0,0,0,0,0,0,0,0,0,0,0~
,0,0,0,0,0,0,0,0,0)';$S;OUT;
    'MBB_DQS_L3':'(0,DC64,0,0,0,0,0,0,0,0,0,0,0,0,0,0,0,0,0,0,0,0,0,0,0,0,0,0,0,~
0,0,0,0,0,0,0,0,0,0,0)';$S;BIDI;
    'MBB_DATA27':'(0,DB62,0,0,0,0,0,0,0,0,0,0,0,0,0,0,0,0,0,0,0,0,0,0,0,0,0,0,0,~
0,0,0,0,0,0,0,0,0,0,0)';$S;BIDI;
    'MBB_DATA16':'(0,CP63,0,0,0,0,0,0,0,0,0,0,0,0,0,0,0,0,0,0,0,0,0,0,0,0,0,0,0,~
0,0,0,0,0,0,0,0,0,0,0)';$S;BIDI;
    'MBB_DATA8':'(0,CH63,0,0,0,0,0,0,0,0,0,0,0,0,0,0,0,0,0,0,0,0,0,0,0,0,0,0,0,0~
,0,0,0,0,0,0,0,0,0,0)';$S;BIDI;
    'MBB_CHECK7':'(0,BV62,0,0,0,0,0,0,0,0,0,0,0,0,0,0,0,0,0,0,0,0,0,0,0,0,0,0,0,~
0,0,0,0,0,0,0,0,0,0,0)';$S;BIDI;
    'MBB_CA2':'(0,BH63,0,0,0,0,0,0,0,0,0,0,0,0,0,0,0,0,0,0,0,0,0,0,0,0,0,0,0,0,0~
,0,0,0,0,0,0,0,0,0)';$S;OUT;
    'MBB0_RSP_L':'(0,BP63,0,0,0,0,0,0,0,0,0,0,0,0,0,0,0,0,0,0,0,0,0,0,0,0,0,0,0,~
0,0,0,0,0,0,0,0,0,0,0)';$S;IN;
    'MBA_DQS_L9':'(0,AM62,0,0,0,0,0,0,0,0,0,0,0,0,0,0,0,0,0,0,0,0,0,0,0,0,0,0,0,~
0,0,0,0,0,0,0,0,0,0,0)';$S;BIDI;
    'MBA_DQS_H5':'(0,J62,0,0,0,0,0,0,0,0,0,0,0,0,0,0,0,0,0,0,0,0,0,0,0,0,0,0,0,0~
,0,0,0,0,0,0,0,0,0,0)';$S;BIDI;
    'MBA_DATA9':'(0,M62,0,0,0,0,0,0,0,0,0,0,0,0,0,0,0,0,0,0,0,0,0,0,0,0,0,0,0,0,~
0,0,0,0,0,0,0,0,0,0)';$S;BIDI;
    'MBA_CA3':'(0,BA62,0,0,0,0,0,0,0,0,0,0,0,0,0,0,0,0,0,0,0,0,0,0,0,0,0,0,0,0,0~
,0,0,0,0,0,0,0,0,0)';$S;OUT;
    'MBB_DQS_L4':'(0,BW62,0,0,0,0,0,0,0,0,0,0,0,0,0,0,0,0,0,0,0,0,0,0,0,0,0,0,0,~
0,0,0,0,0,0,0,0,0,0,0)';$S;BIDI;
    'MBB_DQS_H0':'(0,CD63,0,0,0,0,0,0,0,0,0,0,0,0,0,0,0,0,0,0,0,0,0,0,0,0,0,0,0,~
0,0,0,0,0,0,0,0,0,0,0)';$S;BIDI;
    'MBB_DATA28':'(0,DD63,0,0,0,0,0,0,0,0,0,0,0,0,0,0,0,0,0,0,0,0,0,0,0,0,0,0,0,~
0,0,0,0,0,0,0,0,0,0,0)';$S;BIDI;
    'MBB_DATA17':'(0,CR62,0,0,0,0,0,0,0,0,0,0,0,0,0,0,0,0,0,0,0,0,0,0,0,0,0,0,0,~
0,0,0,0,0,0,0,0,0,0,0)';$S;BIDI;
    'MBB_DATA9':'(0,CJ62,0,0,0,0,0,0,0,0,0,0,0,0,0,0,0,0,0,0,0,0,0,0,0,0,0,0,0,0~
,0,0,0,0,0,0,0,0,0,0)';$S;BIDI;
    'MBB_CA3':'(0,BJ64,0,0,0,0,0,0,0,0,0,0,0,0,0,0,0,0,0,0,0,0,0,0,0,0,0,0,0,0,0~
,0,0,0,0,0,0,0,0,0)';$S;OUT;
    'MBB1_RSP_L':'(0,BR64,0,0,0,0,0,0,0,0,0,0,0,0,0,0,0,0,0,0,0,0,0,0,0,0,0,0,0,~
0,0,0,0,0,0,0,0,0,0,0)';$S;IN;
    'MBA_DQS_H6':'(0,R62,0,0,0,0,0,0,0,0,0,0,0,0,0,0,0,0,0,0,0,0,0,0,0,0,0,0,0,0~
,0,0,0,0,0,0,0,0,0,0)';$S;BIDI;
    'MBA_CA4':'(0,BA64,0,0,0,0,0,0,0,0,0,0,0,0,0,0,0,0,0,0,0,0,0,0,0,0,0,0,0,0,0~
,0,0,0,0,0,0,0,0,0)';$S;OUT;
    'MBB_DQS_L5':'(0,CE62,0,0,0,0,0,0,0,0,0,0,0,0,0,0,0,0,0,0,0,0,0,0,0,0,0,0,0,~
0,0,0,0,0,0,0,0,0,0,0)';$S;BIDI;
    'MBB_DQS_H1':'(0,CK63,0,0,0,0,0,0,0,0,0,0,0,0,0,0,0,0,0,0,0,0,0,0,0,0,0,0,0,~
0,0,0,0,0,0,0,0,0,0,0)';$S;BIDI;
    'MBB_DATA29':'(0,DE62,0,0,0,0,0,0,0,0,0,0,0,0,0,0,0,0,0,0,0,0,0,0,0,0,0,0,0,~
0,0,0,0,0,0,0,0,0,0,0)';$S;BIDI;
    'MBB_DATA18':'(0,CR64,0,0,0,0,0,0,0,0,0,0,0,0,0,0,0,0,0,0,0,0,0,0,0,0,0,0,0,~
0,0,0,0,0,0,0,0,0,0,0)';$S;BIDI;
    'MBB_CA4':'(0,BJ62,0,0,0,0,0,0,0,0,0,0,0,0,0,0,0,0,0,0,0,0,0,0,0,0,0,0,0,0,0~
,0,0,0,0,0,0,0,0,0)';$S;OUT;
    'MBA_DQS_H7':'(0,AA62,0,0,0,0,0,0,0,0,0,0,0,0,0,0,0,0,0,0,0,0,0,0,0,0,0,0,0,~
0,0,0,0,0,0,0,0,0,0,0)';$S;BIDI;
    'MBA_CA5':'(0,BB63,0,0,0,0,0,0,0,0,0,0,0,0,0,0,0,0,0,0,0,0,0,0,0,0,0,0,0,0,0~
,0,0,0,0,0,0,0,0,0)';$S;OUT;
    'MBA0_CS_L0':'(0,AV63,0,0,0,0,0,0,0,0,0,0,0,0,0,0,0,0,0,0,0,0,0,0,0,0,0,0,0,~
0,0,0,0,0,0,0,0,0,0,0)';$S;OUT;
    'MBB_DQS_L6':'(0,CL62,0,0,0,0,0,0,0,0,0,0,0,0,0,0,0,0,0,0,0,0,0,0,0,0,0,0,0,~
0,0,0,0,0,0,0,0,0,0,0)';$S;BIDI;
    'MBB_DQS_H2':'(0,CT63,0,0,0,0,0,0,0,0,0,0,0,0,0,0,0,0,0,0,0,0,0,0,0,0,0,0,0,~
0,0,0,0,0,0,0,0,0,0,0)';$S;BIDI;
    'MBB_CA5':'(0,BK62,0,0,0,0,0,0,0,0,0,0,0,0,0,0,0,0,0,0,0,0,0,0,0,0,0,0,0,0,0~
,0,0,0,0,0,0,0,0,0)';$S;OUT;
    'MBA_DQS_H8':'(0,AG62,0,0,0,0,0,0,0,0,0,0,0,0,0,0,0,0,0,0,0,0,0,0,0,0,0,0,0,~
0,0,0,0,0,0,0,0,0,0,0)';$S;BIDI;
    'MBA_DATA30':'(0,AH63,0,0,0,0,0,0,0,0,0,0,0,0,0,0,0,0,0,0,0,0,0,0,0,0,0,0,0,~
0,0,0,0,0,0,0,0,0,0,0)';$S;BIDI;
    'MBA_CA6':'(0,BB62,0,0,0,0,0,0,0,0,0,0,0,0,0,0,0,0,0,0,0,0,0,0,0,0,0,0,0,0,0~
,0,0,0,0,0,0,0,0,0)';$S;OUT;
    'MBA1_CS_L0':'(0,AU64,0,0,0,0,0,0,0,0,0,0,0,0,0,0,0,0,0,0,0,0,0,0,0,0,0,0,0,~
0,0,0,0,0,0,0,0,0,0,0)';$S;OUT;
    'MBA0_CS_L1':'(0,AW62,0,0,0,0,0,0,0,0,0,0,0,0,0,0,0,0,0,0,0,0,0,0,0,0,0,0,0,~
0,0,0,0,0,0,0,0,0,0,0)';$S;OUT;
    'MBB_DQS_L7':'(0,CU62,0,0,0,0,0,0,0,0,0,0,0,0,0,0,0,0,0,0,0,0,0,0,0,0,0,0,0,~
0,0,0,0,0,0,0,0,0,0,0)';$S;BIDI;
    'MBB_DQS_H3':'(0,DB63,0,0,0,0,0,0,0,0,0,0,0,0,0,0,0,0,0,0,0,0,0,0,0,0,0,0,0,~
0,0,0,0,0,0,0,0,0,0,0)';$S;BIDI;
    'MBB_CA6':'(0,BK63,0,0,0,0,0,0,0,0,0,0,0,0,0,0,0,0,0,0,0,0,0,0,0,0,0,0,0,0,0~
,0,0,0,0,0,0,0,0,0)';$S;OUT;
    'MBA_DQS_H9':'(0,AN62,0,0,0,0,0,0,0,0,0,0,0,0,0,0,0,0,0,0,0,0,0,0,0,0,0,0,0,~
0,0,0,0,0,0,0,0,0,0,0)';$S;BIDI;
    'MBA_DATA31':'(0,AJ62,0,0,0,0,0,0,0,0,0,0,0,0,0,0,0,0,0,0,0,0,0,0,0,0,0,0,0,~
0,0,0,0,0,0,0,0,0,0,0)';$S;BIDI;
    'MBA_DATA20':'(0,AA64,0,0,0,0,0,0,0,0,0,0,0,0,0,0,0,0,0,0,0,0,0,0,0,0,0,0,0,~
0,0,0,0,0,0,0,0,0,0,0)';$S;BIDI;
    'MBA_CHECK0':'(0,AJ64,0,0,0,0,0,0,0,0,0,0,0,0,0,0,0,0,0,0,0,0,0,0,0,0,0,0,0,~
0,0,0,0,0,0,0,0,0,0,0)';$S;BIDI;
    'MBA1_CS_L1':'(0,AV62,0,0,0,0,0,0,0,0,0,0,0,0,0,0,0,0,0,0,0,0,0,0,0,0,0,0,0,~
0,0,0,0,0,0,0,0,0,0,0)';$S;OUT;
    'MBB_DQS_L8':'(0,DC62,0,0,0,0,0,0,0,0,0,0,0,0,0,0,0,0,0,0,0,0,0,0,0,0,0,0,0,~
0,0,0,0,0,0,0,0,0,0,0)';$S;BIDI;
    'MBB_DQS_H4':'(0,BY62,0,0,0,0,0,0,0,0,0,0,0,0,0,0,0,0,0,0,0,0,0,0,0,0,0,0,0,~
0,0,0,0,0,0,0,0,0,0,0)';$S;BIDI;
    'MBA_DATA21':'(0,AB62,0,0,0,0,0,0,0,0,0,0,0,0,0,0,0,0,0,0,0,0,0,0,0,0,0,0,0,~
0,0,0,0,0,0,0,0,0,0,0)';$S;BIDI;
    'MBA_DATA10':'(0,M63,0,0,0,0,0,0,0,0,0,0,0,0,0,0,0,0,0,0,0,0,0,0,0,0,0,0,0,0~
,0,0,0,0,0,0,0,0,0,0)';$S;BIDI;
    'MBA_CHECK1':'(0,AK62,0,0,0,0,0,0,0,0,0,0,0,0,0,0,0,0,0,0,0,0,0,0,0,0,0,0,0,~
0,0,0,0,0,0,0,0,0,0,0)';$S;BIDI;
    'MBB_DQS_H9':'(0,BV63,0,0,0,0,0,0,0,0,0,0,0,0,0,0,0,0,0,0,0,0,0,0,0,0,0,0,0,~
0,0,0,0,0,0,0,0,0,0,0)';$S;BIDI;
    'MBA_PAR':'(0,BC62,0,0,0,0,0,0,0,0,0,0,0,0,0,0,0,0,0,0,0,0,0,0,0,0,0,0,0,0,0~
,0,0,0,0,0,0,0,0,0)';$S;OUT;
    'MBB_PAR':'(0,BL64,0,0,0,0,0,0,0,0,0,0,0,0,0,0,0,0,0,0,0,0,0,0,0,0,0,0,0,0,0~
,0,0,0,0,0,0,0,0,0)';$S;OUT;
    'MB0_CLK_H':'(0,BC64,0,0,0,0,0,0,0,0,0,0,0,0,0,0,0,0,0,0,0,0,0,0,0,0,0,0,0,0~
,0,0,0,0,0,0,0,0,0,0)';$S;OUT;
    'MB0_CLK_L':'(0,BD63,0,0,0,0,0,0,0,0,0,0,0,0,0,0,0,0,0,0,0,0,0,0,0,0,0,0,0,0~
,0,0,0,0,0,0,0,0,0,0)';$S;OUT;
    'MB1_CLK_H':'(0,BF63,0,0,0,0,0,0,0,0,0,0,0,0,0,0,0,0,0,0,0,0,0,0,0,0,0,0,0,0~
,0,0,0,0,0,0,0,0,0,0)';$S;OUT;
    'MB1_CLK_L':'(0,BG64,0,0,0,0,0,0,0,0,0,0,0,0,0,0,0,0,0,0,0,0,0,0,0,0,0,0,0,0~
,0,0,0,0,0,0,0,0,0,0)';$S;OUT;
    'MBB_DATA19':'(0,CT62,0,0,0,0,0,0,0,0,0,0,0,0,0,0,0,0,0,0,0,0,0,0,0,0,0,0,0,~
0,0,0,0,0,0,0,0,0,0,0)';$S;BIDI;
    'MBA_DATA24':'(0,AC64,0,0,0,0,0,0,0,0,0,0,0,0,0,0,0,0,0,0,0,0,0,0,0,0,0,0,0,~
0,0,0,0,0,0,0,0,0,0,0)';$S;BIDI;
    'MBB_DATA20':'(0,CV63,0,0,0,0,0,0,0,0,0,0,0,0,0,0,0,0,0,0,0,0,0,0,0,0,0,0,0,~
0,0,0,0,0,0,0,0,0,0,0)';$S;BIDI;
    'TEST39B':'(0,BF62,0,0,0,0,0,0,0,0,0,0,0,0,0,0,0,0,0,0,0,0,0,0,0,0,0,0,0,0,0~
,0,0,0,0,0,0,0,0,0)';$S;OUT;
    'MC_ALERT_L':'(0,0,AT55,0,0,0,0,0,0,0,0,0,0,0,0,0,0,0,0,0,0,0,0,0,0,0,0,0,0,~
0,0,0,0,0,0,0,0,0,0,0)';$S;IN;
    'MC_RESET_L':'(0,0,AU55,0,0,0,0,0,0,0,0,0,0,0,0,0,0,0,0,0,0,0,0,0,0,0,0,0,0,~
0,0,0,0,0,0,0,0,0,0,0)';$S;OUT;
    'MCB_DQS_H8':'(0,0,DD55,0,0,0,0,0,0,0,0,0,0,0,0,0,0,0,0,0,0,0,0,0,0,0,0,0,0,~
0,0,0,0,0,0,0,0,0,0,0)';$S;BIDI;
    'MCB_DATA30':'(0,0,DE57,0,0,0,0,0,0,0,0,0,0,0,0,0,0,0,0,0,0,0,0,0,0,0,0,0,0,~
0,0,0,0,0,0,0,0,0,0,0)';$S;BIDI;
    'MCB_DATA8':'(0,0,CH56,0,0,0,0,0,0,0,0,0,0,0,0,0,0,0,0,0,0,0,0,0,0,0,0,0,0,0~
,0,0,0,0,0,0,0,0,0,0)';$S;BIDI;
    'MCB1_CS_L1':'(0,0,BM56,0,0,0,0,0,0,0,0,0,0,0,0,0,0,0,0,0,0,0,0,0,0,0,0,0,0,~
0,0,0,0,0,0,0,0,0,0,0)';$S;OUT;
    'MCB0_CS_L1':'(0,0,BN57,0,0,0,0,0,0,0,0,0,0,0,0,0,0,0,0,0,0,0,0,0,0,0,0,0,0,~
0,0,0,0,0,0,0,0,0,0,0)';$S;OUT;
    'MCA_DQS_L1':'(0,0,P56,0,0,0,0,0,0,0,0,0,0,0,0,0,0,0,0,0,0,0,0,0,0,0,0,0,0,0~
,0,0,0,0,0,0,0,0,0,0)';$S;BIDI;
    'MCA_DATA25':'(0,0,AD55,0,0,0,0,0,0,0,0,0,0,0,0,0,0,0,0,0,0,0,0,0,0,0,0,0,0,~
0,0,0,0,0,0,0,0,0,0,0)';$S;BIDI;
    'MCA_DATA14':'(0,0,T56,0,0,0,0,0,0,0,0,0,0,0,0,0,0,0,0,0,0,0,0,0,0,0,0,0,0,0~
,0,0,0,0,0,0,0,0,0,0)';$S;BIDI;
    'MCA_DATA9':'(0,0,M55,0,0,0,0,0,0,0,0,0,0,0,0,0,0,0,0,0,0,0,0,0,0,0,0,0,0,0,~
0,0,0,0,0,0,0,0,0,0)';$S;BIDI;
    'MCA_CHECK5':'(0,0,AP55,0,0,0,0,0,0,0,0,0,0,0,0,0,0,0,0,0,0,0,0,0,0,0,0,0,0,~
0,0,0,0,0,0,0,0,0,0,0)';$S;BIDI;
    'MCB_DATA31':'(0,0,DF55,0,0,0,0,0,0,0,0,0,0,0,0,0,0,0,0,0,0,0,0,0,0,0,0,0,0,~
0,0,0,0,0,0,0,0,0,0,0)';$S;BIDI;
    'MCB_DATA20':'(0,0,CV56,0,0,0,0,0,0,0,0,0,0,0,0,0,0,0,0,0,0,0,0,0,0,0,0,0,0,~
0,0,0,0,0,0,0,0,0,0,0)';$S;BIDI;
    'MCB_DATA9':'(0,0,CJ55,0,0,0,0,0,0,0,0,0,0,0,0,0,0,0,0,0,0,0,0,0,0,0,0,0,0,0~
,0,0,0,0,0,0,0,0,0,0)';$S;BIDI;
    'MCB_CHECK0':'(0,0,BY56,0,0,0,0,0,0,0,0,0,0,0,0,0,0,0,0,0,0,0,0,0,0,0,0,0,0,~
0,0,0,0,0,0,0,0,0,0,0)';$S;BIDI;
    'MCA_DQS_L2':'(0,0,Y56,0,0,0,0,0,0,0,0,0,0,0,0,0,0,0,0,0,0,0,0,0,0,0,0,0,0,0~
,0,0,0,0,0,0,0,0,0,0)';$S;BIDI;
    'MCA_DATA26':'(0,0,AD56,0,0,0,0,0,0,0,0,0,0,0,0,0,0,0,0,0,0,0,0,0,0,0,0,0,0,~
0,0,0,0,0,0,0,0,0,0,0)';$S;BIDI;
    'MCA_DATA15':'(0,0,U55,0,0,0,0,0,0,0,0,0,0,0,0,0,0,0,0,0,0,0,0,0,0,0,0,0,0,0~
,0,0,0,0,0,0,0,0,0,0)';$S;BIDI;
    'MCA_CHECK6':'(0,0,AP56,0,0,0,0,0,0,0,0,0,0,0,0,0,0,0,0,0,0,0,0,0,0,0,0,0,0,~
0,0,0,0,0,0,0,0,0,0,0)';$S;BIDI;
    'MCA0_RSP_L':'(0,0,BN55,0,0,0,0,0,0,0,0,0,0,0,0,0,0,0,0,0,0,0,0,0,0,0,0,0,0,~
0,0,0,0,0,0,0,0,0,0,0)';$S;IN;
    'MCB_DATA21':'(0,0,CW55,0,0,0,0,0,0,0,0,0,0,0,0,0,0,0,0,0,0,0,0,0,0,0,0,0,0,~
0,0,0,0,0,0,0,0,0,0,0)';$S;BIDI;
    'MCB_DATA10':'(0,0,CJ57,0,0,0,0,0,0,0,0,0,0,0,0,0,0,0,0,0,0,0,0,0,0,0,0,0,0,~
0,0,0,0,0,0,0,0,0,0,0)';$S;BIDI;
    'MCB_CHECK1':'(0,0,CA55,0,0,0,0,0,0,0,0,0,0,0,0,0,0,0,0,0,0,0,0,0,0,0,0,0,0,~
0,0,0,0,0,0,0,0,0,0,0)';$S;BIDI;
    'MCA_DQS_L3':'(0,0,AF56,0,0,0,0,0,0,0,0,0,0,0,0,0,0,0,0,0,0,0,0,0,0,0,0,0,0,~
0,0,0,0,0,0,0,0,0,0,0)';$S;BIDI;
    'MCA_DATA27':'(0,0,AE55,0,0,0,0,0,0,0,0,0,0,0,0,0,0,0,0,0,0,0,0,0,0,0,0,0,0,~
0,0,0,0,0,0,0,0,0,0,0)';$S;BIDI;
    'MCA_DATA16':'(0,0,U57,0,0,0,0,0,0,0,0,0,0,0,0,0,0,0,0,0,0,0,0,0,0,0,0,0,0,0~
,0,0,0,0,0,0,0,0,0,0)';$S;BIDI;
    'MCA_CHECK7':'(0,0,AR55,0,0,0,0,0,0,0,0,0,0,0,0,0,0,0,0,0,0,0,0,0,0,0,0,0,0,~
0,0,0,0,0,0,0,0,0,0,0)';$S;BIDI;
    'MCA1_RSP_L':'(0,0,BP55,0,0,0,0,0,0,0,0,0,0,0,0,0,0,0,0,0,0,0,0,0,0,0,0,0,0,~
0,0,0,0,0,0,0,0,0,0,0)';$S;IN;
    'MCB_DATA22':'(0,0,CW57,0,0,0,0,0,0,0,0,0,0,0,0,0,0,0,0,0,0,0,0,0,0,0,0,0,0,~
0,0,0,0,0,0,0,0,0,0,0)';$S;BIDI;
    'MCB_DATA11':'(0,0,CK55,0,0,0,0,0,0,0,0,0,0,0,0,0,0,0,0,0,0,0,0,0,0,0,0,0,0,~
0,0,0,0,0,0,0,0,0,0,0)';$S;BIDI;
    'MCB_CHECK2':'(0,0,CA57,0,0,0,0,0,0,0,0,0,0,0,0,0,0,0,0,0,0,0,0,0,0,0,0,0,0,~
0,0,0,0,0,0,0,0,0,0,0)';$S;BIDI;
    'MCA_DQS_L4':'(0,0,AM56,0,0,0,0,0,0,0,0,0,0,0,0,0,0,0,0,0,0,0,0,0,0,0,0,0,0,~
0,0,0,0,0,0,0,0,0,0,0)';$S;BIDI;
    'MCA_DQS_H0':'(0,0,G57,0,0,0,0,0,0,0,0,0,0,0,0,0,0,0,0,0,0,0,0,0,0,0,0,0,0,0~
,0,0,0,0,0,0,0,0,0,0)';$S;BIDI;
    'MCA_DATA28':'(0,0,AG57,0,0,0,0,0,0,0,0,0,0,0,0,0,0,0,0,0,0,0,0,0,0,0,0,0,0,~
0,0,0,0,0,0,0,0,0,0,0)';$S;BIDI;
    'MCA_DATA17':'(0,0,V55,0,0,0,0,0,0,0,0,0,0,0,0,0,0,0,0,0,0,0,0,0,0,0,0,0,0,0~
,0,0,0,0,0,0,0,0,0,0)';$S;BIDI;
    'MCB_DATA23':'(0,0,CY55,0,0,0,0,0,0,0,0,0,0,0,0,0,0,0,0,0,0,0,0,0,0,0,0,0,0,~
0,0,0,0,0,0,0,0,0,0,0)';$S;BIDI;
    'MCB_DATA12':'(0,0,CM56,0,0,0,0,0,0,0,0,0,0,0,0,0,0,0,0,0,0,0,0,0,0,0,0,0,0,~
0,0,0,0,0,0,0,0,0,0,0)';$S;BIDI;
    'MCB_CHECK3':'(0,0,CB55,0,0,0,0,0,0,0,0,0,0,0,0,0,0,0,0,0,0,0,0,0,0,0,0,0,0,~
0,0,0,0,0,0,0,0,0,0,0)';$S;BIDI;
    'MCA_DQS_L5':'(0,0,H55,0,0,0,0,0,0,0,0,0,0,0,0,0,0,0,0,0,0,0,0,0,0,0,0,0,0,0~
,0,0,0,0,0,0,0,0,0,0)';$S;BIDI;
    'MCA_DQS_H1':'(0,0,N57,0,0,0,0,0,0,0,0,0,0,0,0,0,0,0,0,0,0,0,0,0,0,0,0,0,0,0~
,0,0,0,0,0,0,0,0,0,0)';$S;BIDI;
    'MCA_DATA29':'(0,0,AH55,0,0,0,0,0,0,0,0,0,0,0,0,0,0,0,0,0,0,0,0,0,0,0,0,0,0,~
0,0,0,0,0,0,0,0,0,0,0)';$S;BIDI;
    'MCA_DATA18':'(0,0,V56,0,0,0,0,0,0,0,0,0,0,0,0,0,0,0,0,0,0,0,0,0,0,0,0,0,0,0~
,0,0,0,0,0,0,0,0,0,0)';$S;BIDI;
    'MCB_DQS_L0':'(0,0,CE57,0,0,0,0,0,0,0,0,0,0,0,0,0,0,0,0,0,0,0,0,0,0,0,0,0,0,~
0,0,0,0,0,0,0,0,0,0,0)';$S;BIDI;
    'MCB_DATA24':'(0,0,CY56,0,0,0,0,0,0,0,0,0,0,0,0,0,0,0,0,0,0,0,0,0,0,0,0,0,0,~
0,0,0,0,0,0,0,0,0,0,0)';$S;BIDI;
    'MCB_DATA13':'(0,0,CN55,0,0,0,0,0,0,0,0,0,0,0,0,0,0,0,0,0,0,0,0,0,0,0,0,0,0,~
0,0,0,0,0,0,0,0,0,0,0)';$S;BIDI;
    'MCB_CHECK4':'(0,0,BT56,0,0,0,0,0,0,0,0,0,0,0,0,0,0,0,0,0,0,0,0,0,0,0,0,0,0,~
0,0,0,0,0,0,0,0,0,0,0)';$S;BIDI;
    'MCA_DQS_L6':'(0,0,P55,0,0,0,0,0,0,0,0,0,0,0,0,0,0,0,0,0,0,0,0,0,0,0,0,0,0,0~
,0,0,0,0,0,0,0,0,0,0)';$S;BIDI;
    'MCA_DQS_H2':'(0,0,W57,0,0,0,0,0,0,0,0,0,0,0,0,0,0,0,0,0,0,0,0,0,0,0,0,0,0,0~
,0,0,0,0,0,0,0,0,0,0)';$S;BIDI;
    'MCA_DATA19':'(0,0,W55,0,0,0,0,0,0,0,0,0,0,0,0,0,0,0,0,0,0,0,0,0,0,0,0,0,0,0~
,0,0,0,0,0,0,0,0,0,0)';$S;BIDI;
    'MCB_DQS_L1':'(0,0,CL57,0,0,0,0,0,0,0,0,0,0,0,0,0,0,0,0,0,0,0,0,0,0,0,0,0,0,~
0,0,0,0,0,0,0,0,0,0,0)';$S;BIDI;
    'MCB_DATA25':'(0,0,DA55,0,0,0,0,0,0,0,0,0,0,0,0,0,0,0,0,0,0,0,0,0,0,0,0,0,0,~
0,0,0,0,0,0,0,0,0,0,0)';$S;BIDI;
    'MCB_DATA14':'(0,0,CN57,0,0,0,0,0,0,0,0,0,0,0,0,0,0,0,0,0,0,0,0,0,0,0,0,0,0,~
0,0,0,0,0,0,0,0,0,0,0)';$S;BIDI;
    'MCB_CHECK5':'(0,0,BU55,0,0,0,0,0,0,0,0,0,0,0,0,0,0,0,0,0,0,0,0,0,0,0,0,0,0,~
0,0,0,0,0,0,0,0,0,0,0)';$S;BIDI;
    'MCA_DQS_L7':'(0,0,Y55,0,0,0,0,0,0,0,0,0,0,0,0,0,0,0,0,0,0,0,0,0,0,0,0,0,0,0~
,0,0,0,0,0,0,0,0,0,0)';$S;BIDI;
    'MCA_DQS_H3':'(0,0,AE57,0,0,0,0,0,0,0,0,0,0,0,0,0,0,0,0,0,0,0,0,0,0,0,0,0,0,~
0,0,0,0,0,0,0,0,0,0,0)';$S;BIDI;
    'MCB_DQS_L2':'(0,0,CU57,0,0,0,0,0,0,0,0,0,0,0,0,0,0,0,0,0,0,0,0,0,0,0,0,0,0,~
0,0,0,0,0,0,0,0,0,0,0)';$S;BIDI;
    'MCB_DATA26':'(0,0,DA57,0,0,0,0,0,0,0,0,0,0,0,0,0,0,0,0,0,0,0,0,0,0,0,0,0,0,~
0,0,0,0,0,0,0,0,0,0,0)';$S;BIDI;
    'MCB_DATA15':'(0,0,CP55,0,0,0,0,0,0,0,0,0,0,0,0,0,0,0,0,0,0,0,0,0,0,0,0,0,0,~
0,0,0,0,0,0,0,0,0,0,0)';$S;BIDI;
    'MCB_CHECK6':'(0,0,BU57,0,0,0,0,0,0,0,0,0,0,0,0,0,0,0,0,0,0,0,0,0,0,0,0,0,0,~
0,0,0,0,0,0,0,0,0,0,0)';$S;BIDI;
    'MCA_DQS_L8':'(0,0,AF55,0,0,0,0,0,0,0,0,0,0,0,0,0,0,0,0,0,0,0,0,0,0,0,0,0,0,~
0,0,0,0,0,0,0,0,0,0,0)';$S;BIDI;
    'MCA_DQS_H4':'(0,0,AL57,0,0,0,0,0,0,0,0,0,0,0,0,0,0,0,0,0,0,0,0,0,0,0,0,0,0,~
0,0,0,0,0,0,0,0,0,0,0)';$S;BIDI;
    'MCA_CA0':'(0,0,AW57,0,0,0,0,0,0,0,0,0,0,0,0,0,0,0,0,0,0,0,0,0,0,0,0,0,0,0,0~
,0,0,0,0,0,0,0,0,0)';$S;OUT;
    'MCB_DQS_L3':'(0,0,DC57,0,0,0,0,0,0,0,0,0,0,0,0,0,0,0,0,0,0,0,0,0,0,0,0,0,0,~
0,0,0,0,0,0,0,0,0,0,0)';$S;BIDI;
    'MCB_DATA27':'(0,0,DB55,0,0,0,0,0,0,0,0,0,0,0,0,0,0,0,0,0,0,0,0,0,0,0,0,0,0,~
0,0,0,0,0,0,0,0,0,0,0)';$S;BIDI;
    'MCB_DATA16':'(0,0,CP56,0,0,0,0,0,0,0,0,0,0,0,0,0,0,0,0,0,0,0,0,0,0,0,0,0,0,~
0,0,0,0,0,0,0,0,0,0,0)';$S;BIDI;
    'MCB_CHECK7':'(0,0,BV55,0,0,0,0,0,0,0,0,0,0,0,0,0,0,0,0,0,0,0,0,0,0,0,0,0,0,~
0,0,0,0,0,0,0,0,0,0,0)';$S;BIDI;
    'MCB_CA0':'(0,0,BG55,0,0,0,0,0,0,0,0,0,0,0,0,0,0,0,0,0,0,0,0,0,0,0,0,0,0,0,0~
,0,0,0,0,0,0,0,0,0)';$S;OUT;
    'MCB1_RSP_L':'(0,0,BR57,0,0,0,0,0,0,0,0,0,0,0,0,0,0,0,0,0,0,0,0,0,0,0,0,0,0,~
0,0,0,0,0,0,0,0,0,0,0)';$S;IN;
    'MCB0_RSP_L':'(0,0,BP56,0,0,0,0,0,0,0,0,0,0,0,0,0,0,0,0,0,0,0,0,0,0,0,0,0,0,~
0,0,0,0,0,0,0,0,0,0,0)';$S;IN;
    'MCA_DQS_L9':'(0,0,AM55,0,0,0,0,0,0,0,0,0,0,0,0,0,0,0,0,0,0,0,0,0,0,0,0,0,0,~
0,0,0,0,0,0,0,0,0,0,0)';$S;BIDI;
    'MCA_DQS_H5':'(0,0,J55,0,0,0,0,0,0,0,0,0,0,0,0,0,0,0,0,0,0,0,0,0,0,0,0,0,0,0~
,0,0,0,0,0,0,0,0,0,0)';$S;BIDI;
    'MCA_DATA0':'(0,0,E57,0,0,0,0,0,0,0,0,0,0,0,0,0,0,0,0,0,0,0,0,0,0,0,0,0,0,0,~
0,0,0,0,0,0,0,0,0,0)';$S;BIDI;
    'MCA_CA1':'(0,0,AY56,0,0,0,0,0,0,0,0,0,0,0,0,0,0,0,0,0,0,0,0,0,0,0,0,0,0,0,0~
,0,0,0,0,0,0,0,0,0)';$S;OUT;
    'MCB_DQS_L4':'(0,0,BW55,0,0,0,0,0,0,0,0,0,0,0,0,0,0,0,0,0,0,0,0,0,0,0,0,0,0,~
0,0,0,0,0,0,0,0,0,0,0)';$S;BIDI;
    'MCB_DQS_H0':'(0,0,CD56,0,0,0,0,0,0,0,0,0,0,0,0,0,0,0,0,0,0,0,0,0,0,0,0,0,0,~
0,0,0,0,0,0,0,0,0,0,0)';$S;BIDI;
    'MCB_DATA28':'(0,0,DD56,0,0,0,0,0,0,0,0,0,0,0,0,0,0,0,0,0,0,0,0,0,0,0,0,0,0,~
0,0,0,0,0,0,0,0,0,0,0)';$S;BIDI;
    'MCB_DATA17':'(0,0,CR55,0,0,0,0,0,0,0,0,0,0,0,0,0,0,0,0,0,0,0,0,0,0,0,0,0,0,~
0,0,0,0,0,0,0,0,0,0,0)';$S;BIDI;
    'MCB_DATA0':'(0,0,CB56,0,0,0,0,0,0,0,0,0,0,0,0,0,0,0,0,0,0,0,0,0,0,0,0,0,0,0~
,0,0,0,0,0,0,0,0,0,0)';$S;BIDI;
    'MCB_CA1':'(0,0,BH55,0,0,0,0,0,0,0,0,0,0,0,0,0,0,0,0,0,0,0,0,0,0,0,0,0,0,0,0~
,0,0,0,0,0,0,0,0,0)';$S;OUT;
    'MCA_DQS_H6':'(0,0,R55,0,0,0,0,0,0,0,0,0,0,0,0,0,0,0,0,0,0,0,0,0,0,0,0,0,0,0~
,0,0,0,0,0,0,0,0,0,0)';$S;BIDI;
    'MCA_DATA1':'(0,0,F55,0,0,0,0,0,0,0,0,0,0,0,0,0,0,0,0,0,0,0,0,0,0,0,0,0,0,0,~
0,0,0,0,0,0,0,0,0,0)';$S;BIDI;
    'MCA_CA2':'(0,0,AY55,0,0,0,0,0,0,0,0,0,0,0,0,0,0,0,0,0,0,0,0,0,0,0,0,0,0,0,0~
,0,0,0,0,0,0,0,0,0)';$S;OUT;
    'MCA0_CS_L0':'(0,0,AV56,0,0,0,0,0,0,0,0,0,0,0,0,0,0,0,0,0,0,0,0,0,0,0,0,0,0,~
0,0,0,0,0,0,0,0,0,0,0)';$S;OUT;
    'MCB_DQS_L5':'(0,0,CE55,0,0,0,0,0,0,0,0,0,0,0,0,0,0,0,0,0,0,0,0,0,0,0,0,0,0,~
0,0,0,0,0,0,0,0,0,0,0)';$S;BIDI;
    'MCB_DQS_H1':'(0,0,CK56,0,0,0,0,0,0,0,0,0,0,0,0,0,0,0,0,0,0,0,0,0,0,0,0,0,0,~
0,0,0,0,0,0,0,0,0,0,0)';$S;BIDI;
    'MCB_DATA29':'(0,0,DE55,0,0,0,0,0,0,0,0,0,0,0,0,0,0,0,0,0,0,0,0,0,0,0,0,0,0,~
0,0,0,0,0,0,0,0,0,0,0)';$S;BIDI;
    'MCB_DATA18':'(0,0,CR57,0,0,0,0,0,0,0,0,0,0,0,0,0,0,0,0,0,0,0,0,0,0,0,0,0,0,~
0,0,0,0,0,0,0,0,0,0,0)';$S;BIDI;
    'MCB_DATA1':'(0,0,CC55,0,0,0,0,0,0,0,0,0,0,0,0,0,0,0,0,0,0,0,0,0,0,0,0,0,0,0~
,0,0,0,0,0,0,0,0,0,0)';$S;BIDI;
    'MCB_CA2':'(0,0,BH56,0,0,0,0,0,0,0,0,0,0,0,0,0,0,0,0,0,0,0,0,0,0,0,0,0,0,0,0~
,0,0,0,0,0,0,0,0,0)';$S;OUT;
    'MCA_DQS_H7':'(0,0,AA55,0,0,0,0,0,0,0,0,0,0,0,0,0,0,0,0,0,0,0,0,0,0,0,0,0,0,~
0,0,0,0,0,0,0,0,0,0,0)';$S;BIDI;
    'MCA_DATA2':'(0,0,F56,0,0,0,0,0,0,0,0,0,0,0,0,0,0,0,0,0,0,0,0,0,0,0,0,0,0,0,~
0,0,0,0,0,0,0,0,0,0)';$S;BIDI;
    'MCA_CA3':'(0,0,BA55,0,0,0,0,0,0,0,0,0,0,0,0,0,0,0,0,0,0,0,0,0,0,0,0,0,0,0,0~
,0,0,0,0,0,0,0,0,0)';$S;OUT;
    'MCA1_CS_L0':'(0,0,AU57,0,0,0,0,0,0,0,0,0,0,0,0,0,0,0,0,0,0,0,0,0,0,0,0,0,0,~
0,0,0,0,0,0,0,0,0,0,0)';$S;OUT;
    'MCA0_CS_L1':'(0,0,AW55,0,0,0,0,0,0,0,0,0,0,0,0,0,0,0,0,0,0,0,0,0,0,0,0,0,0,~
0,0,0,0,0,0,0,0,0,0,0)';$S;OUT;
    'MCB_DQS_L6':'(0,0,CL55,0,0,0,0,0,0,0,0,0,0,0,0,0,0,0,0,0,0,0,0,0,0,0,0,0,0,~
0,0,0,0,0,0,0,0,0,0,0)';$S;BIDI;
    'MCB_DQS_H2':'(0,0,CT56,0,0,0,0,0,0,0,0,0,0,0,0,0,0,0,0,0,0,0,0,0,0,0,0,0,0,~
0,0,0,0,0,0,0,0,0,0,0)';$S;BIDI;
    'MCB_DATA19':'(0,0,CT55,0,0,0,0,0,0,0,0,0,0,0,0,0,0,0,0,0,0,0,0,0,0,0,0,0,0,~
0,0,0,0,0,0,0,0,0,0,0)';$S;BIDI;
    'MCB_DATA2':'(0,0,CC57,0,0,0,0,0,0,0,0,0,0,0,0,0,0,0,0,0,0,0,0,0,0,0,0,0,0,0~
,0,0,0,0,0,0,0,0,0,0)';$S;BIDI;
    'MCB_CA3':'(0,0,BJ57,0,0,0,0,0,0,0,0,0,0,0,0,0,0,0,0,0,0,0,0,0,0,0,0,0,0,0,0~
,0,0,0,0,0,0,0,0,0)';$S;OUT;
    'MCA_DQS_H8':'(0,0,AG55,0,0,0,0,0,0,0,0,0,0,0,0,0,0,0,0,0,0,0,0,0,0,0,0,0,0,~
0,0,0,0,0,0,0,0,0,0,0)';$S;BIDI;
    'MCA_DATA30':'(0,0,AH56,0,0,0,0,0,0,0,0,0,0,0,0,0,0,0,0,0,0,0,0,0,0,0,0,0,0,~
0,0,0,0,0,0,0,0,0,0,0)';$S;BIDI;
    'MCA_DATA3':'(0,0,G55,0,0,0,0,0,0,0,0,0,0,0,0,0,0,0,0,0,0,0,0,0,0,0,0,0,0,0,~
0,0,0,0,0,0,0,0,0,0)';$S;BIDI;
    'MCA_CA4':'(0,0,BA57,0,0,0,0,0,0,0,0,0,0,0,0,0,0,0,0,0,0,0,0,0,0,0,0,0,0,0,0~
,0,0,0,0,0,0,0,0,0)';$S;OUT;
    'MCA1_CS_L1':'(0,0,AV55,0,0,0,0,0,0,0,0,0,0,0,0,0,0,0,0,0,0,0,0,0,0,0,0,0,0,~
0,0,0,0,0,0,0,0,0,0,0)';$S;OUT;
    'MCB_DQS_L7':'(0,0,CU55,0,0,0,0,0,0,0,0,0,0,0,0,0,0,0,0,0,0,0,0,0,0,0,0,0,0,~
0,0,0,0,0,0,0,0,0,0,0)';$S;BIDI;
    'MCB_DQS_H3':'(0,0,DB56,0,0,0,0,0,0,0,0,0,0,0,0,0,0,0,0,0,0,0,0,0,0,0,0,0,0,~
0,0,0,0,0,0,0,0,0,0,0)';$S;BIDI;
    'MCB_DATA3':'(0,0,CD55,0,0,0,0,0,0,0,0,0,0,0,0,0,0,0,0,0,0,0,0,0,0,0,0,0,0,0~
,0,0,0,0,0,0,0,0,0,0)';$S;BIDI;
    'MCB_CA4':'(0,0,BJ55,0,0,0,0,0,0,0,0,0,0,0,0,0,0,0,0,0,0,0,0,0,0,0,0,0,0,0,0~
,0,0,0,0,0,0,0,0,0)';$S;OUT;
    'MCA_DQS_H9':'(0,0,AN55,0,0,0,0,0,0,0,0,0,0,0,0,0,0,0,0,0,0,0,0,0,0,0,0,0,0,~
0,0,0,0,0,0,0,0,0,0,0)';$S;BIDI;
    'MCA_DATA31':'(0,0,AJ55,0,0,0,0,0,0,0,0,0,0,0,0,0,0,0,0,0,0,0,0,0,0,0,0,0,0,~
0,0,0,0,0,0,0,0,0,0,0)';$S;BIDI;
    'MCA_DATA20':'(0,0,AA57,0,0,0,0,0,0,0,0,0,0,0,0,0,0,0,0,0,0,0,0,0,0,0,0,0,0,~
0,0,0,0,0,0,0,0,0,0,0)';$S;BIDI;
    'MCA_DATA4':'(0,0,J57,0,0,0,0,0,0,0,0,0,0,0,0,0,0,0,0,0,0,0,0,0,0,0,0,0,0,0,~
0,0,0,0,0,0,0,0,0,0)';$S;BIDI;
    'MCA_CHECK0':'(0,0,AJ57,0,0,0,0,0,0,0,0,0,0,0,0,0,0,0,0,0,0,0,0,0,0,0,0,0,0,~
0,0,0,0,0,0,0,0,0,0,0)';$S;BIDI;
    'MCA_CA5':'(0,0,BB56,0,0,0,0,0,0,0,0,0,0,0,0,0,0,0,0,0,0,0,0,0,0,0,0,0,0,0,0~
,0,0,0,0,0,0,0,0,0)';$S;OUT;
    'MCB_DQS_L8':'(0,0,DC55,0,0,0,0,0,0,0,0,0,0,0,0,0,0,0,0,0,0,0,0,0,0,0,0,0,0,~
0,0,0,0,0,0,0,0,0,0,0)';$S;BIDI;
    'MCB_DQS_H4':'(0,0,BY55,0,0,0,0,0,0,0,0,0,0,0,0,0,0,0,0,0,0,0,0,0,0,0,0,0,0,~
0,0,0,0,0,0,0,0,0,0,0)';$S;BIDI;
    'MCB_DATA4':'(0,0,CF56,0,0,0,0,0,0,0,0,0,0,0,0,0,0,0,0,0,0,0,0,0,0,0,0,0,0,0~
,0,0,0,0,0,0,0,0,0,0)';$S;BIDI;
    'MCB_CA5':'(0,0,BK55,0,0,0,0,0,0,0,0,0,0,0,0,0,0,0,0,0,0,0,0,0,0,0,0,0,0,0,0~
,0,0,0,0,0,0,0,0,0)';$S;OUT;
    'MCA_DATA21':'(0,0,AB55,0,0,0,0,0,0,0,0,0,0,0,0,0,0,0,0,0,0,0,0,0,0,0,0,0,0,~
0,0,0,0,0,0,0,0,0,0,0)';$S;BIDI;
    'MCA_DATA10':'(0,0,M56,0,0,0,0,0,0,0,0,0,0,0,0,0,0,0,0,0,0,0,0,0,0,0,0,0,0,0~
,0,0,0,0,0,0,0,0,0,0)';$S;BIDI;
    'MCA_DATA5':'(0,0,K55,0,0,0,0,0,0,0,0,0,0,0,0,0,0,0,0,0,0,0,0,0,0,0,0,0,0,0,~
0,0,0,0,0,0,0,0,0,0)';$S;BIDI;
    'MCA_CHECK1':'(0,0,AK55,0,0,0,0,0,0,0,0,0,0,0,0,0,0,0,0,0,0,0,0,0,0,0,0,0,0,~
0,0,0,0,0,0,0,0,0,0,0)';$S;BIDI;
    'MCA_CA6':'(0,0,BB55,0,0,0,0,0,0,0,0,0,0,0,0,0,0,0,0,0,0,0,0,0,0,0,0,0,0,0,0~
,0,0,0,0,0,0,0,0,0)';$S;OUT;
    'MCB_DQS_L9':'(0,0,BW57,0,0,0,0,0,0,0,0,0,0,0,0,0,0,0,0,0,0,0,0,0,0,0,0,0,0,~
0,0,0,0,0,0,0,0,0,0,0)';$S;BIDI;
    'MCB_DQS_H5':'(0,0,CF55,0,0,0,0,0,0,0,0,0,0,0,0,0,0,0,0,0,0,0,0,0,0,0,0,0,0,~
0,0,0,0,0,0,0,0,0,0,0)';$S;BIDI;
    'MCB_DATA5':'(0,0,CG55,0,0,0,0,0,0,0,0,0,0,0,0,0,0,0,0,0,0,0,0,0,0,0,0,0,0,0~
,0,0,0,0,0,0,0,0,0,0)';$S;BIDI;
    'MCB_CA6':'(0,0,BK56,0,0,0,0,0,0,0,0,0,0,0,0,0,0,0,0,0,0,0,0,0,0,0,0,0,0,0,0~
,0,0,0,0,0,0,0,0,0)';$S;OUT;
    'MCA_DATA22':'(0,0,AB56,0,0,0,0,0,0,0,0,0,0,0,0,0,0,0,0,0,0,0,0,0,0,0,0,0,0,~
0,0,0,0,0,0,0,0,0,0,0)';$S;BIDI;
    'MCA_DATA11':'(0,0,N55,0,0,0,0,0,0,0,0,0,0,0,0,0,0,0,0,0,0,0,0,0,0,0,0,0,0,0~
,0,0,0,0,0,0,0,0,0,0)';$S;BIDI;
    'MCA_DATA6':'(0,0,K56,0,0,0,0,0,0,0,0,0,0,0,0,0,0,0,0,0,0,0,0,0,0,0,0,0,0,0,~
0,0,0,0,0,0,0,0,0,0)';$S;BIDI;
    'MCA_CHECK2':'(0,0,AK56,0,0,0,0,0,0,0,0,0,0,0,0,0,0,0,0,0,0,0,0,0,0,0,0,0,0,~
0,0,0,0,0,0,0,0,0,0,0)';$S;BIDI;
    'MCB_DQS_H6':'(0,0,CM55,0,0,0,0,0,0,0,0,0,0,0,0,0,0,0,0,0,0,0,0,0,0,0,0,0,0,~
0,0,0,0,0,0,0,0,0,0,0)';$S;BIDI;
    'MCB_DATA6':'(0,0,CG57,0,0,0,0,0,0,0,0,0,0,0,0,0,0,0,0,0,0,0,0,0,0,0,0,0,0,0~
,0,0,0,0,0,0,0,0,0,0)';$S;BIDI;
    'MCA_DATA23':'(0,0,AC55,0,0,0,0,0,0,0,0,0,0,0,0,0,0,0,0,0,0,0,0,0,0,0,0,0,0,~
0,0,0,0,0,0,0,0,0,0,0)';$S;BIDI;
    'MCA_DATA12':'(0,0,R57,0,0,0,0,0,0,0,0,0,0,0,0,0,0,0,0,0,0,0,0,0,0,0,0,0,0,0~
,0,0,0,0,0,0,0,0,0,0)';$S;BIDI;
    'MCA_DATA7':'(0,0,L55,0,0,0,0,0,0,0,0,0,0,0,0,0,0,0,0,0,0,0,0,0,0,0,0,0,0,0,~
0,0,0,0,0,0,0,0,0,0)';$S;BIDI;
    'MCA_CHECK3':'(0,0,AL55,0,0,0,0,0,0,0,0,0,0,0,0,0,0,0,0,0,0,0,0,0,0,0,0,0,0,~
0,0,0,0,0,0,0,0,0,0,0)';$S;BIDI;
    'MCB_DQS_H7':'(0,0,CV55,0,0,0,0,0,0,0,0,0,0,0,0,0,0,0,0,0,0,0,0,0,0,0,0,0,0,~
0,0,0,0,0,0,0,0,0,0,0)';$S;BIDI;
    'MCB_DATA7':'(0,0,CH55,0,0,0,0,0,0,0,0,0,0,0,0,0,0,0,0,0,0,0,0,0,0,0,0,0,0,0~
,0,0,0,0,0,0,0,0,0,0)';$S;BIDI;
    'MCB1_CS_L0':'(0,0,BL55,0,0,0,0,0,0,0,0,0,0,0,0,0,0,0,0,0,0,0,0,0,0,0,0,0,0,~
0,0,0,0,0,0,0,0,0,0,0)';$S;OUT;
    'MCB0_CS_L0':'(0,0,BM55,0,0,0,0,0,0,0,0,0,0,0,0,0,0,0,0,0,0,0,0,0,0,0,0,0,0,~
0,0,0,0,0,0,0,0,0,0,0)';$S;OUT;
    'MCA_DQS_L0':'(0,0,H56,0,0,0,0,0,0,0,0,0,0,0,0,0,0,0,0,0,0,0,0,0,0,0,0,0,0,0~
,0,0,0,0,0,0,0,0,0,0)';$S;BIDI;
    'MCA_DATA24':'(0,0,AC57,0,0,0,0,0,0,0,0,0,0,0,0,0,0,0,0,0,0,0,0,0,0,0,0,0,0,~
0,0,0,0,0,0,0,0,0,0,0)';$S;BIDI;
    'MCA_DATA13':'(0,0,T55,0,0,0,0,0,0,0,0,0,0,0,0,0,0,0,0,0,0,0,0,0,0,0,0,0,0,0~
,0,0,0,0,0,0,0,0,0,0)';$S;BIDI;
    'MCA_DATA8':'(0,0,L57,0,0,0,0,0,0,0,0,0,0,0,0,0,0,0,0,0,0,0,0,0,0,0,0,0,0,0,~
0,0,0,0,0,0,0,0,0,0)';$S;BIDI;
    'MCA_CHECK4':'(0,0,AN57,0,0,0,0,0,0,0,0,0,0,0,0,0,0,0,0,0,0,0,0,0,0,0,0,0,0,~
0,0,0,0,0,0,0,0,0,0,0)';$S;BIDI;
    'MCB_DQS_H9':'(0,0,BV56,0,0,0,0,0,0,0,0,0,0,0,0,0,0,0,0,0,0,0,0,0,0,0,0,0,0,~
0,0,0,0,0,0,0,0,0,0,0)';$S;BIDI;
    'MCA_PAR':'(0,0,BC55,0,0,0,0,0,0,0,0,0,0,0,0,0,0,0,0,0,0,0,0,0,0,0,0,0,0,0,0~
,0,0,0,0,0,0,0,0,0)';$S;OUT;
    'MCB_PAR':'(0,0,BL57,0,0,0,0,0,0,0,0,0,0,0,0,0,0,0,0,0,0,0,0,0,0,0,0,0,0,0,0~
,0,0,0,0,0,0,0,0,0)';$S;OUT;
    'MC0_CLK_H':'(0,0,BC57,0,0,0,0,0,0,0,0,0,0,0,0,0,0,0,0,0,0,0,0,0,0,0,0,0,0,0~
,0,0,0,0,0,0,0,0,0,0)';$S;OUT;
    'MC0_CLK_L':'(0,0,BD56,0,0,0,0,0,0,0,0,0,0,0,0,0,0,0,0,0,0,0,0,0,0,0,0,0,0,0~
,0,0,0,0,0,0,0,0,0,0)';$S;OUT;
    'MC1_CLK_H':'(0,0,BF56,0,0,0,0,0,0,0,0,0,0,0,0,0,0,0,0,0,0,0,0,0,0,0,0,0,0,0~
,0,0,0,0,0,0,0,0,0,0)';$S;OUT;
    'MC1_CLK_L':'(0,0,BG57,0,0,0,0,0,0,0,0,0,0,0,0,0,0,0,0,0,0,0,0,0,0,0,0,0,0,0~
,0,0,0,0,0,0,0,0,0,0)';$S;OUT;
    'TEST39C':'(0,0,BF55,0,0,0,0,0,0,0,0,0,0,0,0,0,0,0,0,0,0,0,0,0,0,0,0,0,0,0,0~
,0,0,0,0,0,0,0,0,0)';$S;OUT;
    'MD_ALERT_L':'(0,0,0,AT58,0,0,0,0,0,0,0,0,0,0,0,0,0,0,0,0,0,0,0,0,0,0,0,0,0,~
0,0,0,0,0,0,0,0,0,0,0)';$S;IN;
    'MD_RESET_L':'(0,0,0,AU59,0,0,0,0,0,0,0,0,0,0,0,0,0,0,0,0,0,0,0,0,0,0,0,0,0,~
0,0,0,0,0,0,0,0,0,0,0)';$S;OUT;
    'MDB_DATA23':'(0,0,0,CY58,0,0,0,0,0,0,0,0,0,0,0,0,0,0,0,0,0,0,0,0,0,0,0,0,0,~
0,0,0,0,0,0,0,0,0,0,0)';$S;BIDI;
    'MDB_DATA12':'(0,0,0,CM60,0,0,0,0,0,0,0,0,0,0,0,0,0,0,0,0,0,0,0,0,0,0,0,0,0,~
0,0,0,0,0,0,0,0,0,0,0)';$S;BIDI;
    'MDB_DATA2':'(0,0,0,CC60,0,0,0,0,0,0,0,0,0,0,0,0,0,0,0,0,0,0,0,0,0,0,0,0,0,0~
,0,0,0,0,0,0,0,0,0,0)';$S;BIDI;
    'MDB_CHECK3':'(0,0,0,CB58,0,0,0,0,0,0,0,0,0,0,0,0,0,0,0,0,0,0,0,0,0,0,0,0,0,~
0,0,0,0,0,0,0,0,0,0,0)';$S;BIDI;
    'MDA_DQS_L5':'(0,0,0,H58,0,0,0,0,0,0,0,0,0,0,0,0,0,0,0,0,0,0,0,0,0,0,0,0,0,0~
,0,0,0,0,0,0,0,0,0,0)';$S;BIDI;
    'MDA_DQS_H1':'(0,0,0,N60,0,0,0,0,0,0,0,0,0,0,0,0,0,0,0,0,0,0,0,0,0,0,0,0,0,0~
,0,0,0,0,0,0,0,0,0,0)';$S;BIDI;
    'MDA_DATA29':'(0,0,0,AH58,0,0,0,0,0,0,0,0,0,0,0,0,0,0,0,0,0,0,0,0,0,0,0,0,0,~
0,0,0,0,0,0,0,0,0,0,0)';$S;BIDI;
    'MDA_DATA18':'(0,0,0,V60,0,0,0,0,0,0,0,0,0,0,0,0,0,0,0,0,0,0,0,0,0,0,0,0,0,0~
,0,0,0,0,0,0,0,0,0,0)';$S;BIDI;
    'MDA_DATA3':'(0,0,0,G59,0,0,0,0,0,0,0,0,0,0,0,0,0,0,0,0,0,0,0,0,0,0,0,0,0,0,~
0,0,0,0,0,0,0,0,0,0)';$S;BIDI;
    'MDB_DQS_L0':'(0,0,0,CE60,0,0,0,0,0,0,0,0,0,0,0,0,0,0,0,0,0,0,0,0,0,0,0,0,0,~
0,0,0,0,0,0,0,0,0,0,0)';$S;BIDI;
    'MDB_DATA24':'(0,0,0,CY60,0,0,0,0,0,0,0,0,0,0,0,0,0,0,0,0,0,0,0,0,0,0,0,0,0,~
0,0,0,0,0,0,0,0,0,0,0)';$S;BIDI;
    'MDB_DATA13':'(0,0,0,CN59,0,0,0,0,0,0,0,0,0,0,0,0,0,0,0,0,0,0,0,0,0,0,0,0,0,~
0,0,0,0,0,0,0,0,0,0,0)';$S;BIDI;
    'MDB_DATA3':'(0,0,0,CD58,0,0,0,0,0,0,0,0,0,0,0,0,0,0,0,0,0,0,0,0,0,0,0,0,0,0~
,0,0,0,0,0,0,0,0,0,0)';$S;BIDI;
    'MDB_CHECK4':'(0,0,0,BT60,0,0,0,0,0,0,0,0,0,0,0,0,0,0,0,0,0,0,0,0,0,0,0,0,0,~
0,0,0,0,0,0,0,0,0,0,0)';$S;BIDI;
    'MDA_DQS_L6':'(0,0,0,P58,0,0,0,0,0,0,0,0,0,0,0,0,0,0,0,0,0,0,0,0,0,0,0,0,0,0~
,0,0,0,0,0,0,0,0,0,0)';$S;BIDI;
    'MDA_DQS_H2':'(0,0,0,W60,0,0,0,0,0,0,0,0,0,0,0,0,0,0,0,0,0,0,0,0,0,0,0,0,0,0~
,0,0,0,0,0,0,0,0,0,0)';$S;BIDI;
    'MDA_DATA19':'(0,0,0,W59,0,0,0,0,0,0,0,0,0,0,0,0,0,0,0,0,0,0,0,0,0,0,0,0,0,0~
,0,0,0,0,0,0,0,0,0,0)';$S;BIDI;
    'MDA_DATA4':'(0,0,0,J60,0,0,0,0,0,0,0,0,0,0,0,0,0,0,0,0,0,0,0,0,0,0,0,0,0,0,~
0,0,0,0,0,0,0,0,0,0)';$S;BIDI;
    'MDB_DQS_L1':'(0,0,0,CL60,0,0,0,0,0,0,0,0,0,0,0,0,0,0,0,0,0,0,0,0,0,0,0,0,0,~
0,0,0,0,0,0,0,0,0,0,0)';$S;BIDI;
    'MDB_DATA25':'(0,0,0,DA59,0,0,0,0,0,0,0,0,0,0,0,0,0,0,0,0,0,0,0,0,0,0,0,0,0,~
0,0,0,0,0,0,0,0,0,0,0)';$S;BIDI;
    'MDB_DATA14':'(0,0,0,CN60,0,0,0,0,0,0,0,0,0,0,0,0,0,0,0,0,0,0,0,0,0,0,0,0,0,~
0,0,0,0,0,0,0,0,0,0,0)';$S;BIDI;
    'MDB_DATA4':'(0,0,0,CF60,0,0,0,0,0,0,0,0,0,0,0,0,0,0,0,0,0,0,0,0,0,0,0,0,0,0~
,0,0,0,0,0,0,0,0,0,0)';$S;BIDI;
    'MDB_CHECK5':'(0,0,0,BU59,0,0,0,0,0,0,0,0,0,0,0,0,0,0,0,0,0,0,0,0,0,0,0,0,0,~
0,0,0,0,0,0,0,0,0,0,0)';$S;BIDI;
    'MDA_DQS_L7':'(0,0,0,Y58,0,0,0,0,0,0,0,0,0,0,0,0,0,0,0,0,0,0,0,0,0,0,0,0,0,0~
,0,0,0,0,0,0,0,0,0,0)';$S;BIDI;
    'MDA_DQS_H3':'(0,0,0,AE60,0,0,0,0,0,0,0,0,0,0,0,0,0,0,0,0,0,0,0,0,0,0,0,0,0,~
0,0,0,0,0,0,0,0,0,0,0)';$S;BIDI;
    'MDA_DATA5':'(0,0,0,K58,0,0,0,0,0,0,0,0,0,0,0,0,0,0,0,0,0,0,0,0,0,0,0,0,0,0,~
0,0,0,0,0,0,0,0,0,0)';$S;BIDI;
    'MDB_DQS_L2':'(0,0,0,CU60,0,0,0,0,0,0,0,0,0,0,0,0,0,0,0,0,0,0,0,0,0,0,0,0,0,~
0,0,0,0,0,0,0,0,0,0,0)';$S;BIDI;
    'MDB_DATA26':'(0,0,0,DA60,0,0,0,0,0,0,0,0,0,0,0,0,0,0,0,0,0,0,0,0,0,0,0,0,0,~
0,0,0,0,0,0,0,0,0,0,0)';$S;BIDI;
    'MDB_DATA15':'(0,0,0,CP58,0,0,0,0,0,0,0,0,0,0,0,0,0,0,0,0,0,0,0,0,0,0,0,0,0,~
0,0,0,0,0,0,0,0,0,0,0)';$S;BIDI;
    'MDB_DATA5':'(0,0,0,CG59,0,0,0,0,0,0,0,0,0,0,0,0,0,0,0,0,0,0,0,0,0,0,0,0,0,0~
,0,0,0,0,0,0,0,0,0,0)';$S;BIDI;
    'MDB_CHECK6':'(0,0,0,BU60,0,0,0,0,0,0,0,0,0,0,0,0,0,0,0,0,0,0,0,0,0,0,0,0,0,~
0,0,0,0,0,0,0,0,0,0,0)';$S;BIDI;
    'MDA_DQS_L8':'(0,0,0,AF58,0,0,0,0,0,0,0,0,0,0,0,0,0,0,0,0,0,0,0,0,0,0,0,0,0,~
0,0,0,0,0,0,0,0,0,0,0)';$S;BIDI;
    'MDA_DQS_H4':'(0,0,0,AL60,0,0,0,0,0,0,0,0,0,0,0,0,0,0,0,0,0,0,0,0,0,0,0,0,0,~
0,0,0,0,0,0,0,0,0,0,0)';$S;BIDI;
    'MDA_DATA6':'(0,0,0,K60,0,0,0,0,0,0,0,0,0,0,0,0,0,0,0,0,0,0,0,0,0,0,0,0,0,0,~
0,0,0,0,0,0,0,0,0,0)';$S;BIDI;
    'MDB_DQS_L3':'(0,0,0,DC60,0,0,0,0,0,0,0,0,0,0,0,0,0,0,0,0,0,0,0,0,0,0,0,0,0,~
0,0,0,0,0,0,0,0,0,0,0)';$S;BIDI;
    'MDB_DATA27':'(0,0,0,DB58,0,0,0,0,0,0,0,0,0,0,0,0,0,0,0,0,0,0,0,0,0,0,0,0,0,~
0,0,0,0,0,0,0,0,0,0,0)';$S;BIDI;
    'MDB_DATA16':'(0,0,0,CP60,0,0,0,0,0,0,0,0,0,0,0,0,0,0,0,0,0,0,0,0,0,0,0,0,0,~
0,0,0,0,0,0,0,0,0,0,0)';$S;BIDI;
    'MDB_DATA6':'(0,0,0,CG60,0,0,0,0,0,0,0,0,0,0,0,0,0,0,0,0,0,0,0,0,0,0,0,0,0,0~
,0,0,0,0,0,0,0,0,0,0)';$S;BIDI;
    'MDB_CHECK7':'(0,0,0,BV58,0,0,0,0,0,0,0,0,0,0,0,0,0,0,0,0,0,0,0,0,0,0,0,0,0,~
0,0,0,0,0,0,0,0,0,0,0)';$S;BIDI;
    'MDB0_RSP_L':'(0,0,0,BP60,0,0,0,0,0,0,0,0,0,0,0,0,0,0,0,0,0,0,0,0,0,0,0,0,0,~
0,0,0,0,0,0,0,0,0,0,0)';$S;IN;
    'MDA_DQS_L9':'(0,0,0,AM58,0,0,0,0,0,0,0,0,0,0,0,0,0,0,0,0,0,0,0,0,0,0,0,0,0,~
0,0,0,0,0,0,0,0,0,0,0)';$S;BIDI;
    'MDA_DQS_H5':'(0,0,0,J59,0,0,0,0,0,0,0,0,0,0,0,0,0,0,0,0,0,0,0,0,0,0,0,0,0,0~
,0,0,0,0,0,0,0,0,0,0)';$S;BIDI;
    'MDA_DATA7':'(0,0,0,L59,0,0,0,0,0,0,0,0,0,0,0,0,0,0,0,0,0,0,0,0,0,0,0,0,0,0,~
0,0,0,0,0,0,0,0,0,0)';$S;BIDI;
    'MDB_DQS_L4':'(0,0,0,BW59,0,0,0,0,0,0,0,0,0,0,0,0,0,0,0,0,0,0,0,0,0,0,0,0,0,~
0,0,0,0,0,0,0,0,0,0,0)';$S;BIDI;
    'MDB_DQS_H0':'(0,0,0,CD60,0,0,0,0,0,0,0,0,0,0,0,0,0,0,0,0,0,0,0,0,0,0,0,0,0,~
0,0,0,0,0,0,0,0,0,0,0)';$S;BIDI;
    'MDB_DATA28':'(0,0,0,DD60,0,0,0,0,0,0,0,0,0,0,0,0,0,0,0,0,0,0,0,0,0,0,0,0,0,~
0,0,0,0,0,0,0,0,0,0,0)';$S;BIDI;
    'MDB_DATA17':'(0,0,0,CR59,0,0,0,0,0,0,0,0,0,0,0,0,0,0,0,0,0,0,0,0,0,0,0,0,0,~
0,0,0,0,0,0,0,0,0,0,0)';$S;BIDI;
    'MDB_DATA7':'(0,0,0,CH58,0,0,0,0,0,0,0,0,0,0,0,0,0,0,0,0,0,0,0,0,0,0,0,0,0,0~
,0,0,0,0,0,0,0,0,0,0)';$S;BIDI;
    'MDB1_RSP_L':'(0,0,0,BR60,0,0,0,0,0,0,0,0,0,0,0,0,0,0,0,0,0,0,0,0,0,0,0,0,0,~
0,0,0,0,0,0,0,0,0,0,0)';$S;IN;
    'MDA_DQS_H6':'(0,0,0,R59,0,0,0,0,0,0,0,0,0,0,0,0,0,0,0,0,0,0,0,0,0,0,0,0,0,0~
,0,0,0,0,0,0,0,0,0,0)';$S;BIDI;
    'MDA_DATA8':'(0,0,0,L60,0,0,0,0,0,0,0,0,0,0,0,0,0,0,0,0,0,0,0,0,0,0,0,0,0,0,~
0,0,0,0,0,0,0,0,0,0)';$S;BIDI;
    'MDB_DQS_L5':'(0,0,0,CE59,0,0,0,0,0,0,0,0,0,0,0,0,0,0,0,0,0,0,0,0,0,0,0,0,0,~
0,0,0,0,0,0,0,0,0,0,0)';$S;BIDI;
    'MDB_DQS_H1':'(0,0,0,CK60,0,0,0,0,0,0,0,0,0,0,0,0,0,0,0,0,0,0,0,0,0,0,0,0,0,~
0,0,0,0,0,0,0,0,0,0,0)';$S;BIDI;
    'MDB_DATA29':'(0,0,0,DE59,0,0,0,0,0,0,0,0,0,0,0,0,0,0,0,0,0,0,0,0,0,0,0,0,0,~
0,0,0,0,0,0,0,0,0,0,0)';$S;BIDI;
    'MDB_DATA18':'(0,0,0,CR60,0,0,0,0,0,0,0,0,0,0,0,0,0,0,0,0,0,0,0,0,0,0,0,0,0,~
0,0,0,0,0,0,0,0,0,0,0)';$S;BIDI;
    'MDB_DATA8':'(0,0,0,CH60,0,0,0,0,0,0,0,0,0,0,0,0,0,0,0,0,0,0,0,0,0,0,0,0,0,0~
,0,0,0,0,0,0,0,0,0,0)';$S;BIDI;
    'MDA_DQS_H7':'(0,0,0,AA59,0,0,0,0,0,0,0,0,0,0,0,0,0,0,0,0,0,0,0,0,0,0,0,0,0,~
0,0,0,0,0,0,0,0,0,0,0)';$S;BIDI;
    'MDA_DATA9':'(0,0,0,M58,0,0,0,0,0,0,0,0,0,0,0,0,0,0,0,0,0,0,0,0,0,0,0,0,0,0,~
0,0,0,0,0,0,0,0,0,0)';$S;BIDI;
    'MDA_CA0':'(0,0,0,AW60,0,0,0,0,0,0,0,0,0,0,0,0,0,0,0,0,0,0,0,0,0,0,0,0,0,0,0~
,0,0,0,0,0,0,0,0,0)';$S;OUT;
    'MDA0_CS_L0':'(0,0,0,AV60,0,0,0,0,0,0,0,0,0,0,0,0,0,0,0,0,0,0,0,0,0,0,0,0,0,~
0,0,0,0,0,0,0,0,0,0,0)';$S;OUT;
    'MDB_DQS_L6':'(0,0,0,CL59,0,0,0,0,0,0,0,0,0,0,0,0,0,0,0,0,0,0,0,0,0,0,0,0,0,~
0,0,0,0,0,0,0,0,0,0,0)';$S;BIDI;
    'MDB_DQS_H2':'(0,0,0,CT60,0,0,0,0,0,0,0,0,0,0,0,0,0,0,0,0,0,0,0,0,0,0,0,0,0,~
0,0,0,0,0,0,0,0,0,0,0)';$S;BIDI;
    'MDB_DATA19':'(0,0,0,CT58,0,0,0,0,0,0,0,0,0,0,0,0,0,0,0,0,0,0,0,0,0,0,0,0,0,~
0,0,0,0,0,0,0,0,0,0,0)';$S;BIDI;
    'MDB_DATA9':'(0,0,0,CJ59,0,0,0,0,0,0,0,0,0,0,0,0,0,0,0,0,0,0,0,0,0,0,0,0,0,0~
,0,0,0,0,0,0,0,0,0,0)';$S;BIDI;
    'MDB_CA0':'(0,0,0,BG59,0,0,0,0,0,0,0,0,0,0,0,0,0,0,0,0,0,0,0,0,0,0,0,0,0,0,0~
,0,0,0,0,0,0,0,0,0)';$S;OUT;
    'MDA_DQS_H8':'(0,0,0,AG59,0,0,0,0,0,0,0,0,0,0,0,0,0,0,0,0,0,0,0,0,0,0,0,0,0,~
0,0,0,0,0,0,0,0,0,0,0)';$S;BIDI;
    'MDA_DATA30':'(0,0,0,AH60,0,0,0,0,0,0,0,0,0,0,0,0,0,0,0,0,0,0,0,0,0,0,0,0,0,~
0,0,0,0,0,0,0,0,0,0,0)';$S;BIDI;
    'MDA_CA1':'(0,0,0,AY60,0,0,0,0,0,0,0,0,0,0,0,0,0,0,0,0,0,0,0,0,0,0,0,0,0,0,0~
,0,0,0,0,0,0,0,0,0)';$S;OUT;
    'MDA1_CS_L0':'(0,0,0,AU60,0,0,0,0,0,0,0,0,0,0,0,0,0,0,0,0,0,0,0,0,0,0,0,0,0,~
0,0,0,0,0,0,0,0,0,0,0)';$S;OUT;
    'MDA0_CS_L1':'(0,0,0,AW59,0,0,0,0,0,0,0,0,0,0,0,0,0,0,0,0,0,0,0,0,0,0,0,0,0,~
0,0,0,0,0,0,0,0,0,0,0)';$S;OUT;
    'MDB_DQS_L7':'(0,0,0,CU59,0,0,0,0,0,0,0,0,0,0,0,0,0,0,0,0,0,0,0,0,0,0,0,0,0,~
0,0,0,0,0,0,0,0,0,0,0)';$S;BIDI;
    'MDB_DQS_H3':'(0,0,0,DB60,0,0,0,0,0,0,0,0,0,0,0,0,0,0,0,0,0,0,0,0,0,0,0,0,0,~
0,0,0,0,0,0,0,0,0,0,0)';$S;BIDI;
    'MDB_CA1':'(0,0,0,BH58,0,0,0,0,0,0,0,0,0,0,0,0,0,0,0,0,0,0,0,0,0,0,0,0,0,0,0~
,0,0,0,0,0,0,0,0,0)';$S;OUT;
    'MDA_DQS_H9':'(0,0,0,AN59,0,0,0,0,0,0,0,0,0,0,0,0,0,0,0,0,0,0,0,0,0,0,0,0,0,~
0,0,0,0,0,0,0,0,0,0,0)';$S;BIDI;
    'MDA_DATA31':'(0,0,0,AJ59,0,0,0,0,0,0,0,0,0,0,0,0,0,0,0,0,0,0,0,0,0,0,0,0,0,~
0,0,0,0,0,0,0,0,0,0,0)';$S;BIDI;
    'MDA_DATA20':'(0,0,0,AA60,0,0,0,0,0,0,0,0,0,0,0,0,0,0,0,0,0,0,0,0,0,0,0,0,0,~
0,0,0,0,0,0,0,0,0,0,0)';$S;BIDI;
    'MDA_CHECK0':'(0,0,0,AJ60,0,0,0,0,0,0,0,0,0,0,0,0,0,0,0,0,0,0,0,0,0,0,0,0,0,~
0,0,0,0,0,0,0,0,0,0,0)';$S;BIDI;
    'MDA_CA2':'(0,0,0,AY58,0,0,0,0,0,0,0,0,0,0,0,0,0,0,0,0,0,0,0,0,0,0,0,0,0,0,0~
,0,0,0,0,0,0,0,0,0)';$S;OUT;
    'MDA1_CS_L1':'(0,0,0,AV58,0,0,0,0,0,0,0,0,0,0,0,0,0,0,0,0,0,0,0,0,0,0,0,0,0,~
0,0,0,0,0,0,0,0,0,0,0)';$S;OUT;
    'MDB_DQS_L8':'(0,0,0,DC59,0,0,0,0,0,0,0,0,0,0,0,0,0,0,0,0,0,0,0,0,0,0,0,0,0,~
0,0,0,0,0,0,0,0,0,0,0)';$S;BIDI;
    'MDB_DQS_H4':'(0,0,0,BY58,0,0,0,0,0,0,0,0,0,0,0,0,0,0,0,0,0,0,0,0,0,0,0,0,0,~
0,0,0,0,0,0,0,0,0,0,0)';$S;BIDI;
    'MDB_CA2':'(0,0,0,BH60,0,0,0,0,0,0,0,0,0,0,0,0,0,0,0,0,0,0,0,0,0,0,0,0,0,0,0~
,0,0,0,0,0,0,0,0,0)';$S;OUT;
    'MDA_DATA21':'(0,0,0,AB58,0,0,0,0,0,0,0,0,0,0,0,0,0,0,0,0,0,0,0,0,0,0,0,0,0,~
0,0,0,0,0,0,0,0,0,0,0)';$S;BIDI;
    'MDA_DATA10':'(0,0,0,M60,0,0,0,0,0,0,0,0,0,0,0,0,0,0,0,0,0,0,0,0,0,0,0,0,0,0~
,0,0,0,0,0,0,0,0,0,0)';$S;BIDI;
    'MDA_CHECK1':'(0,0,0,AK58,0,0,0,0,0,0,0,0,0,0,0,0,0,0,0,0,0,0,0,0,0,0,0,0,0,~
0,0,0,0,0,0,0,0,0,0,0)';$S;BIDI;
    'MDA_CA3':'(0,0,0,BA59,0,0,0,0,0,0,0,0,0,0,0,0,0,0,0,0,0,0,0,0,0,0,0,0,0,0,0~
,0,0,0,0,0,0,0,0,0)';$S;OUT;
    'MDB_DQS_L9':'(0,0,0,BW60,0,0,0,0,0,0,0,0,0,0,0,0,0,0,0,0,0,0,0,0,0,0,0,0,0,~
0,0,0,0,0,0,0,0,0,0,0)';$S;BIDI;
    'MDB_DQS_H5':'(0,0,0,CF58,0,0,0,0,0,0,0,0,0,0,0,0,0,0,0,0,0,0,0,0,0,0,0,0,0,~
0,0,0,0,0,0,0,0,0,0,0)';$S;BIDI;
    'MDA_DATA22':'(0,0,0,AB60,0,0,0,0,0,0,0,0,0,0,0,0,0,0,0,0,0,0,0,0,0,0,0,0,0,~
0,0,0,0,0,0,0,0,0,0,0)';$S;BIDI;
    'MDA_DATA11':'(0,0,0,N59,0,0,0,0,0,0,0,0,0,0,0,0,0,0,0,0,0,0,0,0,0,0,0,0,0,0~
,0,0,0,0,0,0,0,0,0,0)';$S;BIDI;
    'MDA_CHECK2':'(0,0,0,AK60,0,0,0,0,0,0,0,0,0,0,0,0,0,0,0,0,0,0,0,0,0,0,0,0,0,~
0,0,0,0,0,0,0,0,0,0,0)';$S;BIDI;
    'MDA_CA4':'(0,0,0,BA60,0,0,0,0,0,0,0,0,0,0,0,0,0,0,0,0,0,0,0,0,0,0,0,0,0,0,0~
,0,0,0,0,0,0,0,0,0)';$S;OUT;
    'MDB_DQS_H6':'(0,0,0,CM58,0,0,0,0,0,0,0,0,0,0,0,0,0,0,0,0,0,0,0,0,0,0,0,0,0,~
0,0,0,0,0,0,0,0,0,0,0)';$S;BIDI;
    'MDB_CA4':'(0,0,0,BJ59,0,0,0,0,0,0,0,0,0,0,0,0,0,0,0,0,0,0,0,0,0,0,0,0,0,0,0~
,0,0,0,0,0,0,0,0,0)';$S;OUT;
    'MDA_DATA23':'(0,0,0,AC59,0,0,0,0,0,0,0,0,0,0,0,0,0,0,0,0,0,0,0,0,0,0,0,0,0,~
0,0,0,0,0,0,0,0,0,0,0)';$S;BIDI;
    'MDA_DATA12':'(0,0,0,R60,0,0,0,0,0,0,0,0,0,0,0,0,0,0,0,0,0,0,0,0,0,0,0,0,0,0~
,0,0,0,0,0,0,0,0,0,0)';$S;BIDI;
    'MDA_CHECK3':'(0,0,0,AL59,0,0,0,0,0,0,0,0,0,0,0,0,0,0,0,0,0,0,0,0,0,0,0,0,0,~
0,0,0,0,0,0,0,0,0,0,0)';$S;BIDI;
    'MDA_CA5':'(0,0,0,BB60,0,0,0,0,0,0,0,0,0,0,0,0,0,0,0,0,0,0,0,0,0,0,0,0,0,0,0~
,0,0,0,0,0,0,0,0,0)';$S;OUT;
    'MDB_DQS_H7':'(0,0,0,CV58,0,0,0,0,0,0,0,0,0,0,0,0,0,0,0,0,0,0,0,0,0,0,0,0,0,~
0,0,0,0,0,0,0,0,0,0,0)';$S;BIDI;
    'MDB_CA5':'(0,0,0,BK58,0,0,0,0,0,0,0,0,0,0,0,0,0,0,0,0,0,0,0,0,0,0,0,0,0,0,0~
,0,0,0,0,0,0,0,0,0)';$S;OUT;
    'MDB0_CS_L0':'(0,0,0,BM58,0,0,0,0,0,0,0,0,0,0,0,0,0,0,0,0,0,0,0,0,0,0,0,0,0,~
0,0,0,0,0,0,0,0,0,0,0)';$S;OUT;
    'MDA_DQS_L0':'(0,0,0,H60,0,0,0,0,0,0,0,0,0,0,0,0,0,0,0,0,0,0,0,0,0,0,0,0,0,0~
,0,0,0,0,0,0,0,0,0,0)';$S;BIDI;
    'MDA_DATA24':'(0,0,0,AC60,0,0,0,0,0,0,0,0,0,0,0,0,0,0,0,0,0,0,0,0,0,0,0,0,0,~
0,0,0,0,0,0,0,0,0,0,0)';$S;BIDI;
    'MDA_DATA13':'(0,0,0,T58,0,0,0,0,0,0,0,0,0,0,0,0,0,0,0,0,0,0,0,0,0,0,0,0,0,0~
,0,0,0,0,0,0,0,0,0,0)';$S;BIDI;
    'MDA_CHECK4':'(0,0,0,AN60,0,0,0,0,0,0,0,0,0,0,0,0,0,0,0,0,0,0,0,0,0,0,0,0,0,~
0,0,0,0,0,0,0,0,0,0,0)';$S;BIDI;
    'MDA_CA6':'(0,0,0,BB58,0,0,0,0,0,0,0,0,0,0,0,0,0,0,0,0,0,0,0,0,0,0,0,0,0,0,0~
,0,0,0,0,0,0,0,0,0)';$S;OUT;
    'MDB_DQS_H8':'(0,0,0,DD58,0,0,0,0,0,0,0,0,0,0,0,0,0,0,0,0,0,0,0,0,0,0,0,0,0,~
0,0,0,0,0,0,0,0,0,0,0)';$S;BIDI;
    'MDB_DATA30':'(0,0,0,DE60,0,0,0,0,0,0,0,0,0,0,0,0,0,0,0,0,0,0,0,0,0,0,0,0,0,~
0,0,0,0,0,0,0,0,0,0,0)';$S;BIDI;
    'MDB_CA6':'(0,0,0,BK60,0,0,0,0,0,0,0,0,0,0,0,0,0,0,0,0,0,0,0,0,0,0,0,0,0,0,0~
,0,0,0,0,0,0,0,0,0)';$S;OUT;
    'MDB1_CS_L0':'(0,0,0,BL59,0,0,0,0,0,0,0,0,0,0,0,0,0,0,0,0,0,0,0,0,0,0,0,0,0,~
0,0,0,0,0,0,0,0,0,0,0)';$S;OUT;
    'MDB0_CS_L1':'(0,0,0,BN60,0,0,0,0,0,0,0,0,0,0,0,0,0,0,0,0,0,0,0,0,0,0,0,0,0,~
0,0,0,0,0,0,0,0,0,0,0)';$S;OUT;
    'MDA_DQS_L1':'(0,0,0,P60,0,0,0,0,0,0,0,0,0,0,0,0,0,0,0,0,0,0,0,0,0,0,0,0,0,0~
,0,0,0,0,0,0,0,0,0,0)';$S;BIDI;
    'MDA_DATA25':'(0,0,0,AD58,0,0,0,0,0,0,0,0,0,0,0,0,0,0,0,0,0,0,0,0,0,0,0,0,0,~
0,0,0,0,0,0,0,0,0,0,0)';$S;BIDI;
    'MDA_DATA14':'(0,0,0,T60,0,0,0,0,0,0,0,0,0,0,0,0,0,0,0,0,0,0,0,0,0,0,0,0,0,0~
,0,0,0,0,0,0,0,0,0,0)';$S;BIDI;
    'MDA_CHECK5':'(0,0,0,AP58,0,0,0,0,0,0,0,0,0,0,0,0,0,0,0,0,0,0,0,0,0,0,0,0,0,~
0,0,0,0,0,0,0,0,0,0,0)';$S;BIDI;
    'MDB_DATA31':'(0,0,0,DF60,0,0,0,0,0,0,0,0,0,0,0,0,0,0,0,0,0,0,0,0,0,0,0,0,0,~
0,0,0,0,0,0,0,0,0,0,0)';$S;BIDI;
    'MDB_DATA20':'(0,0,0,CV60,0,0,0,0,0,0,0,0,0,0,0,0,0,0,0,0,0,0,0,0,0,0,0,0,0,~
0,0,0,0,0,0,0,0,0,0,0)';$S;BIDI;
    'MDB_CHECK0':'(0,0,0,BY60,0,0,0,0,0,0,0,0,0,0,0,0,0,0,0,0,0,0,0,0,0,0,0,0,0,~
0,0,0,0,0,0,0,0,0,0,0)';$S;BIDI;
    'MDB1_CS_L1':'(0,0,0,BM60,0,0,0,0,0,0,0,0,0,0,0,0,0,0,0,0,0,0,0,0,0,0,0,0,0,~
0,0,0,0,0,0,0,0,0,0,0)';$S;OUT;
    'MDA_DQS_L2':'(0,0,0,Y60,0,0,0,0,0,0,0,0,0,0,0,0,0,0,0,0,0,0,0,0,0,0,0,0,0,0~
,0,0,0,0,0,0,0,0,0,0)';$S;BIDI;
    'MDA_DATA26':'(0,0,0,AD60,0,0,0,0,0,0,0,0,0,0,0,0,0,0,0,0,0,0,0,0,0,0,0,0,0,~
0,0,0,0,0,0,0,0,0,0,0)';$S;BIDI;
    'MDA_DATA15':'(0,0,0,U59,0,0,0,0,0,0,0,0,0,0,0,0,0,0,0,0,0,0,0,0,0,0,0,0,0,0~
,0,0,0,0,0,0,0,0,0,0)';$S;BIDI;
    'MDA_DATA0':'(0,0,0,E60,0,0,0,0,0,0,0,0,0,0,0,0,0,0,0,0,0,0,0,0,0,0,0,0,0,0,~
0,0,0,0,0,0,0,0,0,0)';$S;BIDI;
    'MDA_CHECK6':'(0,0,0,AP60,0,0,0,0,0,0,0,0,0,0,0,0,0,0,0,0,0,0,0,0,0,0,0,0,0,~
0,0,0,0,0,0,0,0,0,0,0)';$S;BIDI;
    'MDB_DATA21':'(0,0,0,CW59,0,0,0,0,0,0,0,0,0,0,0,0,0,0,0,0,0,0,0,0,0,0,0,0,0,~
0,0,0,0,0,0,0,0,0,0,0)';$S;BIDI;
    'MDB_DATA10':'(0,0,0,CJ60,0,0,0,0,0,0,0,0,0,0,0,0,0,0,0,0,0,0,0,0,0,0,0,0,0,~
0,0,0,0,0,0,0,0,0,0,0)';$S;BIDI;
    'MDB_DATA0':'(0,0,0,CB60,0,0,0,0,0,0,0,0,0,0,0,0,0,0,0,0,0,0,0,0,0,0,0,0,0,0~
,0,0,0,0,0,0,0,0,0,0)';$S;BIDI;
    'MDB_CHECK1':'(0,0,0,CA59,0,0,0,0,0,0,0,0,0,0,0,0,0,0,0,0,0,0,0,0,0,0,0,0,0,~
0,0,0,0,0,0,0,0,0,0,0)';$S;BIDI;
    'MDA_DQS_L3':'(0,0,0,AF60,0,0,0,0,0,0,0,0,0,0,0,0,0,0,0,0,0,0,0,0,0,0,0,0,0,~
0,0,0,0,0,0,0,0,0,0,0)';$S;BIDI;
    'MDA_DATA27':'(0,0,0,AE59,0,0,0,0,0,0,0,0,0,0,0,0,0,0,0,0,0,0,0,0,0,0,0,0,0,~
0,0,0,0,0,0,0,0,0,0,0)';$S;BIDI;
    'MDA_DATA16':'(0,0,0,U60,0,0,0,0,0,0,0,0,0,0,0,0,0,0,0,0,0,0,0,0,0,0,0,0,0,0~
,0,0,0,0,0,0,0,0,0,0)';$S;BIDI;
    'MDA_DATA1':'(0,0,0,F58,0,0,0,0,0,0,0,0,0,0,0,0,0,0,0,0,0,0,0,0,0,0,0,0,0,0,~
0,0,0,0,0,0,0,0,0,0)';$S;BIDI;
    'MDA_CHECK7':'(0,0,0,AR59,0,0,0,0,0,0,0,0,0,0,0,0,0,0,0,0,0,0,0,0,0,0,0,0,0,~
0,0,0,0,0,0,0,0,0,0,0)';$S;BIDI;
    'MDA0_RSP_L':'(0,0,0,BN59,0,0,0,0,0,0,0,0,0,0,0,0,0,0,0,0,0,0,0,0,0,0,0,0,0,~
0,0,0,0,0,0,0,0,0,0,0)';$S;IN;
    'MDB_DATA22':'(0,0,0,CW60,0,0,0,0,0,0,0,0,0,0,0,0,0,0,0,0,0,0,0,0,0,0,0,0,0,~
0,0,0,0,0,0,0,0,0,0,0)';$S;BIDI;
    'MDB_DATA11':'(0,0,0,CK58,0,0,0,0,0,0,0,0,0,0,0,0,0,0,0,0,0,0,0,0,0,0,0,0,0,~
0,0,0,0,0,0,0,0,0,0,0)';$S;BIDI;
    'MDB_DATA1':'(0,0,0,CC59,0,0,0,0,0,0,0,0,0,0,0,0,0,0,0,0,0,0,0,0,0,0,0,0,0,0~
,0,0,0,0,0,0,0,0,0,0)';$S;BIDI;
    'MDB_CHECK2':'(0,0,0,CA60,0,0,0,0,0,0,0,0,0,0,0,0,0,0,0,0,0,0,0,0,0,0,0,0,0,~
0,0,0,0,0,0,0,0,0,0,0)';$S;BIDI;
    'MDA_DQS_L4':'(0,0,0,AM60,0,0,0,0,0,0,0,0,0,0,0,0,0,0,0,0,0,0,0,0,0,0,0,0,0,~
0,0,0,0,0,0,0,0,0,0,0)';$S;BIDI;
    'MDA_DQS_H0':'(0,0,0,G60,0,0,0,0,0,0,0,0,0,0,0,0,0,0,0,0,0,0,0,0,0,0,0,0,0,0~
,0,0,0,0,0,0,0,0,0,0)';$S;BIDI;
    'MDA_DATA28':'(0,0,0,AG60,0,0,0,0,0,0,0,0,0,0,0,0,0,0,0,0,0,0,0,0,0,0,0,0,0,~
0,0,0,0,0,0,0,0,0,0,0)';$S;BIDI;
    'MDA_DATA17':'(0,0,0,V58,0,0,0,0,0,0,0,0,0,0,0,0,0,0,0,0,0,0,0,0,0,0,0,0,0,0~
,0,0,0,0,0,0,0,0,0,0)';$S;BIDI;
    'MDA_DATA2':'(0,0,0,F60,0,0,0,0,0,0,0,0,0,0,0,0,0,0,0,0,0,0,0,0,0,0,0,0,0,0,~
0,0,0,0,0,0,0,0,0,0)';$S;BIDI;
    'MDA1_RSP_L':'(0,0,0,BP58,0,0,0,0,0,0,0,0,0,0,0,0,0,0,0,0,0,0,0,0,0,0,0,0,0,~
0,0,0,0,0,0,0,0,0,0,0)';$S;IN;
    'MDA_PAR':'(0,0,0,BC59,0,0,0,0,0,0,0,0,0,0,0,0,0,0,0,0,0,0,0,0,0,0,0,0,0,0,0~
,0,0,0,0,0,0,0,0,0)';$S;OUT;
    'MDB_PAR':'(0,0,0,BL60,0,0,0,0,0,0,0,0,0,0,0,0,0,0,0,0,0,0,0,0,0,0,0,0,0,0,0~
,0,0,0,0,0,0,0,0,0)';$S;OUT;
    'MDB_CA3':'(0,0,0,BJ60,0,0,0,0,0,0,0,0,0,0,0,0,0,0,0,0,0,0,0,0,0,0,0,0,0,0,0~
,0,0,0,0,0,0,0,0,0)';$S;OUT;
    'MDB_DQS_H9':'(0,0,0,BV60,0,0,0,0,0,0,0,0,0,0,0,0,0,0,0,0,0,0,0,0,0,0,0,0,0,~
0,0,0,0,0,0,0,0,0,0,0)';$S;BIDI;
    'MD0_CLK_H':'(0,0,0,BC60,0,0,0,0,0,0,0,0,0,0,0,0,0,0,0,0,0,0,0,0,0,0,0,0,0,0~
,0,0,0,0,0,0,0,0,0,0)';$S;OUT;
    'MD0_CLK_L':'(0,0,0,BD60,0,0,0,0,0,0,0,0,0,0,0,0,0,0,0,0,0,0,0,0,0,0,0,0,0,0~
,0,0,0,0,0,0,0,0,0,0)';$S;OUT;
    'MD1_CLK_H':'(0,0,0,BF60,0,0,0,0,0,0,0,0,0,0,0,0,0,0,0,0,0,0,0,0,0,0,0,0,0,0~
,0,0,0,0,0,0,0,0,0,0)';$S;OUT;
    'MD1_CLK_L':'(0,0,0,BG60,0,0,0,0,0,0,0,0,0,0,0,0,0,0,0,0,0,0,0,0,0,0,0,0,0,0~
,0,0,0,0,0,0,0,0,0,0)';$S;OUT;
    'TEST39D':'(0,0,0,BF58,0,0,0,0,0,0,0,0,0,0,0,0,0,0,0,0,0,0,0,0,0,0,0,0,0,0,0~
,0,0,0,0,0,0,0,0,0)';$S;OUT;
    'ME_ALERT_L':'(0,0,0,0,AT69,0,0,0,0,0,0,0,0,0,0,0,0,0,0,0,0,0,0,0,0,0,0,0,0,~
0,0,0,0,0,0,0,0,0,0,0)';$S;IN;
    'ME_RESET_L':'(0,0,0,0,AU69,0,0,0,0,0,0,0,0,0,0,0,0,0,0,0,0,0,0,0,0,0,0,0,0,~
0,0,0,0,0,0,0,0,0,0,0)';$S;OUT;
    'MEB_DQS_L2':'(0,0,0,0,CU71,0,0,0,0,0,0,0,0,0,0,0,0,0,0,0,0,0,0,0,0,0,0,0,0,~
0,0,0,0,0,0,0,0,0,0,0)';$S;BIDI;
    'MEB_DATA26':'(0,0,0,0,DA71,0,0,0,0,0,0,0,0,0,0,0,0,0,0,0,0,0,0,0,0,0,0,0,0,~
0,0,0,0,0,0,0,0,0,0,0)';$S;BIDI;
    'MEB_DATA15':'(0,0,0,0,CP69,0,0,0,0,0,0,0,0,0,0,0,0,0,0,0,0,0,0,0,0,0,0,0,0,~
0,0,0,0,0,0,0,0,0,0,0)';$S;BIDI;
    'MEB_CHECK6':'(0,0,0,0,BU71,0,0,0,0,0,0,0,0,0,0,0,0,0,0,0,0,0,0,0,0,0,0,0,0,~
0,0,0,0,0,0,0,0,0,0,0)';$S;BIDI;
    'MEA_DQS_L8':'(0,0,0,0,AF69,0,0,0,0,0,0,0,0,0,0,0,0,0,0,0,0,0,0,0,0,0,0,0,0,~
0,0,0,0,0,0,0,0,0,0,0)';$S;BIDI;
    'MEA_DQS_H4':'(0,0,0,0,AL71,0,0,0,0,0,0,0,0,0,0,0,0,0,0,0,0,0,0,0,0,0,0,0,0,~
0,0,0,0,0,0,0,0,0,0,0)';$S;BIDI;
    'MEB_DQS_L3':'(0,0,0,0,DC71,0,0,0,0,0,0,0,0,0,0,0,0,0,0,0,0,0,0,0,0,0,0,0,0,~
0,0,0,0,0,0,0,0,0,0,0)';$S;BIDI;
    'MEB_DATA27':'(0,0,0,0,DB69,0,0,0,0,0,0,0,0,0,0,0,0,0,0,0,0,0,0,0,0,0,0,0,0,~
0,0,0,0,0,0,0,0,0,0,0)';$S;BIDI;
    'MEB_DATA16':'(0,0,0,0,CP70,0,0,0,0,0,0,0,0,0,0,0,0,0,0,0,0,0,0,0,0,0,0,0,0,~
0,0,0,0,0,0,0,0,0,0,0)';$S;BIDI;
    'MEB_CHECK7':'(0,0,0,0,BV69,0,0,0,0,0,0,0,0,0,0,0,0,0,0,0,0,0,0,0,0,0,0,0,0,~
0,0,0,0,0,0,0,0,0,0,0)';$S;BIDI;
    'MEB1_RSP_L':'(0,0,0,0,BR71,0,0,0,0,0,0,0,0,0,0,0,0,0,0,0,0,0,0,0,0,0,0,0,0,~
0,0,0,0,0,0,0,0,0,0,0)';$S;IN;
    'MEB0_RSP_L':'(0,0,0,0,BP70,0,0,0,0,0,0,0,0,0,0,0,0,0,0,0,0,0,0,0,0,0,0,0,0,~
0,0,0,0,0,0,0,0,0,0,0)';$S;IN;
    'MEA_DQS_L9':'(0,0,0,0,AM69,0,0,0,0,0,0,0,0,0,0,0,0,0,0,0,0,0,0,0,0,0,0,0,0,~
0,0,0,0,0,0,0,0,0,0,0)';$S;BIDI;
    'MEA_DQS_H5':'(0,0,0,0,J69,0,0,0,0,0,0,0,0,0,0,0,0,0,0,0,0,0,0,0,0,0,0,0,0,0~
,0,0,0,0,0,0,0,0,0,0)';$S;BIDI;
    'MEB_DQS_L4':'(0,0,0,0,BW69,0,0,0,0,0,0,0,0,0,0,0,0,0,0,0,0,0,0,0,0,0,0,0,0,~
0,0,0,0,0,0,0,0,0,0,0)';$S;BIDI;
    'MEB_DQS_H0':'(0,0,0,0,CD70,0,0,0,0,0,0,0,0,0,0,0,0,0,0,0,0,0,0,0,0,0,0,0,0,~
0,0,0,0,0,0,0,0,0,0,0)';$S;BIDI;
    'MEB_DATA28':'(0,0,0,0,DD70,0,0,0,0,0,0,0,0,0,0,0,0,0,0,0,0,0,0,0,0,0,0,0,0,~
0,0,0,0,0,0,0,0,0,0,0)';$S;BIDI;
    'MEB_DATA17':'(0,0,0,0,CR69,0,0,0,0,0,0,0,0,0,0,0,0,0,0,0,0,0,0,0,0,0,0,0,0,~
0,0,0,0,0,0,0,0,0,0,0)';$S;BIDI;
    'MEA_DQS_H6':'(0,0,0,0,R69,0,0,0,0,0,0,0,0,0,0,0,0,0,0,0,0,0,0,0,0,0,0,0,0,0~
,0,0,0,0,0,0,0,0,0,0)';$S;BIDI;
    'MEB_DQS_L5':'(0,0,0,0,CE69,0,0,0,0,0,0,0,0,0,0,0,0,0,0,0,0,0,0,0,0,0,0,0,0,~
0,0,0,0,0,0,0,0,0,0,0)';$S;BIDI;
    'MEB_DQS_H1':'(0,0,0,0,CK70,0,0,0,0,0,0,0,0,0,0,0,0,0,0,0,0,0,0,0,0,0,0,0,0,~
0,0,0,0,0,0,0,0,0,0,0)';$S;BIDI;
    'MEB_DATA29':'(0,0,0,0,DE69,0,0,0,0,0,0,0,0,0,0,0,0,0,0,0,0,0,0,0,0,0,0,0,0,~
0,0,0,0,0,0,0,0,0,0,0)';$S;BIDI;
    'MEB_DATA18':'(0,0,0,0,CR71,0,0,0,0,0,0,0,0,0,0,0,0,0,0,0,0,0,0,0,0,0,0,0,0,~
0,0,0,0,0,0,0,0,0,0,0)';$S;BIDI;
    'MEA_DQS_H7':'(0,0,0,0,AA69,0,0,0,0,0,0,0,0,0,0,0,0,0,0,0,0,0,0,0,0,0,0,0,0,~
0,0,0,0,0,0,0,0,0,0,0)';$S;BIDI;
    'MEA_DATA0':'(0,0,0,0,E71,0,0,0,0,0,0,0,0,0,0,0,0,0,0,0,0,0,0,0,0,0,0,0,0,0,~
0,0,0,0,0,0,0,0,0,0)';$S;BIDI;
    'MEA1_CS_L0':'(0,0,0,0,AU71,0,0,0,0,0,0,0,0,0,0,0,0,0,0,0,0,0,0,0,0,0,0,0,0,~
0,0,0,0,0,0,0,0,0,0,0)';$S;OUT;
    'MEA0_CS_L0':'(0,0,0,0,AV70,0,0,0,0,0,0,0,0,0,0,0,0,0,0,0,0,0,0,0,0,0,0,0,0,~
0,0,0,0,0,0,0,0,0,0,0)';$S;OUT;
    'MEB_DQS_L6':'(0,0,0,0,CL69,0,0,0,0,0,0,0,0,0,0,0,0,0,0,0,0,0,0,0,0,0,0,0,0,~
0,0,0,0,0,0,0,0,0,0,0)';$S;BIDI;
    'MEB_DQS_H2':'(0,0,0,0,CT70,0,0,0,0,0,0,0,0,0,0,0,0,0,0,0,0,0,0,0,0,0,0,0,0,~
0,0,0,0,0,0,0,0,0,0,0)';$S;BIDI;
    'MEB_DATA19':'(0,0,0,0,CT69,0,0,0,0,0,0,0,0,0,0,0,0,0,0,0,0,0,0,0,0,0,0,0,0,~
0,0,0,0,0,0,0,0,0,0,0)';$S;BIDI;
    'MEB_DATA0':'(0,0,0,0,CB70,0,0,0,0,0,0,0,0,0,0,0,0,0,0,0,0,0,0,0,0,0,0,0,0,0~
,0,0,0,0,0,0,0,0,0,0)';$S;BIDI;
    'MEA_DQS_H8':'(0,0,0,0,AG69,0,0,0,0,0,0,0,0,0,0,0,0,0,0,0,0,0,0,0,0,0,0,0,0,~
0,0,0,0,0,0,0,0,0,0,0)';$S;BIDI;
    'MEA_DATA30':'(0,0,0,0,AH70,0,0,0,0,0,0,0,0,0,0,0,0,0,0,0,0,0,0,0,0,0,0,0,0,~
0,0,0,0,0,0,0,0,0,0,0)';$S;BIDI;
    'MEA_DATA1':'(0,0,0,0,F69,0,0,0,0,0,0,0,0,0,0,0,0,0,0,0,0,0,0,0,0,0,0,0,0,0,~
0,0,0,0,0,0,0,0,0,0)';$S;BIDI;
    'MEA1_CS_L1':'(0,0,0,0,AV69,0,0,0,0,0,0,0,0,0,0,0,0,0,0,0,0,0,0,0,0,0,0,0,0,~
0,0,0,0,0,0,0,0,0,0,0)';$S;OUT;
    'MEA0_CS_L1':'(0,0,0,0,AW69,0,0,0,0,0,0,0,0,0,0,0,0,0,0,0,0,0,0,0,0,0,0,0,0,~
0,0,0,0,0,0,0,0,0,0,0)';$S;OUT;
    'MEB_DQS_L7':'(0,0,0,0,CU69,0,0,0,0,0,0,0,0,0,0,0,0,0,0,0,0,0,0,0,0,0,0,0,0,~
0,0,0,0,0,0,0,0,0,0,0)';$S;BIDI;
    'MEB_DQS_H3':'(0,0,0,0,DB70,0,0,0,0,0,0,0,0,0,0,0,0,0,0,0,0,0,0,0,0,0,0,0,0,~
0,0,0,0,0,0,0,0,0,0,0)';$S;BIDI;
    'MEB_DATA1':'(0,0,0,0,CC69,0,0,0,0,0,0,0,0,0,0,0,0,0,0,0,0,0,0,0,0,0,0,0,0,0~
,0,0,0,0,0,0,0,0,0,0)';$S;BIDI;
    'MEA_DQS_H9':'(0,0,0,0,AN69,0,0,0,0,0,0,0,0,0,0,0,0,0,0,0,0,0,0,0,0,0,0,0,0,~
0,0,0,0,0,0,0,0,0,0,0)';$S;BIDI;
    'MEA_DATA31':'(0,0,0,0,AJ69,0,0,0,0,0,0,0,0,0,0,0,0,0,0,0,0,0,0,0,0,0,0,0,0,~
0,0,0,0,0,0,0,0,0,0,0)';$S;BIDI;
    'MEA_DATA20':'(0,0,0,0,AA71,0,0,0,0,0,0,0,0,0,0,0,0,0,0,0,0,0,0,0,0,0,0,0,0,~
0,0,0,0,0,0,0,0,0,0,0)';$S;BIDI;
    'MEA_DATA2':'(0,0,0,0,F70,0,0,0,0,0,0,0,0,0,0,0,0,0,0,0,0,0,0,0,0,0,0,0,0,0,~
0,0,0,0,0,0,0,0,0,0)';$S;BIDI;
    'MEA_CHECK0':'(0,0,0,0,AJ71,0,0,0,0,0,0,0,0,0,0,0,0,0,0,0,0,0,0,0,0,0,0,0,0,~
0,0,0,0,0,0,0,0,0,0,0)';$S;BIDI;
    'MEA_CA0':'(0,0,0,0,AW71,0,0,0,0,0,0,0,0,0,0,0,0,0,0,0,0,0,0,0,0,0,0,0,0,0,0~
,0,0,0,0,0,0,0,0,0)';$S;OUT;
    'MEB_DQS_L8':'(0,0,0,0,DC69,0,0,0,0,0,0,0,0,0,0,0,0,0,0,0,0,0,0,0,0,0,0,0,0,~
0,0,0,0,0,0,0,0,0,0,0)';$S;BIDI;
    'MEB_DQS_H4':'(0,0,0,0,BY69,0,0,0,0,0,0,0,0,0,0,0,0,0,0,0,0,0,0,0,0,0,0,0,0,~
0,0,0,0,0,0,0,0,0,0,0)';$S;BIDI;
    'MEB_DATA2':'(0,0,0,0,CC71,0,0,0,0,0,0,0,0,0,0,0,0,0,0,0,0,0,0,0,0,0,0,0,0,0~
,0,0,0,0,0,0,0,0,0,0)';$S;BIDI;
    'MEB_CA0':'(0,0,0,0,BG69,0,0,0,0,0,0,0,0,0,0,0,0,0,0,0,0,0,0,0,0,0,0,0,0,0,0~
,0,0,0,0,0,0,0,0,0)';$S;OUT;
    'MEA_DATA21':'(0,0,0,0,AB69,0,0,0,0,0,0,0,0,0,0,0,0,0,0,0,0,0,0,0,0,0,0,0,0,~
0,0,0,0,0,0,0,0,0,0,0)';$S;BIDI;
    'MEA_DATA10':'(0,0,0,0,M70,0,0,0,0,0,0,0,0,0,0,0,0,0,0,0,0,0,0,0,0,0,0,0,0,0~
,0,0,0,0,0,0,0,0,0,0)';$S;BIDI;
    'MEA_DATA3':'(0,0,0,0,G69,0,0,0,0,0,0,0,0,0,0,0,0,0,0,0,0,0,0,0,0,0,0,0,0,0,~
0,0,0,0,0,0,0,0,0,0)';$S;BIDI;
    'MEA_CHECK1':'(0,0,0,0,AK69,0,0,0,0,0,0,0,0,0,0,0,0,0,0,0,0,0,0,0,0,0,0,0,0,~
0,0,0,0,0,0,0,0,0,0,0)';$S;BIDI;
    'MEA_CA1':'(0,0,0,0,AY70,0,0,0,0,0,0,0,0,0,0,0,0,0,0,0,0,0,0,0,0,0,0,0,0,0,0~
,0,0,0,0,0,0,0,0,0)';$S;OUT;
    'MEB_DQS_L9':'(0,0,0,0,BW71,0,0,0,0,0,0,0,0,0,0,0,0,0,0,0,0,0,0,0,0,0,0,0,0,~
0,0,0,0,0,0,0,0,0,0,0)';$S;BIDI;
    'MEB_DQS_H5':'(0,0,0,0,CF69,0,0,0,0,0,0,0,0,0,0,0,0,0,0,0,0,0,0,0,0,0,0,0,0,~
0,0,0,0,0,0,0,0,0,0,0)';$S;BIDI;
    'MEB_DATA3':'(0,0,0,0,CD69,0,0,0,0,0,0,0,0,0,0,0,0,0,0,0,0,0,0,0,0,0,0,0,0,0~
,0,0,0,0,0,0,0,0,0,0)';$S;BIDI;
    'MEB_CA1':'(0,0,0,0,BH69,0,0,0,0,0,0,0,0,0,0,0,0,0,0,0,0,0,0,0,0,0,0,0,0,0,0~
,0,0,0,0,0,0,0,0,0)';$S;OUT;
    'MEA_DATA22':'(0,0,0,0,AB70,0,0,0,0,0,0,0,0,0,0,0,0,0,0,0,0,0,0,0,0,0,0,0,0,~
0,0,0,0,0,0,0,0,0,0,0)';$S;BIDI;
    'MEA_DATA11':'(0,0,0,0,N69,0,0,0,0,0,0,0,0,0,0,0,0,0,0,0,0,0,0,0,0,0,0,0,0,0~
,0,0,0,0,0,0,0,0,0,0)';$S;BIDI;
    'MEA_DATA4':'(0,0,0,0,J71,0,0,0,0,0,0,0,0,0,0,0,0,0,0,0,0,0,0,0,0,0,0,0,0,0,~
0,0,0,0,0,0,0,0,0,0)';$S;BIDI;
    'MEA_CHECK2':'(0,0,0,0,AK70,0,0,0,0,0,0,0,0,0,0,0,0,0,0,0,0,0,0,0,0,0,0,0,0,~
0,0,0,0,0,0,0,0,0,0,0)';$S;BIDI;
    'MEA_CA2':'(0,0,0,0,AY69,0,0,0,0,0,0,0,0,0,0,0,0,0,0,0,0,0,0,0,0,0,0,0,0,0,0~
,0,0,0,0,0,0,0,0,0)';$S;OUT;
    'MEB_DQS_H6':'(0,0,0,0,CM69,0,0,0,0,0,0,0,0,0,0,0,0,0,0,0,0,0,0,0,0,0,0,0,0,~
0,0,0,0,0,0,0,0,0,0,0)';$S;BIDI;
    'MEB_DATA4':'(0,0,0,0,CF70,0,0,0,0,0,0,0,0,0,0,0,0,0,0,0,0,0,0,0,0,0,0,0,0,0~
,0,0,0,0,0,0,0,0,0,0)';$S;BIDI;
    'MEB_CA2':'(0,0,0,0,BH70,0,0,0,0,0,0,0,0,0,0,0,0,0,0,0,0,0,0,0,0,0,0,0,0,0,0~
,0,0,0,0,0,0,0,0,0)';$S;OUT;
    'MEA_DATA23':'(0,0,0,0,AC69,0,0,0,0,0,0,0,0,0,0,0,0,0,0,0,0,0,0,0,0,0,0,0,0,~
0,0,0,0,0,0,0,0,0,0,0)';$S;BIDI;
    'MEA_DATA12':'(0,0,0,0,R71,0,0,0,0,0,0,0,0,0,0,0,0,0,0,0,0,0,0,0,0,0,0,0,0,0~
,0,0,0,0,0,0,0,0,0,0)';$S;BIDI;
    'MEA_DATA5':'(0,0,0,0,K69,0,0,0,0,0,0,0,0,0,0,0,0,0,0,0,0,0,0,0,0,0,0,0,0,0,~
0,0,0,0,0,0,0,0,0,0)';$S;BIDI;
    'MEA_CHECK3':'(0,0,0,0,AL69,0,0,0,0,0,0,0,0,0,0,0,0,0,0,0,0,0,0,0,0,0,0,0,0,~
0,0,0,0,0,0,0,0,0,0,0)';$S;BIDI;
    'MEA_CA3':'(0,0,0,0,BA69,0,0,0,0,0,0,0,0,0,0,0,0,0,0,0,0,0,0,0,0,0,0,0,0,0,0~
,0,0,0,0,0,0,0,0,0)';$S;OUT;
    'MEB_DQS_H7':'(0,0,0,0,CV69,0,0,0,0,0,0,0,0,0,0,0,0,0,0,0,0,0,0,0,0,0,0,0,0,~
0,0,0,0,0,0,0,0,0,0,0)';$S;BIDI;
    'MEB_DATA5':'(0,0,0,0,CG69,0,0,0,0,0,0,0,0,0,0,0,0,0,0,0,0,0,0,0,0,0,0,0,0,0~
,0,0,0,0,0,0,0,0,0,0)';$S;BIDI;
    'MEB_CA3':'(0,0,0,0,BJ71,0,0,0,0,0,0,0,0,0,0,0,0,0,0,0,0,0,0,0,0,0,0,0,0,0,0~
,0,0,0,0,0,0,0,0,0)';$S;OUT;
    'MEB1_CS_L0':'(0,0,0,0,BL69,0,0,0,0,0,0,0,0,0,0,0,0,0,0,0,0,0,0,0,0,0,0,0,0,~
0,0,0,0,0,0,0,0,0,0,0)';$S;OUT;
    'MEB0_CS_L0':'(0,0,0,0,BM69,0,0,0,0,0,0,0,0,0,0,0,0,0,0,0,0,0,0,0,0,0,0,0,0,~
0,0,0,0,0,0,0,0,0,0,0)';$S;OUT;
    'MEA_DQS_L0':'(0,0,0,0,H70,0,0,0,0,0,0,0,0,0,0,0,0,0,0,0,0,0,0,0,0,0,0,0,0,0~
,0,0,0,0,0,0,0,0,0,0)';$S;BIDI;
    'MEA_DATA24':'(0,0,0,0,AC71,0,0,0,0,0,0,0,0,0,0,0,0,0,0,0,0,0,0,0,0,0,0,0,0,~
0,0,0,0,0,0,0,0,0,0,0)';$S;BIDI;
    'MEA_DATA13':'(0,0,0,0,T69,0,0,0,0,0,0,0,0,0,0,0,0,0,0,0,0,0,0,0,0,0,0,0,0,0~
,0,0,0,0,0,0,0,0,0,0)';$S;BIDI;
    'MEA_DATA6':'(0,0,0,0,K70,0,0,0,0,0,0,0,0,0,0,0,0,0,0,0,0,0,0,0,0,0,0,0,0,0,~
0,0,0,0,0,0,0,0,0,0)';$S;BIDI;
    'MEA_CHECK4':'(0,0,0,0,AN71,0,0,0,0,0,0,0,0,0,0,0,0,0,0,0,0,0,0,0,0,0,0,0,0,~
0,0,0,0,0,0,0,0,0,0,0)';$S;BIDI;
    'MEA_CA4':'(0,0,0,0,BA71,0,0,0,0,0,0,0,0,0,0,0,0,0,0,0,0,0,0,0,0,0,0,0,0,0,0~
,0,0,0,0,0,0,0,0,0)';$S;OUT;
    'MEB_DQS_H8':'(0,0,0,0,DD69,0,0,0,0,0,0,0,0,0,0,0,0,0,0,0,0,0,0,0,0,0,0,0,0,~
0,0,0,0,0,0,0,0,0,0,0)';$S;BIDI;
    'MEB_DATA30':'(0,0,0,0,DE71,0,0,0,0,0,0,0,0,0,0,0,0,0,0,0,0,0,0,0,0,0,0,0,0,~
0,0,0,0,0,0,0,0,0,0,0)';$S;BIDI;
    'MEB_DATA6':'(0,0,0,0,CG71,0,0,0,0,0,0,0,0,0,0,0,0,0,0,0,0,0,0,0,0,0,0,0,0,0~
,0,0,0,0,0,0,0,0,0,0)';$S;BIDI;
    'MEB_CA4':'(0,0,0,0,BJ69,0,0,0,0,0,0,0,0,0,0,0,0,0,0,0,0,0,0,0,0,0,0,0,0,0,0~
,0,0,0,0,0,0,0,0,0)';$S;OUT;
    'MEB1_CS_L1':'(0,0,0,0,BM70,0,0,0,0,0,0,0,0,0,0,0,0,0,0,0,0,0,0,0,0,0,0,0,0,~
0,0,0,0,0,0,0,0,0,0,0)';$S;OUT;
    'MEB0_CS_L1':'(0,0,0,0,BN71,0,0,0,0,0,0,0,0,0,0,0,0,0,0,0,0,0,0,0,0,0,0,0,0,~
0,0,0,0,0,0,0,0,0,0,0)';$S;OUT;
    'MEA_DQS_L1':'(0,0,0,0,P70,0,0,0,0,0,0,0,0,0,0,0,0,0,0,0,0,0,0,0,0,0,0,0,0,0~
,0,0,0,0,0,0,0,0,0,0)';$S;BIDI;
    'MEA_DATA25':'(0,0,0,0,AD69,0,0,0,0,0,0,0,0,0,0,0,0,0,0,0,0,0,0,0,0,0,0,0,0,~
0,0,0,0,0,0,0,0,0,0,0)';$S;BIDI;
    'MEA_DATA14':'(0,0,0,0,T70,0,0,0,0,0,0,0,0,0,0,0,0,0,0,0,0,0,0,0,0,0,0,0,0,0~
,0,0,0,0,0,0,0,0,0,0)';$S;BIDI;
    'MEA_DATA7':'(0,0,0,0,L69,0,0,0,0,0,0,0,0,0,0,0,0,0,0,0,0,0,0,0,0,0,0,0,0,0,~
0,0,0,0,0,0,0,0,0,0)';$S;BIDI;
    'MEA_CHECK5':'(0,0,0,0,AP69,0,0,0,0,0,0,0,0,0,0,0,0,0,0,0,0,0,0,0,0,0,0,0,0,~
0,0,0,0,0,0,0,0,0,0,0)';$S;BIDI;
    'MEA_CA5':'(0,0,0,0,BB70,0,0,0,0,0,0,0,0,0,0,0,0,0,0,0,0,0,0,0,0,0,0,0,0,0,0~
,0,0,0,0,0,0,0,0,0)';$S;OUT;
    'MEB_DATA31':'(0,0,0,0,DF69,0,0,0,0,0,0,0,0,0,0,0,0,0,0,0,0,0,0,0,0,0,0,0,0,~
0,0,0,0,0,0,0,0,0,0,0)';$S;BIDI;
    'MEB_DATA20':'(0,0,0,0,CV70,0,0,0,0,0,0,0,0,0,0,0,0,0,0,0,0,0,0,0,0,0,0,0,0,~
0,0,0,0,0,0,0,0,0,0,0)';$S;BIDI;
    'MEB_DATA7':'(0,0,0,0,CH69,0,0,0,0,0,0,0,0,0,0,0,0,0,0,0,0,0,0,0,0,0,0,0,0,0~
,0,0,0,0,0,0,0,0,0,0)';$S;BIDI;
    'MEB_CHECK0':'(0,0,0,0,BY70,0,0,0,0,0,0,0,0,0,0,0,0,0,0,0,0,0,0,0,0,0,0,0,0,~
0,0,0,0,0,0,0,0,0,0,0)';$S;BIDI;
    'MEB_CA5':'(0,0,0,0,BK69,0,0,0,0,0,0,0,0,0,0,0,0,0,0,0,0,0,0,0,0,0,0,0,0,0,0~
,0,0,0,0,0,0,0,0,0)';$S;OUT;
    'MEA_DQS_L2':'(0,0,0,0,Y70,0,0,0,0,0,0,0,0,0,0,0,0,0,0,0,0,0,0,0,0,0,0,0,0,0~
,0,0,0,0,0,0,0,0,0,0)';$S;BIDI;
    'MEA_DATA26':'(0,0,0,0,AD70,0,0,0,0,0,0,0,0,0,0,0,0,0,0,0,0,0,0,0,0,0,0,0,0,~
0,0,0,0,0,0,0,0,0,0,0)';$S;BIDI;
    'MEA_DATA15':'(0,0,0,0,U69,0,0,0,0,0,0,0,0,0,0,0,0,0,0,0,0,0,0,0,0,0,0,0,0,0~
,0,0,0,0,0,0,0,0,0,0)';$S;BIDI;
    'MEA_DATA8':'(0,0,0,0,L71,0,0,0,0,0,0,0,0,0,0,0,0,0,0,0,0,0,0,0,0,0,0,0,0,0,~
0,0,0,0,0,0,0,0,0,0)';$S;BIDI;
    'MEA_CHECK6':'(0,0,0,0,AP70,0,0,0,0,0,0,0,0,0,0,0,0,0,0,0,0,0,0,0,0,0,0,0,0,~
0,0,0,0,0,0,0,0,0,0,0)';$S;BIDI;
    'MEA_CA6':'(0,0,0,0,BB69,0,0,0,0,0,0,0,0,0,0,0,0,0,0,0,0,0,0,0,0,0,0,0,0,0,0~
,0,0,0,0,0,0,0,0,0)';$S;OUT;
    'MEB_DATA21':'(0,0,0,0,CW69,0,0,0,0,0,0,0,0,0,0,0,0,0,0,0,0,0,0,0,0,0,0,0,0,~
0,0,0,0,0,0,0,0,0,0,0)';$S;BIDI;
    'MEB_DATA10':'(0,0,0,0,CJ71,0,0,0,0,0,0,0,0,0,0,0,0,0,0,0,0,0,0,0,0,0,0,0,0,~
0,0,0,0,0,0,0,0,0,0,0)';$S;BIDI;
    'MEB_DATA8':'(0,0,0,0,CH70,0,0,0,0,0,0,0,0,0,0,0,0,0,0,0,0,0,0,0,0,0,0,0,0,0~
,0,0,0,0,0,0,0,0,0,0)';$S;BIDI;
    'MEB_CHECK1':'(0,0,0,0,CA69,0,0,0,0,0,0,0,0,0,0,0,0,0,0,0,0,0,0,0,0,0,0,0,0,~
0,0,0,0,0,0,0,0,0,0,0)';$S;BIDI;
    'MEB_CA6':'(0,0,0,0,BK70,0,0,0,0,0,0,0,0,0,0,0,0,0,0,0,0,0,0,0,0,0,0,0,0,0,0~
,0,0,0,0,0,0,0,0,0)';$S;OUT;
    'MEA_DQS_L3':'(0,0,0,0,AF70,0,0,0,0,0,0,0,0,0,0,0,0,0,0,0,0,0,0,0,0,0,0,0,0,~
0,0,0,0,0,0,0,0,0,0,0)';$S;BIDI;
    'MEA_DATA27':'(0,0,0,0,AE69,0,0,0,0,0,0,0,0,0,0,0,0,0,0,0,0,0,0,0,0,0,0,0,0,~
0,0,0,0,0,0,0,0,0,0,0)';$S;BIDI;
    'MEA_DATA16':'(0,0,0,0,U71,0,0,0,0,0,0,0,0,0,0,0,0,0,0,0,0,0,0,0,0,0,0,0,0,0~
,0,0,0,0,0,0,0,0,0,0)';$S;BIDI;
    'MEA_DATA9':'(0,0,0,0,M69,0,0,0,0,0,0,0,0,0,0,0,0,0,0,0,0,0,0,0,0,0,0,0,0,0,~
0,0,0,0,0,0,0,0,0,0)';$S;BIDI;
    'MEA_CHECK7':'(0,0,0,0,AR69,0,0,0,0,0,0,0,0,0,0,0,0,0,0,0,0,0,0,0,0,0,0,0,0,~
0,0,0,0,0,0,0,0,0,0,0)';$S;BIDI;
    'MEA1_RSP_L':'(0,0,0,0,BP69,0,0,0,0,0,0,0,0,0,0,0,0,0,0,0,0,0,0,0,0,0,0,0,0,~
0,0,0,0,0,0,0,0,0,0,0)';$S;IN;
    'MEA0_RSP_L':'(0,0,0,0,BN69,0,0,0,0,0,0,0,0,0,0,0,0,0,0,0,0,0,0,0,0,0,0,0,0,~
0,0,0,0,0,0,0,0,0,0,0)';$S;IN;
    'MEB_DATA22':'(0,0,0,0,CW71,0,0,0,0,0,0,0,0,0,0,0,0,0,0,0,0,0,0,0,0,0,0,0,0,~
0,0,0,0,0,0,0,0,0,0,0)';$S;BIDI;
    'MEB_DATA11':'(0,0,0,0,CK69,0,0,0,0,0,0,0,0,0,0,0,0,0,0,0,0,0,0,0,0,0,0,0,0,~
0,0,0,0,0,0,0,0,0,0,0)';$S;BIDI;
    'MEB_DATA9':'(0,0,0,0,CJ69,0,0,0,0,0,0,0,0,0,0,0,0,0,0,0,0,0,0,0,0,0,0,0,0,0~
,0,0,0,0,0,0,0,0,0,0)';$S;BIDI;
    'MEB_CHECK2':'(0,0,0,0,CA71,0,0,0,0,0,0,0,0,0,0,0,0,0,0,0,0,0,0,0,0,0,0,0,0,~
0,0,0,0,0,0,0,0,0,0,0)';$S;BIDI;
    'MEA_DQS_L4':'(0,0,0,0,AM70,0,0,0,0,0,0,0,0,0,0,0,0,0,0,0,0,0,0,0,0,0,0,0,0,~
0,0,0,0,0,0,0,0,0,0,0)';$S;BIDI;
    'MEA_DQS_H0':'(0,0,0,0,G71,0,0,0,0,0,0,0,0,0,0,0,0,0,0,0,0,0,0,0,0,0,0,0,0,0~
,0,0,0,0,0,0,0,0,0,0)';$S;BIDI;
    'MEA_DATA28':'(0,0,0,0,AG71,0,0,0,0,0,0,0,0,0,0,0,0,0,0,0,0,0,0,0,0,0,0,0,0,~
0,0,0,0,0,0,0,0,0,0,0)';$S;BIDI;
    'MEA_DATA17':'(0,0,0,0,V69,0,0,0,0,0,0,0,0,0,0,0,0,0,0,0,0,0,0,0,0,0,0,0,0,0~
,0,0,0,0,0,0,0,0,0,0)';$S;BIDI;
    'MEB_DATA23':'(0,0,0,0,CY69,0,0,0,0,0,0,0,0,0,0,0,0,0,0,0,0,0,0,0,0,0,0,0,0,~
0,0,0,0,0,0,0,0,0,0,0)';$S;BIDI;
    'MEB_DATA12':'(0,0,0,0,CM70,0,0,0,0,0,0,0,0,0,0,0,0,0,0,0,0,0,0,0,0,0,0,0,0,~
0,0,0,0,0,0,0,0,0,0,0)';$S;BIDI;
    'MEB_CHECK3':'(0,0,0,0,CB69,0,0,0,0,0,0,0,0,0,0,0,0,0,0,0,0,0,0,0,0,0,0,0,0,~
0,0,0,0,0,0,0,0,0,0,0)';$S;BIDI;
    'MEA_DQS_L5':'(0,0,0,0,H69,0,0,0,0,0,0,0,0,0,0,0,0,0,0,0,0,0,0,0,0,0,0,0,0,0~
,0,0,0,0,0,0,0,0,0,0)';$S;BIDI;
    'MEA_DQS_H1':'(0,0,0,0,N71,0,0,0,0,0,0,0,0,0,0,0,0,0,0,0,0,0,0,0,0,0,0,0,0,0~
,0,0,0,0,0,0,0,0,0,0)';$S;BIDI;
    'MEA_DATA29':'(0,0,0,0,AH69,0,0,0,0,0,0,0,0,0,0,0,0,0,0,0,0,0,0,0,0,0,0,0,0,~
0,0,0,0,0,0,0,0,0,0,0)';$S;BIDI;
    'MEA_DATA18':'(0,0,0,0,V70,0,0,0,0,0,0,0,0,0,0,0,0,0,0,0,0,0,0,0,0,0,0,0,0,0~
,0,0,0,0,0,0,0,0,0,0)';$S;BIDI;
    'MEB_DQS_L0':'(0,0,0,0,CE71,0,0,0,0,0,0,0,0,0,0,0,0,0,0,0,0,0,0,0,0,0,0,0,0,~
0,0,0,0,0,0,0,0,0,0,0)';$S;BIDI;
    'MEB_DATA24':'(0,0,0,0,CY70,0,0,0,0,0,0,0,0,0,0,0,0,0,0,0,0,0,0,0,0,0,0,0,0,~
0,0,0,0,0,0,0,0,0,0,0)';$S;BIDI;
    'MEB_DATA13':'(0,0,0,0,CN69,0,0,0,0,0,0,0,0,0,0,0,0,0,0,0,0,0,0,0,0,0,0,0,0,~
0,0,0,0,0,0,0,0,0,0,0)';$S;BIDI;
    'MEB_CHECK4':'(0,0,0,0,BT70,0,0,0,0,0,0,0,0,0,0,0,0,0,0,0,0,0,0,0,0,0,0,0,0,~
0,0,0,0,0,0,0,0,0,0,0)';$S;BIDI;
    'MEA_DQS_L6':'(0,0,0,0,P69,0,0,0,0,0,0,0,0,0,0,0,0,0,0,0,0,0,0,0,0,0,0,0,0,0~
,0,0,0,0,0,0,0,0,0,0)';$S;BIDI;
    'MEA_DQS_H2':'(0,0,0,0,W71,0,0,0,0,0,0,0,0,0,0,0,0,0,0,0,0,0,0,0,0,0,0,0,0,0~
,0,0,0,0,0,0,0,0,0,0)';$S;BIDI;
    'MEA_DATA19':'(0,0,0,0,W69,0,0,0,0,0,0,0,0,0,0,0,0,0,0,0,0,0,0,0,0,0,0,0,0,0~
,0,0,0,0,0,0,0,0,0,0)';$S;BIDI;
    'MEB_DQS_L1':'(0,0,0,0,CL71,0,0,0,0,0,0,0,0,0,0,0,0,0,0,0,0,0,0,0,0,0,0,0,0,~
0,0,0,0,0,0,0,0,0,0,0)';$S;BIDI;
    'MEB_DATA25':'(0,0,0,0,DA69,0,0,0,0,0,0,0,0,0,0,0,0,0,0,0,0,0,0,0,0,0,0,0,0,~
0,0,0,0,0,0,0,0,0,0,0)';$S;BIDI;
    'MEB_DATA14':'(0,0,0,0,CN71,0,0,0,0,0,0,0,0,0,0,0,0,0,0,0,0,0,0,0,0,0,0,0,0,~
0,0,0,0,0,0,0,0,0,0,0)';$S;BIDI;
    'MEB_CHECK5':'(0,0,0,0,BU69,0,0,0,0,0,0,0,0,0,0,0,0,0,0,0,0,0,0,0,0,0,0,0,0,~
0,0,0,0,0,0,0,0,0,0,0)';$S;BIDI;
    'MEA_DQS_L7':'(0,0,0,0,Y69,0,0,0,0,0,0,0,0,0,0,0,0,0,0,0,0,0,0,0,0,0,0,0,0,0~
,0,0,0,0,0,0,0,0,0,0)';$S;BIDI;
    'MEA_DQS_H3':'(0,0,0,0,AE71,0,0,0,0,0,0,0,0,0,0,0,0,0,0,0,0,0,0,0,0,0,0,0,0,~
0,0,0,0,0,0,0,0,0,0,0)';$S;BIDI;
    'MEA_PAR':'(0,0,0,0,BC69,0,0,0,0,0,0,0,0,0,0,0,0,0,0,0,0,0,0,0,0,0,0,0,0,0,0~
,0,0,0,0,0,0,0,0,0)';$S;OUT;
    'MEB_PAR':'(0,0,0,0,BL71,0,0,0,0,0,0,0,0,0,0,0,0,0,0,0,0,0,0,0,0,0,0,0,0,0,0~
,0,0,0,0,0,0,0,0,0)';$S;OUT;
    'MEB_DQS_H9':'(0,0,0,0,BV70,0,0,0,0,0,0,0,0,0,0,0,0,0,0,0,0,0,0,0,0,0,0,0,0,~
0,0,0,0,0,0,0,0,0,0,0)';$S;BIDI;
    'ME0_CLK_H':'(0,0,0,0,BC71,0,0,0,0,0,0,0,0,0,0,0,0,0,0,0,0,0,0,0,0,0,0,0,0,0~
,0,0,0,0,0,0,0,0,0,0)';$S;OUT;
    'ME0_CLK_L':'(0,0,0,0,BD70,0,0,0,0,0,0,0,0,0,0,0,0,0,0,0,0,0,0,0,0,0,0,0,0,0~
,0,0,0,0,0,0,0,0,0,0)';$S;OUT;
    'ME1_CLK_H':'(0,0,0,0,BF70,0,0,0,0,0,0,0,0,0,0,0,0,0,0,0,0,0,0,0,0,0,0,0,0,0~
,0,0,0,0,0,0,0,0,0,0)';$S;OUT;
    'ME1_CLK_L':'(0,0,0,0,BG71,0,0,0,0,0,0,0,0,0,0,0,0,0,0,0,0,0,0,0,0,0,0,0,0,0~
,0,0,0,0,0,0,0,0,0,0)';$S;OUT;
    'TEST39E':'(0,0,0,0,BF69,0,0,0,0,0,0,0,0,0,0,0,0,0,0,0,0,0,0,0,0,0,0,0,0,0,0~
,0,0,0,0,0,0,0,0,0)';$S;OUT;
    'MF_ALERT_L':'(0,0,0,0,0,AT65,0,0,0,0,0,0,0,0,0,0,0,0,0,0,0,0,0,0,0,0,0,0,0,~
0,0,0,0,0,0,0,0,0,0,0)';$S;IN;
    'MF_RESET_L':'(0,0,0,0,0,AU66,0,0,0,0,0,0,0,0,0,0,0,0,0,0,0,0,0,0,0,0,0,0,0,~
0,0,0,0,0,0,0,0,0,0,0)';$S;OUT;
    'MFB_DQS_L6':'(0,0,0,0,0,CL66,0,0,0,0,0,0,0,0,0,0,0,0,0,0,0,0,0,0,0,0,0,0,0,~
0,0,0,0,0,0,0,0,0,0,0)';$S;BIDI;
    'MFB_DQS_H2':'(0,0,0,0,0,CT67,0,0,0,0,0,0,0,0,0,0,0,0,0,0,0,0,0,0,0,0,0,0,0,~
0,0,0,0,0,0,0,0,0,0,0)';$S;BIDI;
    'MFB_DATA19':'(0,0,0,0,0,CT65,0,0,0,0,0,0,0,0,0,0,0,0,0,0,0,0,0,0,0,0,0,0,0,~
0,0,0,0,0,0,0,0,0,0,0)';$S;BIDI;
    'MFB_DATA7':'(0,0,0,0,0,CH65,0,0,0,0,0,0,0,0,0,0,0,0,0,0,0,0,0,0,0,0,0,0,0,0~
,0,0,0,0,0,0,0,0,0,0)';$S;BIDI;
    'MFA_DQS_H8':'(0,0,0,0,0,AG66,0,0,0,0,0,0,0,0,0,0,0,0,0,0,0,0,0,0,0,0,0,0,0,~
0,0,0,0,0,0,0,0,0,0,0)';$S;BIDI;
    'MFA_DATA30':'(0,0,0,0,0,AH67,0,0,0,0,0,0,0,0,0,0,0,0,0,0,0,0,0,0,0,0,0,0,0,~
0,0,0,0,0,0,0,0,0,0,0)';$S;BIDI;
    'MFA_DATA8':'(0,0,0,0,0,L67,0,0,0,0,0,0,0,0,0,0,0,0,0,0,0,0,0,0,0,0,0,0,0,0,~
0,0,0,0,0,0,0,0,0,0)';$S;BIDI;
    'MFA1_CS_L0':'(0,0,0,0,0,AU67,0,0,0,0,0,0,0,0,0,0,0,0,0,0,0,0,0,0,0,0,0,0,0,~
0,0,0,0,0,0,0,0,0,0,0)';$S;OUT;
    'MFA0_CS_L1':'(0,0,0,0,0,AW66,0,0,0,0,0,0,0,0,0,0,0,0,0,0,0,0,0,0,0,0,0,0,0,~
0,0,0,0,0,0,0,0,0,0,0)';$S;OUT;
    'MFB_DQS_L7':'(0,0,0,0,0,CU66,0,0,0,0,0,0,0,0,0,0,0,0,0,0,0,0,0,0,0,0,0,0,0,~
0,0,0,0,0,0,0,0,0,0,0)';$S;BIDI;
    'MFB_DQS_H3':'(0,0,0,0,0,DB67,0,0,0,0,0,0,0,0,0,0,0,0,0,0,0,0,0,0,0,0,0,0,0,~
0,0,0,0,0,0,0,0,0,0,0)';$S;BIDI;
    'MFB_DATA8':'(0,0,0,0,0,CH67,0,0,0,0,0,0,0,0,0,0,0,0,0,0,0,0,0,0,0,0,0,0,0,0~
,0,0,0,0,0,0,0,0,0,0)';$S;BIDI;
    'MFA_DQS_H9':'(0,0,0,0,0,AN66,0,0,0,0,0,0,0,0,0,0,0,0,0,0,0,0,0,0,0,0,0,0,0,~
0,0,0,0,0,0,0,0,0,0,0)';$S;BIDI;
    'MFA_DATA31':'(0,0,0,0,0,AJ66,0,0,0,0,0,0,0,0,0,0,0,0,0,0,0,0,0,0,0,0,0,0,0,~
0,0,0,0,0,0,0,0,0,0,0)';$S;BIDI;
    'MFA_DATA20':'(0,0,0,0,0,AA67,0,0,0,0,0,0,0,0,0,0,0,0,0,0,0,0,0,0,0,0,0,0,0,~
0,0,0,0,0,0,0,0,0,0,0)';$S;BIDI;
    'MFA_DATA9':'(0,0,0,0,0,M65,0,0,0,0,0,0,0,0,0,0,0,0,0,0,0,0,0,0,0,0,0,0,0,0,~
0,0,0,0,0,0,0,0,0,0)';$S;BIDI;
    'MFA_CHECK0':'(0,0,0,0,0,AJ67,0,0,0,0,0,0,0,0,0,0,0,0,0,0,0,0,0,0,0,0,0,0,0,~
0,0,0,0,0,0,0,0,0,0,0)';$S;BIDI;
    'MFA1_CS_L1':'(0,0,0,0,0,AV65,0,0,0,0,0,0,0,0,0,0,0,0,0,0,0,0,0,0,0,0,0,0,0,~
0,0,0,0,0,0,0,0,0,0,0)';$S;OUT;
    'MFB_DQS_L8':'(0,0,0,0,0,DC66,0,0,0,0,0,0,0,0,0,0,0,0,0,0,0,0,0,0,0,0,0,0,0,~
0,0,0,0,0,0,0,0,0,0,0)';$S;BIDI;
    'MFB_DQS_H4':'(0,0,0,0,0,BY65,0,0,0,0,0,0,0,0,0,0,0,0,0,0,0,0,0,0,0,0,0,0,0,~
0,0,0,0,0,0,0,0,0,0,0)';$S;BIDI;
    'MFB_DATA9':'(0,0,0,0,0,CJ66,0,0,0,0,0,0,0,0,0,0,0,0,0,0,0,0,0,0,0,0,0,0,0,0~
,0,0,0,0,0,0,0,0,0,0)';$S;BIDI;
    'MFA_DATA21':'(0,0,0,0,0,AB65,0,0,0,0,0,0,0,0,0,0,0,0,0,0,0,0,0,0,0,0,0,0,0,~
0,0,0,0,0,0,0,0,0,0,0)';$S;BIDI;
    'MFA_DATA10':'(0,0,0,0,0,M67,0,0,0,0,0,0,0,0,0,0,0,0,0,0,0,0,0,0,0,0,0,0,0,0~
,0,0,0,0,0,0,0,0,0,0)';$S;BIDI;
    'MFA_CHECK1':'(0,0,0,0,0,AK65,0,0,0,0,0,0,0,0,0,0,0,0,0,0,0,0,0,0,0,0,0,0,0,~
0,0,0,0,0,0,0,0,0,0,0)';$S;BIDI;
    'MFB_DQS_L9':'(0,0,0,0,0,BW67,0,0,0,0,0,0,0,0,0,0,0,0,0,0,0,0,0,0,0,0,0,0,0,~
0,0,0,0,0,0,0,0,0,0,0)';$S;BIDI;
    'MFB_DQS_H5':'(0,0,0,0,0,CF65,0,0,0,0,0,0,0,0,0,0,0,0,0,0,0,0,0,0,0,0,0,0,0,~
0,0,0,0,0,0,0,0,0,0,0)';$S;BIDI;
    'MFA_DATA22':'(0,0,0,0,0,AB67,0,0,0,0,0,0,0,0,0,0,0,0,0,0,0,0,0,0,0,0,0,0,0,~
0,0,0,0,0,0,0,0,0,0,0)';$S;BIDI;
    'MFA_DATA11':'(0,0,0,0,0,N66,0,0,0,0,0,0,0,0,0,0,0,0,0,0,0,0,0,0,0,0,0,0,0,0~
,0,0,0,0,0,0,0,0,0,0)';$S;BIDI;
    'MFA_CHECK2':'(0,0,0,0,0,AK67,0,0,0,0,0,0,0,0,0,0,0,0,0,0,0,0,0,0,0,0,0,0,0,~
0,0,0,0,0,0,0,0,0,0,0)';$S;BIDI;
    'MFB_DQS_H6':'(0,0,0,0,0,CM65,0,0,0,0,0,0,0,0,0,0,0,0,0,0,0,0,0,0,0,0,0,0,0,~
0,0,0,0,0,0,0,0,0,0,0)';$S;BIDI;
    'MFA_DATA23':'(0,0,0,0,0,AC66,0,0,0,0,0,0,0,0,0,0,0,0,0,0,0,0,0,0,0,0,0,0,0,~
0,0,0,0,0,0,0,0,0,0,0)';$S;BIDI;
    'MFA_DATA12':'(0,0,0,0,0,R67,0,0,0,0,0,0,0,0,0,0,0,0,0,0,0,0,0,0,0,0,0,0,0,0~
,0,0,0,0,0,0,0,0,0,0)';$S;BIDI;
    'MFA_CHECK3':'(0,0,0,0,0,AL66,0,0,0,0,0,0,0,0,0,0,0,0,0,0,0,0,0,0,0,0,0,0,0,~
0,0,0,0,0,0,0,0,0,0,0)';$S;BIDI;
    'MFA_CA0':'(0,0,0,0,0,AW67,0,0,0,0,0,0,0,0,0,0,0,0,0,0,0,0,0,0,0,0,0,0,0,0,0~
,0,0,0,0,0,0,0,0,0)';$S;OUT;
    'MFB_DQS_H7':'(0,0,0,0,0,CV65,0,0,0,0,0,0,0,0,0,0,0,0,0,0,0,0,0,0,0,0,0,0,0,~
0,0,0,0,0,0,0,0,0,0,0)';$S;BIDI;
    'MFB_CA0':'(0,0,0,0,0,BG66,0,0,0,0,0,0,0,0,0,0,0,0,0,0,0,0,0,0,0,0,0,0,0,0,0~
,0,0,0,0,0,0,0,0,0)';$S;OUT;
    'MFB0_CS_L0':'(0,0,0,0,0,BM65,0,0,0,0,0,0,0,0,0,0,0,0,0,0,0,0,0,0,0,0,0,0,0,~
0,0,0,0,0,0,0,0,0,0,0)';$S;OUT;
    'MFA_DQS_L0':'(0,0,0,0,0,H67,0,0,0,0,0,0,0,0,0,0,0,0,0,0,0,0,0,0,0,0,0,0,0,0~
,0,0,0,0,0,0,0,0,0,0)';$S;BIDI;
    'MFA_DATA24':'(0,0,0,0,0,AC67,0,0,0,0,0,0,0,0,0,0,0,0,0,0,0,0,0,0,0,0,0,0,0,~
0,0,0,0,0,0,0,0,0,0,0)';$S;BIDI;
    'MFA_DATA13':'(0,0,0,0,0,T65,0,0,0,0,0,0,0,0,0,0,0,0,0,0,0,0,0,0,0,0,0,0,0,0~
,0,0,0,0,0,0,0,0,0,0)';$S;BIDI;
    'MFA_CHECK4':'(0,0,0,0,0,AN67,0,0,0,0,0,0,0,0,0,0,0,0,0,0,0,0,0,0,0,0,0,0,0,~
0,0,0,0,0,0,0,0,0,0,0)';$S;BIDI;
    'MFA_CA1':'(0,0,0,0,0,AY67,0,0,0,0,0,0,0,0,0,0,0,0,0,0,0,0,0,0,0,0,0,0,0,0,0~
,0,0,0,0,0,0,0,0,0)';$S;OUT;
    'MFB_DQS_H8':'(0,0,0,0,0,DD65,0,0,0,0,0,0,0,0,0,0,0,0,0,0,0,0,0,0,0,0,0,0,0,~
0,0,0,0,0,0,0,0,0,0,0)';$S;BIDI;
    'MFB_DATA30':'(0,0,0,0,0,DE67,0,0,0,0,0,0,0,0,0,0,0,0,0,0,0,0,0,0,0,0,0,0,0,~
0,0,0,0,0,0,0,0,0,0,0)';$S;BIDI;
    'MFB_CA1':'(0,0,0,0,0,BH65,0,0,0,0,0,0,0,0,0,0,0,0,0,0,0,0,0,0,0,0,0,0,0,0,0~
,0,0,0,0,0,0,0,0,0)';$S;OUT;
    'MFB1_CS_L0':'(0,0,0,0,0,BL66,0,0,0,0,0,0,0,0,0,0,0,0,0,0,0,0,0,0,0,0,0,0,0,~
0,0,0,0,0,0,0,0,0,0,0)';$S;OUT;
    'MFB0_CS_L1':'(0,0,0,0,0,BN67,0,0,0,0,0,0,0,0,0,0,0,0,0,0,0,0,0,0,0,0,0,0,0,~
0,0,0,0,0,0,0,0,0,0,0)';$S;OUT;
    'MFA_DQS_L1':'(0,0,0,0,0,P67,0,0,0,0,0,0,0,0,0,0,0,0,0,0,0,0,0,0,0,0,0,0,0,0~
,0,0,0,0,0,0,0,0,0,0)';$S;BIDI;
    'MFA_DATA25':'(0,0,0,0,0,AD65,0,0,0,0,0,0,0,0,0,0,0,0,0,0,0,0,0,0,0,0,0,0,0,~
0,0,0,0,0,0,0,0,0,0,0)';$S;BIDI;
    'MFA_DATA14':'(0,0,0,0,0,T67,0,0,0,0,0,0,0,0,0,0,0,0,0,0,0,0,0,0,0,0,0,0,0,0~
,0,0,0,0,0,0,0,0,0,0)';$S;BIDI;
    'MFA_CHECK5':'(0,0,0,0,0,AP65,0,0,0,0,0,0,0,0,0,0,0,0,0,0,0,0,0,0,0,0,0,0,0,~
0,0,0,0,0,0,0,0,0,0,0)';$S;BIDI;
    'MFA_CA2':'(0,0,0,0,0,AY65,0,0,0,0,0,0,0,0,0,0,0,0,0,0,0,0,0,0,0,0,0,0,0,0,0~
,0,0,0,0,0,0,0,0,0)';$S;OUT;
    'MFB_DATA31':'(0,0,0,0,0,DF67,0,0,0,0,0,0,0,0,0,0,0,0,0,0,0,0,0,0,0,0,0,0,0,~
0,0,0,0,0,0,0,0,0,0,0)';$S;BIDI;
    'MFB_DATA20':'(0,0,0,0,0,CV67,0,0,0,0,0,0,0,0,0,0,0,0,0,0,0,0,0,0,0,0,0,0,0,~
0,0,0,0,0,0,0,0,0,0,0)';$S;BIDI;
    'MFB_CHECK0':'(0,0,0,0,0,BY67,0,0,0,0,0,0,0,0,0,0,0,0,0,0,0,0,0,0,0,0,0,0,0,~
0,0,0,0,0,0,0,0,0,0,0)';$S;BIDI;
    'MFB_CA2':'(0,0,0,0,0,BH67,0,0,0,0,0,0,0,0,0,0,0,0,0,0,0,0,0,0,0,0,0,0,0,0,0~
,0,0,0,0,0,0,0,0,0)';$S;OUT;
    'MFB1_CS_L1':'(0,0,0,0,0,BM67,0,0,0,0,0,0,0,0,0,0,0,0,0,0,0,0,0,0,0,0,0,0,0,~
0,0,0,0,0,0,0,0,0,0,0)';$S;OUT;
    'MFA_DQS_L2':'(0,0,0,0,0,Y67,0,0,0,0,0,0,0,0,0,0,0,0,0,0,0,0,0,0,0,0,0,0,0,0~
,0,0,0,0,0,0,0,0,0,0)';$S;BIDI;
    'MFA_DATA26':'(0,0,0,0,0,AD67,0,0,0,0,0,0,0,0,0,0,0,0,0,0,0,0,0,0,0,0,0,0,0,~
0,0,0,0,0,0,0,0,0,0,0)';$S;BIDI;
    'MFA_DATA15':'(0,0,0,0,0,U66,0,0,0,0,0,0,0,0,0,0,0,0,0,0,0,0,0,0,0,0,0,0,0,0~
,0,0,0,0,0,0,0,0,0,0)';$S;BIDI;
    'MFA_CHECK6':'(0,0,0,0,0,AP67,0,0,0,0,0,0,0,0,0,0,0,0,0,0,0,0,0,0,0,0,0,0,0,~
0,0,0,0,0,0,0,0,0,0,0)';$S;BIDI;
    'MFA_CA3':'(0,0,0,0,0,BA66,0,0,0,0,0,0,0,0,0,0,0,0,0,0,0,0,0,0,0,0,0,0,0,0,0~
,0,0,0,0,0,0,0,0,0)';$S;OUT;
    'MFB_DATA21':'(0,0,0,0,0,CW66,0,0,0,0,0,0,0,0,0,0,0,0,0,0,0,0,0,0,0,0,0,0,0,~
0,0,0,0,0,0,0,0,0,0,0)';$S;BIDI;
    'MFB_DATA10':'(0,0,0,0,0,CJ67,0,0,0,0,0,0,0,0,0,0,0,0,0,0,0,0,0,0,0,0,0,0,0,~
0,0,0,0,0,0,0,0,0,0,0)';$S;BIDI;
    'MFB_CHECK1':'(0,0,0,0,0,CA66,0,0,0,0,0,0,0,0,0,0,0,0,0,0,0,0,0,0,0,0,0,0,0,~
0,0,0,0,0,0,0,0,0,0,0)';$S;BIDI;
    'MFB_CA3':'(0,0,0,0,0,BJ67,0,0,0,0,0,0,0,0,0,0,0,0,0,0,0,0,0,0,0,0,0,0,0,0,0~
,0,0,0,0,0,0,0,0,0)';$S;OUT;
    'MFA_DQS_L3':'(0,0,0,0,0,AF67,0,0,0,0,0,0,0,0,0,0,0,0,0,0,0,0,0,0,0,0,0,0,0,~
0,0,0,0,0,0,0,0,0,0,0)';$S;BIDI;
    'MFA_DATA27':'(0,0,0,0,0,AE66,0,0,0,0,0,0,0,0,0,0,0,0,0,0,0,0,0,0,0,0,0,0,0,~
0,0,0,0,0,0,0,0,0,0,0)';$S;BIDI;
    'MFA_DATA16':'(0,0,0,0,0,U67,0,0,0,0,0,0,0,0,0,0,0,0,0,0,0,0,0,0,0,0,0,0,0,0~
,0,0,0,0,0,0,0,0,0,0)';$S;BIDI;
    'MFA_CHECK7':'(0,0,0,0,0,AR66,0,0,0,0,0,0,0,0,0,0,0,0,0,0,0,0,0,0,0,0,0,0,0,~
0,0,0,0,0,0,0,0,0,0,0)';$S;BIDI;
    'MFA_CA4':'(0,0,0,0,0,BA67,0,0,0,0,0,0,0,0,0,0,0,0,0,0,0,0,0,0,0,0,0,0,0,0,0~
,0,0,0,0,0,0,0,0,0)';$S;OUT;
    'MFA0_RSP_L':'(0,0,0,0,0,BN66,0,0,0,0,0,0,0,0,0,0,0,0,0,0,0,0,0,0,0,0,0,0,0,~
0,0,0,0,0,0,0,0,0,0,0)';$S;IN;
    'MFB_DATA22':'(0,0,0,0,0,CW67,0,0,0,0,0,0,0,0,0,0,0,0,0,0,0,0,0,0,0,0,0,0,0,~
0,0,0,0,0,0,0,0,0,0,0)';$S;BIDI;
    'MFB_DATA11':'(0,0,0,0,0,CK65,0,0,0,0,0,0,0,0,0,0,0,0,0,0,0,0,0,0,0,0,0,0,0,~
0,0,0,0,0,0,0,0,0,0,0)';$S;BIDI;
    'MFB_CHECK2':'(0,0,0,0,0,CA67,0,0,0,0,0,0,0,0,0,0,0,0,0,0,0,0,0,0,0,0,0,0,0,~
0,0,0,0,0,0,0,0,0,0,0)';$S;BIDI;
    'MFB_CA4':'(0,0,0,0,0,BJ66,0,0,0,0,0,0,0,0,0,0,0,0,0,0,0,0,0,0,0,0,0,0,0,0,0~
,0,0,0,0,0,0,0,0,0)';$S;OUT;
    'MFA_DQS_L4':'(0,0,0,0,0,AM67,0,0,0,0,0,0,0,0,0,0,0,0,0,0,0,0,0,0,0,0,0,0,0,~
0,0,0,0,0,0,0,0,0,0,0)';$S;BIDI;
    'MFA_DQS_H0':'(0,0,0,0,0,G67,0,0,0,0,0,0,0,0,0,0,0,0,0,0,0,0,0,0,0,0,0,0,0,0~
,0,0,0,0,0,0,0,0,0,0)';$S;BIDI;
    'MFA_DATA28':'(0,0,0,0,0,AG67,0,0,0,0,0,0,0,0,0,0,0,0,0,0,0,0,0,0,0,0,0,0,0,~
0,0,0,0,0,0,0,0,0,0,0)';$S;BIDI;
    'MFA_DATA17':'(0,0,0,0,0,V65,0,0,0,0,0,0,0,0,0,0,0,0,0,0,0,0,0,0,0,0,0,0,0,0~
,0,0,0,0,0,0,0,0,0,0)';$S;BIDI;
    'MFA_DATA0':'(0,0,0,0,0,E67,0,0,0,0,0,0,0,0,0,0,0,0,0,0,0,0,0,0,0,0,0,0,0,0,~
0,0,0,0,0,0,0,0,0,0)';$S;BIDI;
    'MFA_CA5':'(0,0,0,0,0,BB67,0,0,0,0,0,0,0,0,0,0,0,0,0,0,0,0,0,0,0,0,0,0,0,0,0~
,0,0,0,0,0,0,0,0,0)';$S;OUT;
    'MFA1_RSP_L':'(0,0,0,0,0,BP65,0,0,0,0,0,0,0,0,0,0,0,0,0,0,0,0,0,0,0,0,0,0,0,~
0,0,0,0,0,0,0,0,0,0,0)';$S;IN;
    'MFB_DATA23':'(0,0,0,0,0,CY65,0,0,0,0,0,0,0,0,0,0,0,0,0,0,0,0,0,0,0,0,0,0,0,~
0,0,0,0,0,0,0,0,0,0,0)';$S;BIDI;
    'MFB_DATA12':'(0,0,0,0,0,CM67,0,0,0,0,0,0,0,0,0,0,0,0,0,0,0,0,0,0,0,0,0,0,0,~
0,0,0,0,0,0,0,0,0,0,0)';$S;BIDI;
    'MFB_DATA0':'(0,0,0,0,0,CB67,0,0,0,0,0,0,0,0,0,0,0,0,0,0,0,0,0,0,0,0,0,0,0,0~
,0,0,0,0,0,0,0,0,0,0)';$S;BIDI;
    'MFB_CHECK3':'(0,0,0,0,0,CB65,0,0,0,0,0,0,0,0,0,0,0,0,0,0,0,0,0,0,0,0,0,0,0,~
0,0,0,0,0,0,0,0,0,0,0)';$S;BIDI;
    'MFB_CA5':'(0,0,0,0,0,BK65,0,0,0,0,0,0,0,0,0,0,0,0,0,0,0,0,0,0,0,0,0,0,0,0,0~
,0,0,0,0,0,0,0,0,0)';$S;OUT;
    'MFA_DQS_L5':'(0,0,0,0,0,H65,0,0,0,0,0,0,0,0,0,0,0,0,0,0,0,0,0,0,0,0,0,0,0,0~
,0,0,0,0,0,0,0,0,0,0)';$S;BIDI;
    'MFA_DQS_H1':'(0,0,0,0,0,N67,0,0,0,0,0,0,0,0,0,0,0,0,0,0,0,0,0,0,0,0,0,0,0,0~
,0,0,0,0,0,0,0,0,0,0)';$S;BIDI;
    'MFA_DATA29':'(0,0,0,0,0,AH65,0,0,0,0,0,0,0,0,0,0,0,0,0,0,0,0,0,0,0,0,0,0,0,~
0,0,0,0,0,0,0,0,0,0,0)';$S;BIDI;
    'MFA_DATA18':'(0,0,0,0,0,V67,0,0,0,0,0,0,0,0,0,0,0,0,0,0,0,0,0,0,0,0,0,0,0,0~
,0,0,0,0,0,0,0,0,0,0)';$S;BIDI;
    'MFA_DATA1':'(0,0,0,0,0,F65,0,0,0,0,0,0,0,0,0,0,0,0,0,0,0,0,0,0,0,0,0,0,0,0,~
0,0,0,0,0,0,0,0,0,0)';$S;BIDI;
    'MFA_CA6':'(0,0,0,0,0,BB65,0,0,0,0,0,0,0,0,0,0,0,0,0,0,0,0,0,0,0,0,0,0,0,0,0~
,0,0,0,0,0,0,0,0,0)';$S;OUT;
    'MFB_DQS_L0':'(0,0,0,0,0,CE67,0,0,0,0,0,0,0,0,0,0,0,0,0,0,0,0,0,0,0,0,0,0,0,~
0,0,0,0,0,0,0,0,0,0,0)';$S;BIDI;
    'MFB_DATA24':'(0,0,0,0,0,CY67,0,0,0,0,0,0,0,0,0,0,0,0,0,0,0,0,0,0,0,0,0,0,0,~
0,0,0,0,0,0,0,0,0,0,0)';$S;BIDI;
    'MFB_DATA13':'(0,0,0,0,0,CN66,0,0,0,0,0,0,0,0,0,0,0,0,0,0,0,0,0,0,0,0,0,0,0,~
0,0,0,0,0,0,0,0,0,0,0)';$S;BIDI;
    'MFB_DATA1':'(0,0,0,0,0,CC66,0,0,0,0,0,0,0,0,0,0,0,0,0,0,0,0,0,0,0,0,0,0,0,0~
,0,0,0,0,0,0,0,0,0,0)';$S;BIDI;
    'MFB_CHECK4':'(0,0,0,0,0,BT67,0,0,0,0,0,0,0,0,0,0,0,0,0,0,0,0,0,0,0,0,0,0,0,~
0,0,0,0,0,0,0,0,0,0,0)';$S;BIDI;
    'MFB_CA6':'(0,0,0,0,0,BK67,0,0,0,0,0,0,0,0,0,0,0,0,0,0,0,0,0,0,0,0,0,0,0,0,0~
,0,0,0,0,0,0,0,0,0)';$S;OUT;
    'MFA_DQS_L6':'(0,0,0,0,0,P65,0,0,0,0,0,0,0,0,0,0,0,0,0,0,0,0,0,0,0,0,0,0,0,0~
,0,0,0,0,0,0,0,0,0,0)';$S;BIDI;
    'MFA_DQS_H2':'(0,0,0,0,0,W67,0,0,0,0,0,0,0,0,0,0,0,0,0,0,0,0,0,0,0,0,0,0,0,0~
,0,0,0,0,0,0,0,0,0,0)';$S;BIDI;
    'MFA_DATA19':'(0,0,0,0,0,W66,0,0,0,0,0,0,0,0,0,0,0,0,0,0,0,0,0,0,0,0,0,0,0,0~
,0,0,0,0,0,0,0,0,0,0)';$S;BIDI;
    'MFA_DATA2':'(0,0,0,0,0,F67,0,0,0,0,0,0,0,0,0,0,0,0,0,0,0,0,0,0,0,0,0,0,0,0,~
0,0,0,0,0,0,0,0,0,0)';$S;BIDI;
    'MFB_DQS_L1':'(0,0,0,0,0,CL67,0,0,0,0,0,0,0,0,0,0,0,0,0,0,0,0,0,0,0,0,0,0,0,~
0,0,0,0,0,0,0,0,0,0,0)';$S;BIDI;
    'MFB_DATA25':'(0,0,0,0,0,DA66,0,0,0,0,0,0,0,0,0,0,0,0,0,0,0,0,0,0,0,0,0,0,0,~
0,0,0,0,0,0,0,0,0,0,0)';$S;BIDI;
    'MFB_DATA14':'(0,0,0,0,0,CN67,0,0,0,0,0,0,0,0,0,0,0,0,0,0,0,0,0,0,0,0,0,0,0,~
0,0,0,0,0,0,0,0,0,0,0)';$S;BIDI;
    'MFB_DATA2':'(0,0,0,0,0,CC67,0,0,0,0,0,0,0,0,0,0,0,0,0,0,0,0,0,0,0,0,0,0,0,0~
,0,0,0,0,0,0,0,0,0,0)';$S;BIDI;
    'MFB_CHECK5':'(0,0,0,0,0,BU66,0,0,0,0,0,0,0,0,0,0,0,0,0,0,0,0,0,0,0,0,0,0,0,~
0,0,0,0,0,0,0,0,0,0,0)';$S;BIDI;
    'MFA_DQS_L7':'(0,0,0,0,0,Y65,0,0,0,0,0,0,0,0,0,0,0,0,0,0,0,0,0,0,0,0,0,0,0,0~
,0,0,0,0,0,0,0,0,0,0)';$S;BIDI;
    'MFA_DQS_H3':'(0,0,0,0,0,AE67,0,0,0,0,0,0,0,0,0,0,0,0,0,0,0,0,0,0,0,0,0,0,0,~
0,0,0,0,0,0,0,0,0,0,0)';$S;BIDI;
    'MFA_DATA3':'(0,0,0,0,0,G66,0,0,0,0,0,0,0,0,0,0,0,0,0,0,0,0,0,0,0,0,0,0,0,0,~
0,0,0,0,0,0,0,0,0,0)';$S;BIDI;
    'MFB_DQS_L2':'(0,0,0,0,0,CU67,0,0,0,0,0,0,0,0,0,0,0,0,0,0,0,0,0,0,0,0,0,0,0,~
0,0,0,0,0,0,0,0,0,0,0)';$S;BIDI;
    'MFB_DATA26':'(0,0,0,0,0,DA67,0,0,0,0,0,0,0,0,0,0,0,0,0,0,0,0,0,0,0,0,0,0,0,~
0,0,0,0,0,0,0,0,0,0,0)';$S;BIDI;
    'MFB_DATA15':'(0,0,0,0,0,CP65,0,0,0,0,0,0,0,0,0,0,0,0,0,0,0,0,0,0,0,0,0,0,0,~
0,0,0,0,0,0,0,0,0,0,0)';$S;BIDI;
    'MFB_DATA3':'(0,0,0,0,0,CD65,0,0,0,0,0,0,0,0,0,0,0,0,0,0,0,0,0,0,0,0,0,0,0,0~
,0,0,0,0,0,0,0,0,0,0)';$S;BIDI;
    'MFB_CHECK6':'(0,0,0,0,0,BU67,0,0,0,0,0,0,0,0,0,0,0,0,0,0,0,0,0,0,0,0,0,0,0,~
0,0,0,0,0,0,0,0,0,0,0)';$S;BIDI;
    'MFA_DQS_L8':'(0,0,0,0,0,AF65,0,0,0,0,0,0,0,0,0,0,0,0,0,0,0,0,0,0,0,0,0,0,0,~
0,0,0,0,0,0,0,0,0,0,0)';$S;BIDI;
    'MFA_DQS_H4':'(0,0,0,0,0,AL67,0,0,0,0,0,0,0,0,0,0,0,0,0,0,0,0,0,0,0,0,0,0,0,~
0,0,0,0,0,0,0,0,0,0,0)';$S;BIDI;
    'MFA_DATA4':'(0,0,0,0,0,J67,0,0,0,0,0,0,0,0,0,0,0,0,0,0,0,0,0,0,0,0,0,0,0,0,~
0,0,0,0,0,0,0,0,0,0)';$S;BIDI;
    'MFB_DQS_L3':'(0,0,0,0,0,DC67,0,0,0,0,0,0,0,0,0,0,0,0,0,0,0,0,0,0,0,0,0,0,0,~
0,0,0,0,0,0,0,0,0,0,0)';$S;BIDI;
    'MFB_DATA27':'(0,0,0,0,0,DB65,0,0,0,0,0,0,0,0,0,0,0,0,0,0,0,0,0,0,0,0,0,0,0,~
0,0,0,0,0,0,0,0,0,0,0)';$S;BIDI;
    'MFB_DATA16':'(0,0,0,0,0,CP67,0,0,0,0,0,0,0,0,0,0,0,0,0,0,0,0,0,0,0,0,0,0,0,~
0,0,0,0,0,0,0,0,0,0,0)';$S;BIDI;
    'MFB_DATA4':'(0,0,0,0,0,CF67,0,0,0,0,0,0,0,0,0,0,0,0,0,0,0,0,0,0,0,0,0,0,0,0~
,0,0,0,0,0,0,0,0,0,0)';$S;BIDI;
    'MFB_CHECK7':'(0,0,0,0,0,BV65,0,0,0,0,0,0,0,0,0,0,0,0,0,0,0,0,0,0,0,0,0,0,0,~
0,0,0,0,0,0,0,0,0,0,0)';$S;BIDI;
    'MFB0_RSP_L':'(0,0,0,0,0,BP67,0,0,0,0,0,0,0,0,0,0,0,0,0,0,0,0,0,0,0,0,0,0,0,~
0,0,0,0,0,0,0,0,0,0,0)';$S;IN;
    'MFA_DQS_L9':'(0,0,0,0,0,AM65,0,0,0,0,0,0,0,0,0,0,0,0,0,0,0,0,0,0,0,0,0,0,0,~
0,0,0,0,0,0,0,0,0,0,0)';$S;BIDI;
    'MFA_DQS_H5':'(0,0,0,0,0,J66,0,0,0,0,0,0,0,0,0,0,0,0,0,0,0,0,0,0,0,0,0,0,0,0~
,0,0,0,0,0,0,0,0,0,0)';$S;BIDI;
    'MFA_DATA5':'(0,0,0,0,0,K65,0,0,0,0,0,0,0,0,0,0,0,0,0,0,0,0,0,0,0,0,0,0,0,0,~
0,0,0,0,0,0,0,0,0,0)';$S;BIDI;
    'MFB_DQS_L4':'(0,0,0,0,0,BW66,0,0,0,0,0,0,0,0,0,0,0,0,0,0,0,0,0,0,0,0,0,0,0,~
0,0,0,0,0,0,0,0,0,0,0)';$S;BIDI;
    'MFB_DQS_H0':'(0,0,0,0,0,CD67,0,0,0,0,0,0,0,0,0,0,0,0,0,0,0,0,0,0,0,0,0,0,0,~
0,0,0,0,0,0,0,0,0,0,0)';$S;BIDI;
    'MFB_DATA28':'(0,0,0,0,0,DD67,0,0,0,0,0,0,0,0,0,0,0,0,0,0,0,0,0,0,0,0,0,0,0,~
0,0,0,0,0,0,0,0,0,0,0)';$S;BIDI;
    'MFB_DATA17':'(0,0,0,0,0,CR66,0,0,0,0,0,0,0,0,0,0,0,0,0,0,0,0,0,0,0,0,0,0,0,~
0,0,0,0,0,0,0,0,0,0,0)';$S;BIDI;
    'MFB_DATA5':'(0,0,0,0,0,CG66,0,0,0,0,0,0,0,0,0,0,0,0,0,0,0,0,0,0,0,0,0,0,0,0~
,0,0,0,0,0,0,0,0,0,0)';$S;BIDI;
    'MFB1_RSP_L':'(0,0,0,0,0,BR67,0,0,0,0,0,0,0,0,0,0,0,0,0,0,0,0,0,0,0,0,0,0,0,~
0,0,0,0,0,0,0,0,0,0,0)';$S;IN;
    'MFA_DQS_H6':'(0,0,0,0,0,R66,0,0,0,0,0,0,0,0,0,0,0,0,0,0,0,0,0,0,0,0,0,0,0,0~
,0,0,0,0,0,0,0,0,0,0)';$S;BIDI;
    'MFA_DATA6':'(0,0,0,0,0,K67,0,0,0,0,0,0,0,0,0,0,0,0,0,0,0,0,0,0,0,0,0,0,0,0,~
0,0,0,0,0,0,0,0,0,0)';$S;BIDI;
    'MFB_DQS_L5':'(0,0,0,0,0,CE66,0,0,0,0,0,0,0,0,0,0,0,0,0,0,0,0,0,0,0,0,0,0,0,~
0,0,0,0,0,0,0,0,0,0,0)';$S;BIDI;
    'MFB_DQS_H1':'(0,0,0,0,0,CK67,0,0,0,0,0,0,0,0,0,0,0,0,0,0,0,0,0,0,0,0,0,0,0,~
0,0,0,0,0,0,0,0,0,0,0)';$S;BIDI;
    'MFB_DATA29':'(0,0,0,0,0,DE66,0,0,0,0,0,0,0,0,0,0,0,0,0,0,0,0,0,0,0,0,0,0,0,~
0,0,0,0,0,0,0,0,0,0,0)';$S;BIDI;
    'MFB_DATA18':'(0,0,0,0,0,CR67,0,0,0,0,0,0,0,0,0,0,0,0,0,0,0,0,0,0,0,0,0,0,0,~
0,0,0,0,0,0,0,0,0,0,0)';$S;BIDI;
    'MFB_DATA6':'(0,0,0,0,0,CG67,0,0,0,0,0,0,0,0,0,0,0,0,0,0,0,0,0,0,0,0,0,0,0,0~
,0,0,0,0,0,0,0,0,0,0)';$S;BIDI;
    'MFA_DQS_H7':'(0,0,0,0,0,AA66,0,0,0,0,0,0,0,0,0,0,0,0,0,0,0,0,0,0,0,0,0,0,0,~
0,0,0,0,0,0,0,0,0,0,0)';$S;BIDI;
    'MFA_DATA7':'(0,0,0,0,0,L66,0,0,0,0,0,0,0,0,0,0,0,0,0,0,0,0,0,0,0,0,0,0,0,0,~
0,0,0,0,0,0,0,0,0,0)';$S;BIDI;
    'MFA0_CS_L0':'(0,0,0,0,0,AV67,0,0,0,0,0,0,0,0,0,0,0,0,0,0,0,0,0,0,0,0,0,0,0,~
0,0,0,0,0,0,0,0,0,0,0)';$S;OUT;
    'MFA_PAR':'(0,0,0,0,0,BC66,0,0,0,0,0,0,0,0,0,0,0,0,0,0,0,0,0,0,0,0,0,0,0,0,0~
,0,0,0,0,0,0,0,0,0)';$S;OUT;
    'MFB_PAR':'(0,0,0,0,0,BL67,0,0,0,0,0,0,0,0,0,0,0,0,0,0,0,0,0,0,0,0,0,0,0,0,0~
,0,0,0,0,0,0,0,0,0)';$S;OUT;
    'MFB_DQS_H9':'(0,0,0,0,0,BV67,0,0,0,0,0,0,0,0,0,0,0,0,0,0,0,0,0,0,0,0,0,0,0,~
0,0,0,0,0,0,0,0,0,0,0)';$S;BIDI;
    'MF0_CLK_H':'(0,0,0,0,0,BC67,0,0,0,0,0,0,0,0,0,0,0,0,0,0,0,0,0,0,0,0,0,0,0,0~
,0,0,0,0,0,0,0,0,0,0)';$S;OUT;
    'MF0_CLK_L':'(0,0,0,0,0,BD67,0,0,0,0,0,0,0,0,0,0,0,0,0,0,0,0,0,0,0,0,0,0,0,0~
,0,0,0,0,0,0,0,0,0,0)';$S;OUT;
    'MF1_CLK_H':'(0,0,0,0,0,BF67,0,0,0,0,0,0,0,0,0,0,0,0,0,0,0,0,0,0,0,0,0,0,0,0~
,0,0,0,0,0,0,0,0,0,0)';$S;OUT;
    'MF1_CLK_L':'(0,0,0,0,0,BG67,0,0,0,0,0,0,0,0,0,0,0,0,0,0,0,0,0,0,0,0,0,0,0,0~
,0,0,0,0,0,0,0,0,0,0)';$S;OUT;
    'TEST39F':'(0,0,0,0,0,BF65,0,0,0,0,0,0,0,0,0,0,0,0,0,0,0,0,0,0,0,0,0,0,0,0,0~
,0,0,0,0,0,0,0,0,0)';$S;OUT;
    'MG_ALERT_L':'(0,0,0,0,0,0,AR2,0,0,0,0,0,0,0,0,0,0,0,0,0,0,0,0,0,0,0,0,0,0,0~
,0,0,0,0,0,0,0,0,0,0)';$S;IN;
    'MG_RESET_L':'(0,0,0,0,0,0,AT2,0,0,0,0,0,0,0,0,0,0,0,0,0,0,0,0,0,0,0,0,0,0,0~
,0,0,0,0,0,0,0,0,0,0)';$S;OUT;
    'MGB_DQS_L9':'(0,0,0,0,0,0,BW2,0,0,0,0,0,0,0,0,0,0,0,0,0,0,0,0,0,0,0,0,0,0,0~
,0,0,0,0,0,0,0,0,0,0)';$S;BIDI;
    'MGB_DQS_H5':'(0,0,0,0,0,0,CF4,0,0,0,0,0,0,0,0,0,0,0,0,0,0,0,0,0,0,0,0,0,0,0~
,0,0,0,0,0,0,0,0,0,0)';$S;BIDI;
    'MGB_DATA1':'(0,0,0,0,0,0,CC3,0,0,0,0,0,0,0,0,0,0,0,0,0,0,0,0,0,0,0,0,0,0,0,~
0,0,0,0,0,0,0,0,0,0)';$S;BIDI;
    'MGA_DATA22':'(0,0,0,0,0,0,AB2,0,0,0,0,0,0,0,0,0,0,0,0,0,0,0,0,0,0,0,0,0,0,0~
,0,0,0,0,0,0,0,0,0,0)';$S;BIDI;
    'MGA_DATA11':'(0,0,0,0,0,0,N3,0,0,0,0,0,0,0,0,0,0,0,0,0,0,0,0,0,0,0,0,0,0,0,~
0,0,0,0,0,0,0,0,0,0)';$S;BIDI;
    'MGA_DATA1':'(0,0,0,0,0,0,F4,0,0,0,0,0,0,0,0,0,0,0,0,0,0,0,0,0,0,0,0,0,0,0,0~
,0,0,0,0,0,0,0,0,0)';$S;BIDI;
    'MGA_CHECK2':'(0,0,0,0,0,0,AK2,0,0,0,0,0,0,0,0,0,0,0,0,0,0,0,0,0,0,0,0,0,0,0~
,0,0,0,0,0,0,0,0,0,0)';$S;BIDI;
    'MGB_DQS_H6':'(0,0,0,0,0,0,CM4,0,0,0,0,0,0,0,0,0,0,0,0,0,0,0,0,0,0,0,0,0,0,0~
,0,0,0,0,0,0,0,0,0,0)';$S;BIDI;
    'MGB_DATA2':'(0,0,0,0,0,0,CC2,0,0,0,0,0,0,0,0,0,0,0,0,0,0,0,0,0,0,0,0,0,0,0,~
0,0,0,0,0,0,0,0,0,0)';$S;BIDI;
    'MGA_DATA23':'(0,0,0,0,0,0,AC3,0,0,0,0,0,0,0,0,0,0,0,0,0,0,0,0,0,0,0,0,0,0,0~
,0,0,0,0,0,0,0,0,0,0)';$S;BIDI;
    'MGA_DATA12':'(0,0,0,0,0,0,R2,0,0,0,0,0,0,0,0,0,0,0,0,0,0,0,0,0,0,0,0,0,0,0,~
0,0,0,0,0,0,0,0,0,0)';$S;BIDI;
    'MGA_DATA2':'(0,0,0,0,0,0,F2,0,0,0,0,0,0,0,0,0,0,0,0,0,0,0,0,0,0,0,0,0,0,0,0~
,0,0,0,0,0,0,0,0,0)';$S;BIDI;
    'MGA_CHECK3':'(0,0,0,0,0,0,AL3,0,0,0,0,0,0,0,0,0,0,0,0,0,0,0,0,0,0,0,0,0,0,0~
,0,0,0,0,0,0,0,0,0,0)';$S;BIDI;
    'MGB_DQS_H7':'(0,0,0,0,0,0,CV4,0,0,0,0,0,0,0,0,0,0,0,0,0,0,0,0,0,0,0,0,0,0,0~
,0,0,0,0,0,0,0,0,0,0)';$S;BIDI;
    'MGB_DATA3':'(0,0,0,0,0,0,CD4,0,0,0,0,0,0,0,0,0,0,0,0,0,0,0,0,0,0,0,0,0,0,0,~
0,0,0,0,0,0,0,0,0,0)';$S;BIDI;
    'MGB1_CS_L0':'(0,0,0,0,0,0,BL2,0,0,0,0,0,0,0,0,0,0,0,0,0,0,0,0,0,0,0,0,0,0,0~
,0,0,0,0,0,0,0,0,0,0)';$S;OUT;
    'MGB0_CS_L0':'(0,0,0,0,0,0,BM4,0,0,0,0,0,0,0,0,0,0,0,0,0,0,0,0,0,0,0,0,0,0,0~
,0,0,0,0,0,0,0,0,0,0)';$S;OUT;
    'MGA_DQS_L0':'(0,0,0,0,0,0,H2,0,0,0,0,0,0,0,0,0,0,0,0,0,0,0,0,0,0,0,0,0,0,0,~
0,0,0,0,0,0,0,0,0,0)';$S;BIDI;
    'MGA_DATA24':'(0,0,0,0,0,0,AC2,0,0,0,0,0,0,0,0,0,0,0,0,0,0,0,0,0,0,0,0,0,0,0~
,0,0,0,0,0,0,0,0,0,0)';$S;BIDI;
    'MGA_DATA13':'(0,0,0,0,0,0,T4,0,0,0,0,0,0,0,0,0,0,0,0,0,0,0,0,0,0,0,0,0,0,0,~
0,0,0,0,0,0,0,0,0,0)';$S;BIDI;
    'MGA_DATA3':'(0,0,0,0,0,0,G3,0,0,0,0,0,0,0,0,0,0,0,0,0,0,0,0,0,0,0,0,0,0,0,0~
,0,0,0,0,0,0,0,0,0)';$S;BIDI;
    'MGA_CHECK4':'(0,0,0,0,0,0,AN2,0,0,0,0,0,0,0,0,0,0,0,0,0,0,0,0,0,0,0,0,0,0,0~
,0,0,0,0,0,0,0,0,0,0)';$S;BIDI;
    'MGB_DQS_H8':'(0,0,0,0,0,0,DD4,0,0,0,0,0,0,0,0,0,0,0,0,0,0,0,0,0,0,0,0,0,0,0~
,0,0,0,0,0,0,0,0,0,0)';$S;BIDI;
    'MGB_DATA30':'(0,0,0,0,0,0,DE2,0,0,0,0,0,0,0,0,0,0,0,0,0,0,0,0,0,0,0,0,0,0,0~
,0,0,0,0,0,0,0,0,0,0)';$S;BIDI;
    'MGB_DATA4':'(0,0,0,0,0,0,CF2,0,0,0,0,0,0,0,0,0,0,0,0,0,0,0,0,0,0,0,0,0,0,0,~
0,0,0,0,0,0,0,0,0,0)';$S;BIDI;
    'MGB1_CS_L1':'(0,0,0,0,0,0,BM2,0,0,0,0,0,0,0,0,0,0,0,0,0,0,0,0,0,0,0,0,0,0,0~
,0,0,0,0,0,0,0,0,0,0)';$S;OUT;
    'MGB0_CS_L1':'(0,0,0,0,0,0,BN2,0,0,0,0,0,0,0,0,0,0,0,0,0,0,0,0,0,0,0,0,0,0,0~
,0,0,0,0,0,0,0,0,0,0)';$S;OUT;
    'MGA_DQS_L1':'(0,0,0,0,0,0,P2,0,0,0,0,0,0,0,0,0,0,0,0,0,0,0,0,0,0,0,0,0,0,0,~
0,0,0,0,0,0,0,0,0,0)';$S;BIDI;
    'MGA_DATA25':'(0,0,0,0,0,0,AD4,0,0,0,0,0,0,0,0,0,0,0,0,0,0,0,0,0,0,0,0,0,0,0~
,0,0,0,0,0,0,0,0,0,0)';$S;BIDI;
    'MGA_DATA14':'(0,0,0,0,0,0,T2,0,0,0,0,0,0,0,0,0,0,0,0,0,0,0,0,0,0,0,0,0,0,0,~
0,0,0,0,0,0,0,0,0,0)';$S;BIDI;
    'MGA_DATA4':'(0,0,0,0,0,0,J2,0,0,0,0,0,0,0,0,0,0,0,0,0,0,0,0,0,0,0,0,0,0,0,0~
,0,0,0,0,0,0,0,0,0)';$S;BIDI;
    'MGA_CHECK5':'(0,0,0,0,0,0,AP4,0,0,0,0,0,0,0,0,0,0,0,0,0,0,0,0,0,0,0,0,0,0,0~
,0,0,0,0,0,0,0,0,0,0)';$S;BIDI;
    'MGA_CA0':'(0,0,0,0,0,0,AW2,0,0,0,0,0,0,0,0,0,0,0,0,0,0,0,0,0,0,0,0,0,0,0,0,~
0,0,0,0,0,0,0,0,0)';$S;OUT;
    'MGB_DATA31':'(0,0,0,0,0,0,DF2,0,0,0,0,0,0,0,0,0,0,0,0,0,0,0,0,0,0,0,0,0,0,0~
,0,0,0,0,0,0,0,0,0,0)';$S;BIDI;
    'MGB_DATA20':'(0,0,0,0,0,0,CV2,0,0,0,0,0,0,0,0,0,0,0,0,0,0,0,0,0,0,0,0,0,0,0~
,0,0,0,0,0,0,0,0,0,0)';$S;BIDI;
    'MGB_DATA5':'(0,0,0,0,0,0,CG3,0,0,0,0,0,0,0,0,0,0,0,0,0,0,0,0,0,0,0,0,0,0,0,~
0,0,0,0,0,0,0,0,0,0)';$S;BIDI;
    'MGB_CHECK0':'(0,0,0,0,0,0,BY2,0,0,0,0,0,0,0,0,0,0,0,0,0,0,0,0,0,0,0,0,0,0,0~
,0,0,0,0,0,0,0,0,0,0)';$S;BIDI;
    'MGB_CA0':'(0,0,0,0,0,0,BG3,0,0,0,0,0,0,0,0,0,0,0,0,0,0,0,0,0,0,0,0,0,0,0,0,~
0,0,0,0,0,0,0,0,0)';$S;OUT;
    'MGA_DQS_L2':'(0,0,0,0,0,0,Y2,0,0,0,0,0,0,0,0,0,0,0,0,0,0,0,0,0,0,0,0,0,0,0,~
0,0,0,0,0,0,0,0,0,0)';$S;BIDI;
    'MGA_DATA26':'(0,0,0,0,0,0,AD2,0,0,0,0,0,0,0,0,0,0,0,0,0,0,0,0,0,0,0,0,0,0,0~
,0,0,0,0,0,0,0,0,0,0)';$S;BIDI;
    'MGA_DATA15':'(0,0,0,0,0,0,U3,0,0,0,0,0,0,0,0,0,0,0,0,0,0,0,0,0,0,0,0,0,0,0,~
0,0,0,0,0,0,0,0,0,0)';$S;BIDI;
    'MGA_DATA5':'(0,0,0,0,0,0,K4,0,0,0,0,0,0,0,0,0,0,0,0,0,0,0,0,0,0,0,0,0,0,0,0~
,0,0,0,0,0,0,0,0,0)';$S;BIDI;
    'MGA_CHECK6':'(0,0,0,0,0,0,AP2,0,0,0,0,0,0,0,0,0,0,0,0,0,0,0,0,0,0,0,0,0,0,0~
,0,0,0,0,0,0,0,0,0,0)';$S;BIDI;
    'MGA_CA1':'(0,0,0,0,0,0,AY2,0,0,0,0,0,0,0,0,0,0,0,0,0,0,0,0,0,0,0,0,0,0,0,0,~
0,0,0,0,0,0,0,0,0)';$S;OUT;
    'MGB_DATA21':'(0,0,0,0,0,0,CW3,0,0,0,0,0,0,0,0,0,0,0,0,0,0,0,0,0,0,0,0,0,0,0~
,0,0,0,0,0,0,0,0,0,0)';$S;BIDI;
    'MGB_DATA10':'(0,0,0,0,0,0,CJ2,0,0,0,0,0,0,0,0,0,0,0,0,0,0,0,0,0,0,0,0,0,0,0~
,0,0,0,0,0,0,0,0,0,0)';$S;BIDI;
    'MGB_DATA6':'(0,0,0,0,0,0,CG2,0,0,0,0,0,0,0,0,0,0,0,0,0,0,0,0,0,0,0,0,0,0,0,~
0,0,0,0,0,0,0,0,0,0)';$S;BIDI;
    'MGB_CHECK1':'(0,0,0,0,0,0,CA3,0,0,0,0,0,0,0,0,0,0,0,0,0,0,0,0,0,0,0,0,0,0,0~
,0,0,0,0,0,0,0,0,0,0)';$S;BIDI;
    'MGB_CA1':'(0,0,0,0,0,0,BH4,0,0,0,0,0,0,0,0,0,0,0,0,0,0,0,0,0,0,0,0,0,0,0,0,~
0,0,0,0,0,0,0,0,0)';$S;OUT;
    'MGA_DQS_L3':'(0,0,0,0,0,0,AF2,0,0,0,0,0,0,0,0,0,0,0,0,0,0,0,0,0,0,0,0,0,0,0~
,0,0,0,0,0,0,0,0,0,0)';$S;BIDI;
    'MGA_DATA27':'(0,0,0,0,0,0,AE3,0,0,0,0,0,0,0,0,0,0,0,0,0,0,0,0,0,0,0,0,0,0,0~
,0,0,0,0,0,0,0,0,0,0)';$S;BIDI;
    'MGA_DATA16':'(0,0,0,0,0,0,U2,0,0,0,0,0,0,0,0,0,0,0,0,0,0,0,0,0,0,0,0,0,0,0,~
0,0,0,0,0,0,0,0,0,0)';$S;BIDI;
    'MGA_DATA6':'(0,0,0,0,0,0,K2,0,0,0,0,0,0,0,0,0,0,0,0,0,0,0,0,0,0,0,0,0,0,0,0~
,0,0,0,0,0,0,0,0,0)';$S;BIDI;
    'MGA_CHECK7':'(0,0,0,0,0,0,AR3,0,0,0,0,0,0,0,0,0,0,0,0,0,0,0,0,0,0,0,0,0,0,0~
,0,0,0,0,0,0,0,0,0,0)';$S;BIDI;
    'MGA_CA2':'(0,0,0,0,0,0,AY4,0,0,0,0,0,0,0,0,0,0,0,0,0,0,0,0,0,0,0,0,0,0,0,0,~
0,0,0,0,0,0,0,0,0)';$S;OUT;
    'MGA1_RSP_L':'(0,0,0,0,0,0,BP4,0,0,0,0,0,0,0,0,0,0,0,0,0,0,0,0,0,0,0,0,0,0,0~
,0,0,0,0,0,0,0,0,0,0)';$S;IN;
    'MGA0_RSP_L':'(0,0,0,0,0,0,BN3,0,0,0,0,0,0,0,0,0,0,0,0,0,0,0,0,0,0,0,0,0,0,0~
,0,0,0,0,0,0,0,0,0,0)';$S;IN;
    'MGB_DATA22':'(0,0,0,0,0,0,CW2,0,0,0,0,0,0,0,0,0,0,0,0,0,0,0,0,0,0,0,0,0,0,0~
,0,0,0,0,0,0,0,0,0,0)';$S;BIDI;
    'MGB_DATA11':'(0,0,0,0,0,0,CK4,0,0,0,0,0,0,0,0,0,0,0,0,0,0,0,0,0,0,0,0,0,0,0~
,0,0,0,0,0,0,0,0,0,0)';$S;BIDI;
    'MGB_DATA7':'(0,0,0,0,0,0,CH4,0,0,0,0,0,0,0,0,0,0,0,0,0,0,0,0,0,0,0,0,0,0,0,~
0,0,0,0,0,0,0,0,0,0)';$S;BIDI;
    'MGB_CHECK2':'(0,0,0,0,0,0,CA2,0,0,0,0,0,0,0,0,0,0,0,0,0,0,0,0,0,0,0,0,0,0,0~
,0,0,0,0,0,0,0,0,0,0)';$S;BIDI;
    'MGB_CA2':'(0,0,0,0,0,0,BH2,0,0,0,0,0,0,0,0,0,0,0,0,0,0,0,0,0,0,0,0,0,0,0,0,~
0,0,0,0,0,0,0,0,0)';$S;OUT;
    'MGA_DQS_L4':'(0,0,0,0,0,0,AM2,0,0,0,0,0,0,0,0,0,0,0,0,0,0,0,0,0,0,0,0,0,0,0~
,0,0,0,0,0,0,0,0,0,0)';$S;BIDI;
    'MGA_DQS_H0':'(0,0,0,0,0,0,G2,0,0,0,0,0,0,0,0,0,0,0,0,0,0,0,0,0,0,0,0,0,0,0,~
0,0,0,0,0,0,0,0,0,0)';$S;BIDI;
    'MGA_DATA28':'(0,0,0,0,0,0,AG2,0,0,0,0,0,0,0,0,0,0,0,0,0,0,0,0,0,0,0,0,0,0,0~
,0,0,0,0,0,0,0,0,0,0)';$S;BIDI;
    'MGA_DATA17':'(0,0,0,0,0,0,V4,0,0,0,0,0,0,0,0,0,0,0,0,0,0,0,0,0,0,0,0,0,0,0,~
0,0,0,0,0,0,0,0,0,0)';$S;BIDI;
    'MGA_DATA7':'(0,0,0,0,0,0,L3,0,0,0,0,0,0,0,0,0,0,0,0,0,0,0,0,0,0,0,0,0,0,0,0~
,0,0,0,0,0,0,0,0,0)';$S;BIDI;
    'MGA_CA3':'(0,0,0,0,0,0,BA3,0,0,0,0,0,0,0,0,0,0,0,0,0,0,0,0,0,0,0,0,0,0,0,0,~
0,0,0,0,0,0,0,0,0)';$S;OUT;
    'MGB_DATA23':'(0,0,0,0,0,0,CY4,0,0,0,0,0,0,0,0,0,0,0,0,0,0,0,0,0,0,0,0,0,0,0~
,0,0,0,0,0,0,0,0,0,0)';$S;BIDI;
    'MGB_DATA12':'(0,0,0,0,0,0,CM2,0,0,0,0,0,0,0,0,0,0,0,0,0,0,0,0,0,0,0,0,0,0,0~
,0,0,0,0,0,0,0,0,0,0)';$S;BIDI;
    'MGB_DATA8':'(0,0,0,0,0,0,CH2,0,0,0,0,0,0,0,0,0,0,0,0,0,0,0,0,0,0,0,0,0,0,0,~
0,0,0,0,0,0,0,0,0,0)';$S;BIDI;
    'MGB_CHECK3':'(0,0,0,0,0,0,CB4,0,0,0,0,0,0,0,0,0,0,0,0,0,0,0,0,0,0,0,0,0,0,0~
,0,0,0,0,0,0,0,0,0,0)';$S;BIDI;
    'MGB_CA3':'(0,0,0,0,0,0,BJ2,0,0,0,0,0,0,0,0,0,0,0,0,0,0,0,0,0,0,0,0,0,0,0,0,~
0,0,0,0,0,0,0,0,0)';$S;OUT;
    'MGA_DQS_L5':'(0,0,0,0,0,0,H4,0,0,0,0,0,0,0,0,0,0,0,0,0,0,0,0,0,0,0,0,0,0,0,~
0,0,0,0,0,0,0,0,0,0)';$S;BIDI;
    'MGA_DQS_H1':'(0,0,0,0,0,0,N2,0,0,0,0,0,0,0,0,0,0,0,0,0,0,0,0,0,0,0,0,0,0,0,~
0,0,0,0,0,0,0,0,0,0)';$S;BIDI;
    'MGA_DATA29':'(0,0,0,0,0,0,AH4,0,0,0,0,0,0,0,0,0,0,0,0,0,0,0,0,0,0,0,0,0,0,0~
,0,0,0,0,0,0,0,0,0,0)';$S;BIDI;
    'MGA_DATA18':'(0,0,0,0,0,0,V2,0,0,0,0,0,0,0,0,0,0,0,0,0,0,0,0,0,0,0,0,0,0,0,~
0,0,0,0,0,0,0,0,0,0)';$S;BIDI;
    'MGA_DATA8':'(0,0,0,0,0,0,L2,0,0,0,0,0,0,0,0,0,0,0,0,0,0,0,0,0,0,0,0,0,0,0,0~
,0,0,0,0,0,0,0,0,0)';$S;BIDI;
    'MGA_CA4':'(0,0,0,0,0,0,BA2,0,0,0,0,0,0,0,0,0,0,0,0,0,0,0,0,0,0,0,0,0,0,0,0,~
0,0,0,0,0,0,0,0,0)';$S;OUT;
    'MGB_DQS_L0':'(0,0,0,0,0,0,CE2,0,0,0,0,0,0,0,0,0,0,0,0,0,0,0,0,0,0,0,0,0,0,0~
,0,0,0,0,0,0,0,0,0,0)';$S;BIDI;
    'MGB_DATA24':'(0,0,0,0,0,0,CY2,0,0,0,0,0,0,0,0,0,0,0,0,0,0,0,0,0,0,0,0,0,0,0~
,0,0,0,0,0,0,0,0,0,0)';$S;BIDI;
    'MGB_DATA13':'(0,0,0,0,0,0,CN3,0,0,0,0,0,0,0,0,0,0,0,0,0,0,0,0,0,0,0,0,0,0,0~
,0,0,0,0,0,0,0,0,0,0)';$S;BIDI;
    'MGB_DATA9':'(0,0,0,0,0,0,CJ3,0,0,0,0,0,0,0,0,0,0,0,0,0,0,0,0,0,0,0,0,0,0,0,~
0,0,0,0,0,0,0,0,0,0)';$S;BIDI;
    'MGB_CHECK4':'(0,0,0,0,0,0,BT2,0,0,0,0,0,0,0,0,0,0,0,0,0,0,0,0,0,0,0,0,0,0,0~
,0,0,0,0,0,0,0,0,0,0)';$S;BIDI;
    'MGB_CA4':'(0,0,0,0,0,0,BJ3,0,0,0,0,0,0,0,0,0,0,0,0,0,0,0,0,0,0,0,0,0,0,0,0,~
0,0,0,0,0,0,0,0,0)';$S;OUT;
    'MGA_DQS_L6':'(0,0,0,0,0,0,P4,0,0,0,0,0,0,0,0,0,0,0,0,0,0,0,0,0,0,0,0,0,0,0,~
0,0,0,0,0,0,0,0,0,0)';$S;BIDI;
    'MGA_DQS_H2':'(0,0,0,0,0,0,W2,0,0,0,0,0,0,0,0,0,0,0,0,0,0,0,0,0,0,0,0,0,0,0,~
0,0,0,0,0,0,0,0,0,0)';$S;BIDI;
    'MGA_DATA19':'(0,0,0,0,0,0,W3,0,0,0,0,0,0,0,0,0,0,0,0,0,0,0,0,0,0,0,0,0,0,0,~
0,0,0,0,0,0,0,0,0,0)';$S;BIDI;
    'MGA_DATA9':'(0,0,0,0,0,0,M4,0,0,0,0,0,0,0,0,0,0,0,0,0,0,0,0,0,0,0,0,0,0,0,0~
,0,0,0,0,0,0,0,0,0)';$S;BIDI;
    'MGA_CA5':'(0,0,0,0,0,0,BB2,0,0,0,0,0,0,0,0,0,0,0,0,0,0,0,0,0,0,0,0,0,0,0,0,~
0,0,0,0,0,0,0,0,0)';$S;OUT;
    'MGB_DQS_L1':'(0,0,0,0,0,0,CL2,0,0,0,0,0,0,0,0,0,0,0,0,0,0,0,0,0,0,0,0,0,0,0~
,0,0,0,0,0,0,0,0,0,0)';$S;BIDI;
    'MGB_DATA25':'(0,0,0,0,0,0,DA3,0,0,0,0,0,0,0,0,0,0,0,0,0,0,0,0,0,0,0,0,0,0,0~
,0,0,0,0,0,0,0,0,0,0)';$S;BIDI;
    'MGB_DATA14':'(0,0,0,0,0,0,CN2,0,0,0,0,0,0,0,0,0,0,0,0,0,0,0,0,0,0,0,0,0,0,0~
,0,0,0,0,0,0,0,0,0,0)';$S;BIDI;
    'MGB_CHECK5':'(0,0,0,0,0,0,BU3,0,0,0,0,0,0,0,0,0,0,0,0,0,0,0,0,0,0,0,0,0,0,0~
,0,0,0,0,0,0,0,0,0,0)';$S;BIDI;
    'MGB_CA5':'(0,0,0,0,0,0,BK4,0,0,0,0,0,0,0,0,0,0,0,0,0,0,0,0,0,0,0,0,0,0,0,0,~
0,0,0,0,0,0,0,0,0)';$S;OUT;
    'MGA_DQS_L7':'(0,0,0,0,0,0,Y4,0,0,0,0,0,0,0,0,0,0,0,0,0,0,0,0,0,0,0,0,0,0,0,~
0,0,0,0,0,0,0,0,0,0)';$S;BIDI;
    'MGA_DQS_H3':'(0,0,0,0,0,0,AE2,0,0,0,0,0,0,0,0,0,0,0,0,0,0,0,0,0,0,0,0,0,0,0~
,0,0,0,0,0,0,0,0,0,0)';$S;BIDI;
    'MGA_CA6':'(0,0,0,0,0,0,BB4,0,0,0,0,0,0,0,0,0,0,0,0,0,0,0,0,0,0,0,0,0,0,0,0,~
0,0,0,0,0,0,0,0,0)';$S;OUT;
    'MGB_DQS_L2':'(0,0,0,0,0,0,CU2,0,0,0,0,0,0,0,0,0,0,0,0,0,0,0,0,0,0,0,0,0,0,0~
,0,0,0,0,0,0,0,0,0,0)';$S;BIDI;
    'MGB_DATA26':'(0,0,0,0,0,0,DA2,0,0,0,0,0,0,0,0,0,0,0,0,0,0,0,0,0,0,0,0,0,0,0~
,0,0,0,0,0,0,0,0,0,0)';$S;BIDI;
    'MGB_DATA15':'(0,0,0,0,0,0,CP4,0,0,0,0,0,0,0,0,0,0,0,0,0,0,0,0,0,0,0,0,0,0,0~
,0,0,0,0,0,0,0,0,0,0)';$S;BIDI;
    'MGB_CHECK6':'(0,0,0,0,0,0,BU2,0,0,0,0,0,0,0,0,0,0,0,0,0,0,0,0,0,0,0,0,0,0,0~
,0,0,0,0,0,0,0,0,0,0)';$S;BIDI;
    'MGB_CA6':'(0,0,0,0,0,0,BK2,0,0,0,0,0,0,0,0,0,0,0,0,0,0,0,0,0,0,0,0,0,0,0,0,~
0,0,0,0,0,0,0,0,0)';$S;OUT;
    'MGA_DQS_L8':'(0,0,0,0,0,0,AF4,0,0,0,0,0,0,0,0,0,0,0,0,0,0,0,0,0,0,0,0,0,0,0~
,0,0,0,0,0,0,0,0,0,0)';$S;BIDI;
    'MGA_DQS_H4':'(0,0,0,0,0,0,AL2,0,0,0,0,0,0,0,0,0,0,0,0,0,0,0,0,0,0,0,0,0,0,0~
,0,0,0,0,0,0,0,0,0,0)';$S;BIDI;
    'MGB_DQS_L3':'(0,0,0,0,0,0,DC2,0,0,0,0,0,0,0,0,0,0,0,0,0,0,0,0,0,0,0,0,0,0,0~
,0,0,0,0,0,0,0,0,0,0)';$S;BIDI;
    'MGB_DATA27':'(0,0,0,0,0,0,DB4,0,0,0,0,0,0,0,0,0,0,0,0,0,0,0,0,0,0,0,0,0,0,0~
,0,0,0,0,0,0,0,0,0,0)';$S;BIDI;
    'MGB_DATA16':'(0,0,0,0,0,0,CP2,0,0,0,0,0,0,0,0,0,0,0,0,0,0,0,0,0,0,0,0,0,0,0~
,0,0,0,0,0,0,0,0,0,0)';$S;BIDI;
    'MGB_CHECK7':'(0,0,0,0,0,0,BV4,0,0,0,0,0,0,0,0,0,0,0,0,0,0,0,0,0,0,0,0,0,0,0~
,0,0,0,0,0,0,0,0,0,0)';$S;BIDI;
    'MGB1_RSP_L':'(0,0,0,0,0,0,BR2,0,0,0,0,0,0,0,0,0,0,0,0,0,0,0,0,0,0,0,0,0,0,0~
,0,0,0,0,0,0,0,0,0,0)';$S;IN;
    'MGB0_RSP_L':'(0,0,0,0,0,0,BP2,0,0,0,0,0,0,0,0,0,0,0,0,0,0,0,0,0,0,0,0,0,0,0~
,0,0,0,0,0,0,0,0,0,0)';$S;IN;
    'MGA_DQS_L9':'(0,0,0,0,0,0,AM4,0,0,0,0,0,0,0,0,0,0,0,0,0,0,0,0,0,0,0,0,0,0,0~
,0,0,0,0,0,0,0,0,0,0)';$S;BIDI;
    'MGA_DQS_H5':'(0,0,0,0,0,0,J3,0,0,0,0,0,0,0,0,0,0,0,0,0,0,0,0,0,0,0,0,0,0,0,~
0,0,0,0,0,0,0,0,0,0)';$S;BIDI;
    'MGB_DQS_L4':'(0,0,0,0,0,0,BW3,0,0,0,0,0,0,0,0,0,0,0,0,0,0,0,0,0,0,0,0,0,0,0~
,0,0,0,0,0,0,0,0,0,0)';$S;BIDI;
    'MGB_DQS_H0':'(0,0,0,0,0,0,CD2,0,0,0,0,0,0,0,0,0,0,0,0,0,0,0,0,0,0,0,0,0,0,0~
,0,0,0,0,0,0,0,0,0,0)';$S;BIDI;
    'MGB_DATA28':'(0,0,0,0,0,0,DD2,0,0,0,0,0,0,0,0,0,0,0,0,0,0,0,0,0,0,0,0,0,0,0~
,0,0,0,0,0,0,0,0,0,0)';$S;BIDI;
    'MGB_DATA17':'(0,0,0,0,0,0,CR3,0,0,0,0,0,0,0,0,0,0,0,0,0,0,0,0,0,0,0,0,0,0,0~
,0,0,0,0,0,0,0,0,0,0)';$S;BIDI;
    'MGA_DQS_H6':'(0,0,0,0,0,0,R3,0,0,0,0,0,0,0,0,0,0,0,0,0,0,0,0,0,0,0,0,0,0,0,~
0,0,0,0,0,0,0,0,0,0)';$S;BIDI;
    'MGB_DQS_L5':'(0,0,0,0,0,0,CE3,0,0,0,0,0,0,0,0,0,0,0,0,0,0,0,0,0,0,0,0,0,0,0~
,0,0,0,0,0,0,0,0,0,0)';$S;BIDI;
    'MGB_DQS_H1':'(0,0,0,0,0,0,CK2,0,0,0,0,0,0,0,0,0,0,0,0,0,0,0,0,0,0,0,0,0,0,0~
,0,0,0,0,0,0,0,0,0,0)';$S;BIDI;
    'MGB_DATA29':'(0,0,0,0,0,0,DE3,0,0,0,0,0,0,0,0,0,0,0,0,0,0,0,0,0,0,0,0,0,0,0~
,0,0,0,0,0,0,0,0,0,0)';$S;BIDI;
    'MGB_DATA18':'(0,0,0,0,0,0,CR2,0,0,0,0,0,0,0,0,0,0,0,0,0,0,0,0,0,0,0,0,0,0,0~
,0,0,0,0,0,0,0,0,0,0)';$S;BIDI;
    'MGA_DQS_H7':'(0,0,0,0,0,0,AA3,0,0,0,0,0,0,0,0,0,0,0,0,0,0,0,0,0,0,0,0,0,0,0~
,0,0,0,0,0,0,0,0,0,0)';$S;BIDI;
    'MGA1_CS_L0':'(0,0,0,0,0,0,AV2,0,0,0,0,0,0,0,0,0,0,0,0,0,0,0,0,0,0,0,0,0,0,0~
,0,0,0,0,0,0,0,0,0,0)';$S;OUT;
    'MGA0_CS_L0':'(0,0,0,0,0,0,AU2,0,0,0,0,0,0,0,0,0,0,0,0,0,0,0,0,0,0,0,0,0,0,0~
,0,0,0,0,0,0,0,0,0,0)';$S;OUT;
    'MGB_DQS_L6':'(0,0,0,0,0,0,CL3,0,0,0,0,0,0,0,0,0,0,0,0,0,0,0,0,0,0,0,0,0,0,0~
,0,0,0,0,0,0,0,0,0,0)';$S;BIDI;
    'MGB_DQS_H2':'(0,0,0,0,0,0,CT2,0,0,0,0,0,0,0,0,0,0,0,0,0,0,0,0,0,0,0,0,0,0,0~
,0,0,0,0,0,0,0,0,0,0)';$S;BIDI;
    'MGB_DATA19':'(0,0,0,0,0,0,CT4,0,0,0,0,0,0,0,0,0,0,0,0,0,0,0,0,0,0,0,0,0,0,0~
,0,0,0,0,0,0,0,0,0,0)';$S;BIDI;
    'MGA_DQS_H8':'(0,0,0,0,0,0,AG3,0,0,0,0,0,0,0,0,0,0,0,0,0,0,0,0,0,0,0,0,0,0,0~
,0,0,0,0,0,0,0,0,0,0)';$S;BIDI;
    'MGA_DATA30':'(0,0,0,0,0,0,AH2,0,0,0,0,0,0,0,0,0,0,0,0,0,0,0,0,0,0,0,0,0,0,0~
,0,0,0,0,0,0,0,0,0,0)';$S;BIDI;
    'MGA1_CS_L1':'(0,0,0,0,0,0,AW3,0,0,0,0,0,0,0,0,0,0,0,0,0,0,0,0,0,0,0,0,0,0,0~
,0,0,0,0,0,0,0,0,0,0)';$S;OUT;
    'MGA0_CS_L1':'(0,0,0,0,0,0,AV4,0,0,0,0,0,0,0,0,0,0,0,0,0,0,0,0,0,0,0,0,0,0,0~
,0,0,0,0,0,0,0,0,0,0)';$S;OUT;
    'MGB_DQS_L7':'(0,0,0,0,0,0,CU3,0,0,0,0,0,0,0,0,0,0,0,0,0,0,0,0,0,0,0,0,0,0,0~
,0,0,0,0,0,0,0,0,0,0)';$S;BIDI;
    'MGB_DQS_H3':'(0,0,0,0,0,0,DB2,0,0,0,0,0,0,0,0,0,0,0,0,0,0,0,0,0,0,0,0,0,0,0~
,0,0,0,0,0,0,0,0,0,0)';$S;BIDI;
    'MGA_DQS_H9':'(0,0,0,0,0,0,AN3,0,0,0,0,0,0,0,0,0,0,0,0,0,0,0,0,0,0,0,0,0,0,0~
,0,0,0,0,0,0,0,0,0,0)';$S;BIDI;
    'MGA_DATA31':'(0,0,0,0,0,0,AJ3,0,0,0,0,0,0,0,0,0,0,0,0,0,0,0,0,0,0,0,0,0,0,0~
,0,0,0,0,0,0,0,0,0,0)';$S;BIDI;
    'MGA_DATA20':'(0,0,0,0,0,0,AA2,0,0,0,0,0,0,0,0,0,0,0,0,0,0,0,0,0,0,0,0,0,0,0~
,0,0,0,0,0,0,0,0,0,0)';$S;BIDI;
    'MGA_CHECK0':'(0,0,0,0,0,0,AJ2,0,0,0,0,0,0,0,0,0,0,0,0,0,0,0,0,0,0,0,0,0,0,0~
,0,0,0,0,0,0,0,0,0,0)';$S;BIDI;
    'MGB_DQS_L8':'(0,0,0,0,0,0,DC3,0,0,0,0,0,0,0,0,0,0,0,0,0,0,0,0,0,0,0,0,0,0,0~
,0,0,0,0,0,0,0,0,0,0)';$S;BIDI;
    'MGB_DQS_H4':'(0,0,0,0,0,0,BY4,0,0,0,0,0,0,0,0,0,0,0,0,0,0,0,0,0,0,0,0,0,0,0~
,0,0,0,0,0,0,0,0,0,0)';$S;BIDI;
    'MGB_DATA0':'(0,0,0,0,0,0,CB2,0,0,0,0,0,0,0,0,0,0,0,0,0,0,0,0,0,0,0,0,0,0,0,~
0,0,0,0,0,0,0,0,0,0)';$S;BIDI;
    'MGA_DATA21':'(0,0,0,0,0,0,AB4,0,0,0,0,0,0,0,0,0,0,0,0,0,0,0,0,0,0,0,0,0,0,0~
,0,0,0,0,0,0,0,0,0,0)';$S;BIDI;
    'MGA_DATA10':'(0,0,0,0,0,0,M2,0,0,0,0,0,0,0,0,0,0,0,0,0,0,0,0,0,0,0,0,0,0,0,~
0,0,0,0,0,0,0,0,0,0)';$S;BIDI;
    'MGA_DATA0':'(0,0,0,0,0,0,E2,0,0,0,0,0,0,0,0,0,0,0,0,0,0,0,0,0,0,0,0,0,0,0,0~
,0,0,0,0,0,0,0,0,0)';$S;BIDI;
    'MGA_CHECK1':'(0,0,0,0,0,0,AK4,0,0,0,0,0,0,0,0,0,0,0,0,0,0,0,0,0,0,0,0,0,0,0~
,0,0,0,0,0,0,0,0,0,0)';$S;BIDI;
    'MGB_PAR':'(0,0,0,0,0,0,BL3,0,0,0,0,0,0,0,0,0,0,0,0,0,0,0,0,0,0,0,0,0,0,0,0,~
0,0,0,0,0,0,0,0,0)';$S;OUT;
    'MGB_DQS_H9':'(0,0,0,0,0,0,BV2,0,0,0,0,0,0,0,0,0,0,0,0,0,0,0,0,0,0,0,0,0,0,0~
,0,0,0,0,0,0,0,0,0,0)';$S;BIDI;
    'MGA_PAR':'(0,0,0,0,0,0,BC3,0,0,0,0,0,0,0,0,0,0,0,0,0,0,0,0,0,0,0,0,0,0,0,0,~
0,0,0,0,0,0,0,0,0)';$S;OUT;
    'MG0_CLK_H':'(0,0,0,0,0,0,BC2,0,0,0,0,0,0,0,0,0,0,0,0,0,0,0,0,0,0,0,0,0,0,0,~
0,0,0,0,0,0,0,0,0,0)';$S;OUT;
    'MG0_CLK_L':'(0,0,0,0,0,0,BD2,0,0,0,0,0,0,0,0,0,0,0,0,0,0,0,0,0,0,0,0,0,0,0,~
0,0,0,0,0,0,0,0,0,0)';$S;OUT;
    'MG1_CLK_H':'(0,0,0,0,0,0,BF2,0,0,0,0,0,0,0,0,0,0,0,0,0,0,0,0,0,0,0,0,0,0,0,~
0,0,0,0,0,0,0,0,0,0)';$S;OUT;
    'MG1_CLK_L':'(0,0,0,0,0,0,BG2,0,0,0,0,0,0,0,0,0,0,0,0,0,0,0,0,0,0,0,0,0,0,0,~
0,0,0,0,0,0,0,0,0,0)';$S;OUT;
    'TEST39G':'(0,0,0,0,0,0,BF4,0,0,0,0,0,0,0,0,0,0,0,0,0,0,0,0,0,0,0,0,0,0,0,0,~
0,0,0,0,0,0,0,0,0)';$S;OUT;
    'MH_ALERT_L':'(0,0,0,0,0,0,0,AT14,0,0,0,0,0,0,0,0,0,0,0,0,0,0,0,0,0,0,0,0,0,~
0,0,0,0,0,0,0,0,0,0,0)';$S;IN;
    'MH_RESET_L':'(0,0,0,0,0,0,0,AU14,0,0,0,0,0,0,0,0,0,0,0,0,0,0,0,0,0,0,0,0,0,~
0,0,0,0,0,0,0,0,0,0,0)';$S;OUT;
    'MHB_DATA31':'(0,0,0,0,0,0,0,DF14,0,0,0,0,0,0,0,0,0,0,0,0,0,0,0,0,0,0,0,0,0,~
0,0,0,0,0,0,0,0,0,0,0)';$S;BIDI;
    'MHB_DATA20':'(0,0,0,0,0,0,0,CV13,0,0,0,0,0,0,0,0,0,0,0,0,0,0,0,0,0,0,0,0,0,~
0,0,0,0,0,0,0,0,0,0,0)';$S;BIDI;
    'MHB_CHECK0':'(0,0,0,0,0,0,0,BY13,0,0,0,0,0,0,0,0,0,0,0,0,0,0,0,0,0,0,0,0,0,~
0,0,0,0,0,0,0,0,0,0,0)';$S;BIDI;
    'MHB1_CS_L1':'(0,0,0,0,0,0,0,BM13,0,0,0,0,0,0,0,0,0,0,0,0,0,0,0,0,0,0,0,0,0,~
0,0,0,0,0,0,0,0,0,0,0)';$S;OUT;
    'MHA_DQS_L2':'(0,0,0,0,0,0,0,Y13,0,0,0,0,0,0,0,0,0,0,0,0,0,0,0,0,0,0,0,0,0,0~
,0,0,0,0,0,0,0,0,0,0)';$S;BIDI;
    'MHA_DATA26':'(0,0,0,0,0,0,0,AD13,0,0,0,0,0,0,0,0,0,0,0,0,0,0,0,0,0,0,0,0,0,~
0,0,0,0,0,0,0,0,0,0,0)';$S;BIDI;
    'MHA_DATA15':'(0,0,0,0,0,0,0,U14,0,0,0,0,0,0,0,0,0,0,0,0,0,0,0,0,0,0,0,0,0,0~
,0,0,0,0,0,0,0,0,0,0)';$S;BIDI;
    'MHA_CHECK6':'(0,0,0,0,0,0,0,AP13,0,0,0,0,0,0,0,0,0,0,0,0,0,0,0,0,0,0,0,0,0,~
0,0,0,0,0,0,0,0,0,0,0)';$S;BIDI;
    'MHB_DATA21':'(0,0,0,0,0,0,0,CW14,0,0,0,0,0,0,0,0,0,0,0,0,0,0,0,0,0,0,0,0,0,~
0,0,0,0,0,0,0,0,0,0,0)';$S;BIDI;
    'MHB_DATA10':'(0,0,0,0,0,0,0,CJ12,0,0,0,0,0,0,0,0,0,0,0,0,0,0,0,0,0,0,0,0,0,~
0,0,0,0,0,0,0,0,0,0,0)';$S;BIDI;
    'MHB_CHECK1':'(0,0,0,0,0,0,0,CA14,0,0,0,0,0,0,0,0,0,0,0,0,0,0,0,0,0,0,0,0,0,~
0,0,0,0,0,0,0,0,0,0,0)';$S;BIDI;
    'MHA_DQS_L3':'(0,0,0,0,0,0,0,AF13,0,0,0,0,0,0,0,0,0,0,0,0,0,0,0,0,0,0,0,0,0,~
0,0,0,0,0,0,0,0,0,0,0)';$S;BIDI;
    'MHA_DATA27':'(0,0,0,0,0,0,0,AE14,0,0,0,0,0,0,0,0,0,0,0,0,0,0,0,0,0,0,0,0,0,~
0,0,0,0,0,0,0,0,0,0,0)';$S;BIDI;
    'MHA_DATA16':'(0,0,0,0,0,0,0,U12,0,0,0,0,0,0,0,0,0,0,0,0,0,0,0,0,0,0,0,0,0,0~
,0,0,0,0,0,0,0,0,0,0)';$S;BIDI;
    'MHA_CHECK7':'(0,0,0,0,0,0,0,AR14,0,0,0,0,0,0,0,0,0,0,0,0,0,0,0,0,0,0,0,0,0,~
0,0,0,0,0,0,0,0,0,0,0)';$S;BIDI;
    'MHA0_RSP_L':'(0,0,0,0,0,0,0,BN14,0,0,0,0,0,0,0,0,0,0,0,0,0,0,0,0,0,0,0,0,0,~
0,0,0,0,0,0,0,0,0,0,0)';$S;IN;
    'MHB_DATA22':'(0,0,0,0,0,0,0,CW12,0,0,0,0,0,0,0,0,0,0,0,0,0,0,0,0,0,0,0,0,0,~
0,0,0,0,0,0,0,0,0,0,0)';$S;BIDI;
    'MHB_DATA11':'(0,0,0,0,0,0,0,CK14,0,0,0,0,0,0,0,0,0,0,0,0,0,0,0,0,0,0,0,0,0,~
0,0,0,0,0,0,0,0,0,0,0)';$S;BIDI;
    'MHB_CHECK2':'(0,0,0,0,0,0,0,CA12,0,0,0,0,0,0,0,0,0,0,0,0,0,0,0,0,0,0,0,0,0,~
0,0,0,0,0,0,0,0,0,0,0)';$S;BIDI;
    'MHA_DQS_L4':'(0,0,0,0,0,0,0,AM13,0,0,0,0,0,0,0,0,0,0,0,0,0,0,0,0,0,0,0,0,0,~
0,0,0,0,0,0,0,0,0,0,0)';$S;BIDI;
    'MHA_DQS_H0':'(0,0,0,0,0,0,0,G12,0,0,0,0,0,0,0,0,0,0,0,0,0,0,0,0,0,0,0,0,0,0~
,0,0,0,0,0,0,0,0,0,0)';$S;BIDI;
    'MHA_DATA28':'(0,0,0,0,0,0,0,AG12,0,0,0,0,0,0,0,0,0,0,0,0,0,0,0,0,0,0,0,0,0,~
0,0,0,0,0,0,0,0,0,0,0)';$S;BIDI;
    'MHA_DATA17':'(0,0,0,0,0,0,0,V14,0,0,0,0,0,0,0,0,0,0,0,0,0,0,0,0,0,0,0,0,0,0~
,0,0,0,0,0,0,0,0,0,0)';$S;BIDI;
    'MHA_CA0':'(0,0,0,0,0,0,0,AW12,0,0,0,0,0,0,0,0,0,0,0,0,0,0,0,0,0,0,0,0,0,0,0~
,0,0,0,0,0,0,0,0,0)';$S;OUT;
    'MHA1_RSP_L':'(0,0,0,0,0,0,0,BP14,0,0,0,0,0,0,0,0,0,0,0,0,0,0,0,0,0,0,0,0,0,~
0,0,0,0,0,0,0,0,0,0,0)';$S;IN;
    'MHB_DATA23':'(0,0,0,0,0,0,0,CY14,0,0,0,0,0,0,0,0,0,0,0,0,0,0,0,0,0,0,0,0,0,~
0,0,0,0,0,0,0,0,0,0,0)';$S;BIDI;
    'MHB_DATA12':'(0,0,0,0,0,0,0,CM13,0,0,0,0,0,0,0,0,0,0,0,0,0,0,0,0,0,0,0,0,0,~
0,0,0,0,0,0,0,0,0,0,0)';$S;BIDI;
    'MHB_CHECK3':'(0,0,0,0,0,0,0,CB14,0,0,0,0,0,0,0,0,0,0,0,0,0,0,0,0,0,0,0,0,0,~
0,0,0,0,0,0,0,0,0,0,0)';$S;BIDI;
    'MHB_CA0':'(0,0,0,0,0,0,0,BG14,0,0,0,0,0,0,0,0,0,0,0,0,0,0,0,0,0,0,0,0,0,0,0~
,0,0,0,0,0,0,0,0,0)';$S;OUT;
    'MHA_DQS_L5':'(0,0,0,0,0,0,0,H14,0,0,0,0,0,0,0,0,0,0,0,0,0,0,0,0,0,0,0,0,0,0~
,0,0,0,0,0,0,0,0,0,0)';$S;BIDI;
    'MHA_DQS_H1':'(0,0,0,0,0,0,0,N12,0,0,0,0,0,0,0,0,0,0,0,0,0,0,0,0,0,0,0,0,0,0~
,0,0,0,0,0,0,0,0,0,0)';$S;BIDI;
    'MHA_DATA29':'(0,0,0,0,0,0,0,AH14,0,0,0,0,0,0,0,0,0,0,0,0,0,0,0,0,0,0,0,0,0,~
0,0,0,0,0,0,0,0,0,0,0)';$S;BIDI;
    'MHA_DATA18':'(0,0,0,0,0,0,0,V13,0,0,0,0,0,0,0,0,0,0,0,0,0,0,0,0,0,0,0,0,0,0~
,0,0,0,0,0,0,0,0,0,0)';$S;BIDI;
    'MHA_CA1':'(0,0,0,0,0,0,0,AY13,0,0,0,0,0,0,0,0,0,0,0,0,0,0,0,0,0,0,0,0,0,0,0~
,0,0,0,0,0,0,0,0,0)';$S;OUT;
    'MHB_DQS_L0':'(0,0,0,0,0,0,0,CE12,0,0,0,0,0,0,0,0,0,0,0,0,0,0,0,0,0,0,0,0,0,~
0,0,0,0,0,0,0,0,0,0,0)';$S;BIDI;
    'MHB_DATA24':'(0,0,0,0,0,0,0,CY13,0,0,0,0,0,0,0,0,0,0,0,0,0,0,0,0,0,0,0,0,0,~
0,0,0,0,0,0,0,0,0,0,0)';$S;BIDI;
    'MHB_DATA13':'(0,0,0,0,0,0,0,CN14,0,0,0,0,0,0,0,0,0,0,0,0,0,0,0,0,0,0,0,0,0,~
0,0,0,0,0,0,0,0,0,0,0)';$S;BIDI;
    'MHB_CHECK4':'(0,0,0,0,0,0,0,BT13,0,0,0,0,0,0,0,0,0,0,0,0,0,0,0,0,0,0,0,0,0,~
0,0,0,0,0,0,0,0,0,0,0)';$S;BIDI;
    'MHB_CA1':'(0,0,0,0,0,0,0,BH14,0,0,0,0,0,0,0,0,0,0,0,0,0,0,0,0,0,0,0,0,0,0,0~
,0,0,0,0,0,0,0,0,0)';$S;OUT;
    'MHA_DQS_L6':'(0,0,0,0,0,0,0,P14,0,0,0,0,0,0,0,0,0,0,0,0,0,0,0,0,0,0,0,0,0,0~
,0,0,0,0,0,0,0,0,0,0)';$S;BIDI;
    'MHA_DQS_H2':'(0,0,0,0,0,0,0,W12,0,0,0,0,0,0,0,0,0,0,0,0,0,0,0,0,0,0,0,0,0,0~
,0,0,0,0,0,0,0,0,0,0)';$S;BIDI;
    'MHA_DATA19':'(0,0,0,0,0,0,0,W14,0,0,0,0,0,0,0,0,0,0,0,0,0,0,0,0,0,0,0,0,0,0~
,0,0,0,0,0,0,0,0,0,0)';$S;BIDI;
    'MHA_CA2':'(0,0,0,0,0,0,0,AY14,0,0,0,0,0,0,0,0,0,0,0,0,0,0,0,0,0,0,0,0,0,0,0~
,0,0,0,0,0,0,0,0,0)';$S;OUT;
    'MHB_DQS_L1':'(0,0,0,0,0,0,0,CL12,0,0,0,0,0,0,0,0,0,0,0,0,0,0,0,0,0,0,0,0,0,~
0,0,0,0,0,0,0,0,0,0,0)';$S;BIDI;
    'MHB_DATA25':'(0,0,0,0,0,0,0,DA14,0,0,0,0,0,0,0,0,0,0,0,0,0,0,0,0,0,0,0,0,0,~
0,0,0,0,0,0,0,0,0,0,0)';$S;BIDI;
    'MHB_DATA14':'(0,0,0,0,0,0,0,CN12,0,0,0,0,0,0,0,0,0,0,0,0,0,0,0,0,0,0,0,0,0,~
0,0,0,0,0,0,0,0,0,0,0)';$S;BIDI;
    'MHB_DATA0':'(0,0,0,0,0,0,0,CB13,0,0,0,0,0,0,0,0,0,0,0,0,0,0,0,0,0,0,0,0,0,0~
,0,0,0,0,0,0,0,0,0,0)';$S;BIDI;
    'MHB_CHECK5':'(0,0,0,0,0,0,0,BU14,0,0,0,0,0,0,0,0,0,0,0,0,0,0,0,0,0,0,0,0,0,~
0,0,0,0,0,0,0,0,0,0,0)';$S;BIDI;
    'MHB_CA2':'(0,0,0,0,0,0,0,BH13,0,0,0,0,0,0,0,0,0,0,0,0,0,0,0,0,0,0,0,0,0,0,0~
,0,0,0,0,0,0,0,0,0)';$S;OUT;
    'MHA_DQS_L7':'(0,0,0,0,0,0,0,Y14,0,0,0,0,0,0,0,0,0,0,0,0,0,0,0,0,0,0,0,0,0,0~
,0,0,0,0,0,0,0,0,0,0)';$S;BIDI;
    'MHA_DQS_H3':'(0,0,0,0,0,0,0,AE12,0,0,0,0,0,0,0,0,0,0,0,0,0,0,0,0,0,0,0,0,0,~
0,0,0,0,0,0,0,0,0,0,0)';$S;BIDI;
    'MHA_DATA0':'(0,0,0,0,0,0,0,E12,0,0,0,0,0,0,0,0,0,0,0,0,0,0,0,0,0,0,0,0,0,0,~
0,0,0,0,0,0,0,0,0,0)';$S;BIDI;
    'MHA_CA3':'(0,0,0,0,0,0,0,BA14,0,0,0,0,0,0,0,0,0,0,0,0,0,0,0,0,0,0,0,0,0,0,0~
,0,0,0,0,0,0,0,0,0)';$S;OUT;
    'MHB_DQS_L2':'(0,0,0,0,0,0,0,CU12,0,0,0,0,0,0,0,0,0,0,0,0,0,0,0,0,0,0,0,0,0,~
0,0,0,0,0,0,0,0,0,0,0)';$S;BIDI;
    'MHB_DATA26':'(0,0,0,0,0,0,0,DA12,0,0,0,0,0,0,0,0,0,0,0,0,0,0,0,0,0,0,0,0,0,~
0,0,0,0,0,0,0,0,0,0,0)';$S;BIDI;
    'MHB_DATA15':'(0,0,0,0,0,0,0,CP14,0,0,0,0,0,0,0,0,0,0,0,0,0,0,0,0,0,0,0,0,0,~
0,0,0,0,0,0,0,0,0,0,0)';$S;BIDI;
    'MHB_DATA1':'(0,0,0,0,0,0,0,CC14,0,0,0,0,0,0,0,0,0,0,0,0,0,0,0,0,0,0,0,0,0,0~
,0,0,0,0,0,0,0,0,0,0)';$S;BIDI;
    'MHB_CHECK6':'(0,0,0,0,0,0,0,BU12,0,0,0,0,0,0,0,0,0,0,0,0,0,0,0,0,0,0,0,0,0,~
0,0,0,0,0,0,0,0,0,0,0)';$S;BIDI;
    'MHB_CA3':'(0,0,0,0,0,0,0,BJ12,0,0,0,0,0,0,0,0,0,0,0,0,0,0,0,0,0,0,0,0,0,0,0~
,0,0,0,0,0,0,0,0,0)';$S;OUT;
    'MHA_DQS_L8':'(0,0,0,0,0,0,0,AF14,0,0,0,0,0,0,0,0,0,0,0,0,0,0,0,0,0,0,0,0,0,~
0,0,0,0,0,0,0,0,0,0,0)';$S;BIDI;
    'MHA_DQS_H4':'(0,0,0,0,0,0,0,AL12,0,0,0,0,0,0,0,0,0,0,0,0,0,0,0,0,0,0,0,0,0,~
0,0,0,0,0,0,0,0,0,0,0)';$S;BIDI;
    'MHA_DATA1':'(0,0,0,0,0,0,0,F14,0,0,0,0,0,0,0,0,0,0,0,0,0,0,0,0,0,0,0,0,0,0,~
0,0,0,0,0,0,0,0,0,0)';$S;BIDI;
    'MHA_CA4':'(0,0,0,0,0,0,0,BA12,0,0,0,0,0,0,0,0,0,0,0,0,0,0,0,0,0,0,0,0,0,0,0~
,0,0,0,0,0,0,0,0,0)';$S;OUT;
    'MHB_DQS_L3':'(0,0,0,0,0,0,0,DC12,0,0,0,0,0,0,0,0,0,0,0,0,0,0,0,0,0,0,0,0,0,~
0,0,0,0,0,0,0,0,0,0,0)';$S;BIDI;
    'MHB_DATA27':'(0,0,0,0,0,0,0,DB14,0,0,0,0,0,0,0,0,0,0,0,0,0,0,0,0,0,0,0,0,0,~
0,0,0,0,0,0,0,0,0,0,0)';$S;BIDI;
    'MHB_DATA16':'(0,0,0,0,0,0,0,CP13,0,0,0,0,0,0,0,0,0,0,0,0,0,0,0,0,0,0,0,0,0,~
0,0,0,0,0,0,0,0,0,0,0)';$S;BIDI;
    'MHB_DATA2':'(0,0,0,0,0,0,0,CC12,0,0,0,0,0,0,0,0,0,0,0,0,0,0,0,0,0,0,0,0,0,0~
,0,0,0,0,0,0,0,0,0,0)';$S;BIDI;
    'MHB_CHECK7':'(0,0,0,0,0,0,0,BV14,0,0,0,0,0,0,0,0,0,0,0,0,0,0,0,0,0,0,0,0,0,~
0,0,0,0,0,0,0,0,0,0,0)';$S;BIDI;
    'MHB_CA4':'(0,0,0,0,0,0,0,BJ14,0,0,0,0,0,0,0,0,0,0,0,0,0,0,0,0,0,0,0,0,0,0,0~
,0,0,0,0,0,0,0,0,0)';$S;OUT;
    'MHB0_RSP_L':'(0,0,0,0,0,0,0,BP13,0,0,0,0,0,0,0,0,0,0,0,0,0,0,0,0,0,0,0,0,0,~
0,0,0,0,0,0,0,0,0,0,0)';$S;IN;
    'MHA_DQS_L9':'(0,0,0,0,0,0,0,AM14,0,0,0,0,0,0,0,0,0,0,0,0,0,0,0,0,0,0,0,0,0,~
0,0,0,0,0,0,0,0,0,0,0)';$S;BIDI;
    'MHA_DQS_H5':'(0,0,0,0,0,0,0,J14,0,0,0,0,0,0,0,0,0,0,0,0,0,0,0,0,0,0,0,0,0,0~
,0,0,0,0,0,0,0,0,0,0)';$S;BIDI;
    'MHA_DATA2':'(0,0,0,0,0,0,0,F13,0,0,0,0,0,0,0,0,0,0,0,0,0,0,0,0,0,0,0,0,0,0,~
0,0,0,0,0,0,0,0,0,0)';$S;BIDI;
    'MHA_CA5':'(0,0,0,0,0,0,0,BB13,0,0,0,0,0,0,0,0,0,0,0,0,0,0,0,0,0,0,0,0,0,0,0~
,0,0,0,0,0,0,0,0,0)';$S;OUT;
    'MHB_DQS_L4':'(0,0,0,0,0,0,0,BW14,0,0,0,0,0,0,0,0,0,0,0,0,0,0,0,0,0,0,0,0,0,~
0,0,0,0,0,0,0,0,0,0,0)';$S;BIDI;
    'MHB_DQS_H0':'(0,0,0,0,0,0,0,CD13,0,0,0,0,0,0,0,0,0,0,0,0,0,0,0,0,0,0,0,0,0,~
0,0,0,0,0,0,0,0,0,0,0)';$S;BIDI;
    'MHB_DATA28':'(0,0,0,0,0,0,0,DD13,0,0,0,0,0,0,0,0,0,0,0,0,0,0,0,0,0,0,0,0,0,~
0,0,0,0,0,0,0,0,0,0,0)';$S;BIDI;
    'MHB_DATA17':'(0,0,0,0,0,0,0,CR14,0,0,0,0,0,0,0,0,0,0,0,0,0,0,0,0,0,0,0,0,0,~
0,0,0,0,0,0,0,0,0,0,0)';$S;BIDI;
    'MHB_DATA3':'(0,0,0,0,0,0,0,CD14,0,0,0,0,0,0,0,0,0,0,0,0,0,0,0,0,0,0,0,0,0,0~
,0,0,0,0,0,0,0,0,0,0)';$S;BIDI;
    'MHB_CA5':'(0,0,0,0,0,0,0,BK14,0,0,0,0,0,0,0,0,0,0,0,0,0,0,0,0,0,0,0,0,0,0,0~
,0,0,0,0,0,0,0,0,0)';$S;OUT;
    'MHB1_RSP_L':'(0,0,0,0,0,0,0,BR12,0,0,0,0,0,0,0,0,0,0,0,0,0,0,0,0,0,0,0,0,0,~
0,0,0,0,0,0,0,0,0,0,0)';$S;IN;
    'MHA_DQS_H6':'(0,0,0,0,0,0,0,R14,0,0,0,0,0,0,0,0,0,0,0,0,0,0,0,0,0,0,0,0,0,0~
,0,0,0,0,0,0,0,0,0,0)';$S;BIDI;
    'MHA_DATA3':'(0,0,0,0,0,0,0,G14,0,0,0,0,0,0,0,0,0,0,0,0,0,0,0,0,0,0,0,0,0,0,~
0,0,0,0,0,0,0,0,0,0)';$S;BIDI;
    'MHA_CA6':'(0,0,0,0,0,0,0,BB14,0,0,0,0,0,0,0,0,0,0,0,0,0,0,0,0,0,0,0,0,0,0,0~
,0,0,0,0,0,0,0,0,0)';$S;OUT;
    'MHB_DQS_L5':'(0,0,0,0,0,0,0,CE14,0,0,0,0,0,0,0,0,0,0,0,0,0,0,0,0,0,0,0,0,0,~
0,0,0,0,0,0,0,0,0,0,0)';$S;BIDI;
    'MHB_DQS_H1':'(0,0,0,0,0,0,0,CK13,0,0,0,0,0,0,0,0,0,0,0,0,0,0,0,0,0,0,0,0,0,~
0,0,0,0,0,0,0,0,0,0,0)';$S;BIDI;
    'MHB_DATA29':'(0,0,0,0,0,0,0,DE14,0,0,0,0,0,0,0,0,0,0,0,0,0,0,0,0,0,0,0,0,0,~
0,0,0,0,0,0,0,0,0,0,0)';$S;BIDI;
    'MHB_DATA18':'(0,0,0,0,0,0,0,CR12,0,0,0,0,0,0,0,0,0,0,0,0,0,0,0,0,0,0,0,0,0,~
0,0,0,0,0,0,0,0,0,0,0)';$S;BIDI;
    'MHB_DATA4':'(0,0,0,0,0,0,0,CF13,0,0,0,0,0,0,0,0,0,0,0,0,0,0,0,0,0,0,0,0,0,0~
,0,0,0,0,0,0,0,0,0,0)';$S;BIDI;
    'MHB_CA6':'(0,0,0,0,0,0,0,BK13,0,0,0,0,0,0,0,0,0,0,0,0,0,0,0,0,0,0,0,0,0,0,0~
,0,0,0,0,0,0,0,0,0)';$S;OUT;
    'MHA_DQS_H7':'(0,0,0,0,0,0,0,AA14,0,0,0,0,0,0,0,0,0,0,0,0,0,0,0,0,0,0,0,0,0,~
0,0,0,0,0,0,0,0,0,0,0)';$S;BIDI;
    'MHA_DATA4':'(0,0,0,0,0,0,0,J12,0,0,0,0,0,0,0,0,0,0,0,0,0,0,0,0,0,0,0,0,0,0,~
0,0,0,0,0,0,0,0,0,0)';$S;BIDI;
    'MHA0_CS_L0':'(0,0,0,0,0,0,0,AU12,0,0,0,0,0,0,0,0,0,0,0,0,0,0,0,0,0,0,0,0,0,~
0,0,0,0,0,0,0,0,0,0,0)';$S;OUT;
    'MHB_DQS_L6':'(0,0,0,0,0,0,0,CL14,0,0,0,0,0,0,0,0,0,0,0,0,0,0,0,0,0,0,0,0,0,~
0,0,0,0,0,0,0,0,0,0,0)';$S;BIDI;
    'MHB_DQS_H2':'(0,0,0,0,0,0,0,CT13,0,0,0,0,0,0,0,0,0,0,0,0,0,0,0,0,0,0,0,0,0,~
0,0,0,0,0,0,0,0,0,0,0)';$S;BIDI;
    'MHB_DATA19':'(0,0,0,0,0,0,0,CT14,0,0,0,0,0,0,0,0,0,0,0,0,0,0,0,0,0,0,0,0,0,~
0,0,0,0,0,0,0,0,0,0,0)';$S;BIDI;
    'MHB_DATA5':'(0,0,0,0,0,0,0,CG14,0,0,0,0,0,0,0,0,0,0,0,0,0,0,0,0,0,0,0,0,0,0~
,0,0,0,0,0,0,0,0,0,0)';$S;BIDI;
    'MHA_DQS_H8':'(0,0,0,0,0,0,0,AG14,0,0,0,0,0,0,0,0,0,0,0,0,0,0,0,0,0,0,0,0,0,~
0,0,0,0,0,0,0,0,0,0,0)';$S;BIDI;
    'MHA_DATA30':'(0,0,0,0,0,0,0,AH13,0,0,0,0,0,0,0,0,0,0,0,0,0,0,0,0,0,0,0,0,0,~
0,0,0,0,0,0,0,0,0,0,0)';$S;BIDI;
    'MHA_DATA5':'(0,0,0,0,0,0,0,K14,0,0,0,0,0,0,0,0,0,0,0,0,0,0,0,0,0,0,0,0,0,0,~
0,0,0,0,0,0,0,0,0,0)';$S;BIDI;
    'MHA1_CS_L0':'(0,0,0,0,0,0,0,AV13,0,0,0,0,0,0,0,0,0,0,0,0,0,0,0,0,0,0,0,0,0,~
0,0,0,0,0,0,0,0,0,0,0)';$S;OUT;
    'MHA0_CS_L1':'(0,0,0,0,0,0,0,AV14,0,0,0,0,0,0,0,0,0,0,0,0,0,0,0,0,0,0,0,0,0,~
0,0,0,0,0,0,0,0,0,0,0)';$S;OUT;
    'MHB_DQS_L7':'(0,0,0,0,0,0,0,CU14,0,0,0,0,0,0,0,0,0,0,0,0,0,0,0,0,0,0,0,0,0,~
0,0,0,0,0,0,0,0,0,0,0)';$S;BIDI;
    'MHB_DQS_H3':'(0,0,0,0,0,0,0,DB13,0,0,0,0,0,0,0,0,0,0,0,0,0,0,0,0,0,0,0,0,0,~
0,0,0,0,0,0,0,0,0,0,0)';$S;BIDI;
    'MHB_DATA6':'(0,0,0,0,0,0,0,CG12,0,0,0,0,0,0,0,0,0,0,0,0,0,0,0,0,0,0,0,0,0,0~
,0,0,0,0,0,0,0,0,0,0)';$S;BIDI;
    'MHA_DQS_H9':'(0,0,0,0,0,0,0,AN14,0,0,0,0,0,0,0,0,0,0,0,0,0,0,0,0,0,0,0,0,0,~
0,0,0,0,0,0,0,0,0,0,0)';$S;BIDI;
    'MHA_DATA31':'(0,0,0,0,0,0,0,AJ14,0,0,0,0,0,0,0,0,0,0,0,0,0,0,0,0,0,0,0,0,0,~
0,0,0,0,0,0,0,0,0,0,0)';$S;BIDI;
    'MHA_DATA20':'(0,0,0,0,0,0,0,AA12,0,0,0,0,0,0,0,0,0,0,0,0,0,0,0,0,0,0,0,0,0,~
0,0,0,0,0,0,0,0,0,0,0)';$S;BIDI;
    'MHA_DATA6':'(0,0,0,0,0,0,0,K13,0,0,0,0,0,0,0,0,0,0,0,0,0,0,0,0,0,0,0,0,0,0,~
0,0,0,0,0,0,0,0,0,0)';$S;BIDI;
    'MHA_CHECK0':'(0,0,0,0,0,0,0,AJ12,0,0,0,0,0,0,0,0,0,0,0,0,0,0,0,0,0,0,0,0,0,~
0,0,0,0,0,0,0,0,0,0,0)';$S;BIDI;
    'MHA1_CS_L1':'(0,0,0,0,0,0,0,AW14,0,0,0,0,0,0,0,0,0,0,0,0,0,0,0,0,0,0,0,0,0,~
0,0,0,0,0,0,0,0,0,0,0)';$S;OUT;
    'MHB_DQS_L8':'(0,0,0,0,0,0,0,DC14,0,0,0,0,0,0,0,0,0,0,0,0,0,0,0,0,0,0,0,0,0,~
0,0,0,0,0,0,0,0,0,0,0)';$S;BIDI;
    'MHB_DQS_H4':'(0,0,0,0,0,0,0,BY14,0,0,0,0,0,0,0,0,0,0,0,0,0,0,0,0,0,0,0,0,0,~
0,0,0,0,0,0,0,0,0,0,0)';$S;BIDI;
    'MHB_DATA7':'(0,0,0,0,0,0,0,CH14,0,0,0,0,0,0,0,0,0,0,0,0,0,0,0,0,0,0,0,0,0,0~
,0,0,0,0,0,0,0,0,0,0)';$S;BIDI;
    'MHA_DATA21':'(0,0,0,0,0,0,0,AB14,0,0,0,0,0,0,0,0,0,0,0,0,0,0,0,0,0,0,0,0,0,~
0,0,0,0,0,0,0,0,0,0,0)';$S;BIDI;
    'MHA_DATA10':'(0,0,0,0,0,0,0,M13,0,0,0,0,0,0,0,0,0,0,0,0,0,0,0,0,0,0,0,0,0,0~
,0,0,0,0,0,0,0,0,0,0)';$S;BIDI;
    'MHA_DATA7':'(0,0,0,0,0,0,0,L14,0,0,0,0,0,0,0,0,0,0,0,0,0,0,0,0,0,0,0,0,0,0,~
0,0,0,0,0,0,0,0,0,0)';$S;BIDI;
    'MHA_CHECK1':'(0,0,0,0,0,0,0,AK14,0,0,0,0,0,0,0,0,0,0,0,0,0,0,0,0,0,0,0,0,0,~
0,0,0,0,0,0,0,0,0,0,0)';$S;BIDI;
    'MHB_DQS_L9':'(0,0,0,0,0,0,0,BW12,0,0,0,0,0,0,0,0,0,0,0,0,0,0,0,0,0,0,0,0,0,~
0,0,0,0,0,0,0,0,0,0,0)';$S;BIDI;
    'MHB_DQS_H5':'(0,0,0,0,0,0,0,CF14,0,0,0,0,0,0,0,0,0,0,0,0,0,0,0,0,0,0,0,0,0,~
0,0,0,0,0,0,0,0,0,0,0)';$S;BIDI;
    'MHB_DATA8':'(0,0,0,0,0,0,0,CH13,0,0,0,0,0,0,0,0,0,0,0,0,0,0,0,0,0,0,0,0,0,0~
,0,0,0,0,0,0,0,0,0,0)';$S;BIDI;
    'MHA_DATA22':'(0,0,0,0,0,0,0,AB13,0,0,0,0,0,0,0,0,0,0,0,0,0,0,0,0,0,0,0,0,0,~
0,0,0,0,0,0,0,0,0,0,0)';$S;BIDI;
    'MHA_DATA11':'(0,0,0,0,0,0,0,N14,0,0,0,0,0,0,0,0,0,0,0,0,0,0,0,0,0,0,0,0,0,0~
,0,0,0,0,0,0,0,0,0,0)';$S;BIDI;
    'MHA_DATA8':'(0,0,0,0,0,0,0,L12,0,0,0,0,0,0,0,0,0,0,0,0,0,0,0,0,0,0,0,0,0,0,~
0,0,0,0,0,0,0,0,0,0)';$S;BIDI;
    'MHA_CHECK2':'(0,0,0,0,0,0,0,AK13,0,0,0,0,0,0,0,0,0,0,0,0,0,0,0,0,0,0,0,0,0,~
0,0,0,0,0,0,0,0,0,0,0)';$S;BIDI;
    'MHB_DQS_H6':'(0,0,0,0,0,0,0,CM14,0,0,0,0,0,0,0,0,0,0,0,0,0,0,0,0,0,0,0,0,0,~
0,0,0,0,0,0,0,0,0,0,0)';$S;BIDI;
    'MHB_DATA9':'(0,0,0,0,0,0,0,CJ14,0,0,0,0,0,0,0,0,0,0,0,0,0,0,0,0,0,0,0,0,0,0~
,0,0,0,0,0,0,0,0,0,0)';$S;BIDI;
    'MHA_DATA23':'(0,0,0,0,0,0,0,AC14,0,0,0,0,0,0,0,0,0,0,0,0,0,0,0,0,0,0,0,0,0,~
0,0,0,0,0,0,0,0,0,0,0)';$S;BIDI;
    'MHA_DATA12':'(0,0,0,0,0,0,0,R12,0,0,0,0,0,0,0,0,0,0,0,0,0,0,0,0,0,0,0,0,0,0~
,0,0,0,0,0,0,0,0,0,0)';$S;BIDI;
    'MHA_DATA9':'(0,0,0,0,0,0,0,M14,0,0,0,0,0,0,0,0,0,0,0,0,0,0,0,0,0,0,0,0,0,0,~
0,0,0,0,0,0,0,0,0,0)';$S;BIDI;
    'MHA_CHECK3':'(0,0,0,0,0,0,0,AL14,0,0,0,0,0,0,0,0,0,0,0,0,0,0,0,0,0,0,0,0,0,~
0,0,0,0,0,0,0,0,0,0,0)';$S;BIDI;
    'MHB_DQS_H7':'(0,0,0,0,0,0,0,CV14,0,0,0,0,0,0,0,0,0,0,0,0,0,0,0,0,0,0,0,0,0,~
0,0,0,0,0,0,0,0,0,0,0)';$S;BIDI;
    'MHB0_CS_L0':'(0,0,0,0,0,0,0,BM14,0,0,0,0,0,0,0,0,0,0,0,0,0,0,0,0,0,0,0,0,0,~
0,0,0,0,0,0,0,0,0,0,0)';$S;OUT;
    'MHA_DQS_L0':'(0,0,0,0,0,0,0,H13,0,0,0,0,0,0,0,0,0,0,0,0,0,0,0,0,0,0,0,0,0,0~
,0,0,0,0,0,0,0,0,0,0)';$S;BIDI;
    'MHA_DATA24':'(0,0,0,0,0,0,0,AC12,0,0,0,0,0,0,0,0,0,0,0,0,0,0,0,0,0,0,0,0,0,~
0,0,0,0,0,0,0,0,0,0,0)';$S;BIDI;
    'MHA_DATA13':'(0,0,0,0,0,0,0,T14,0,0,0,0,0,0,0,0,0,0,0,0,0,0,0,0,0,0,0,0,0,0~
,0,0,0,0,0,0,0,0,0,0)';$S;BIDI;
    'MHA_CHECK4':'(0,0,0,0,0,0,0,AN12,0,0,0,0,0,0,0,0,0,0,0,0,0,0,0,0,0,0,0,0,0,~
0,0,0,0,0,0,0,0,0,0,0)';$S;BIDI;
    'MHB_DQS_H8':'(0,0,0,0,0,0,0,DD14,0,0,0,0,0,0,0,0,0,0,0,0,0,0,0,0,0,0,0,0,0,~
0,0,0,0,0,0,0,0,0,0,0)';$S;BIDI;
    'MHB_DATA30':'(0,0,0,0,0,0,0,DE12,0,0,0,0,0,0,0,0,0,0,0,0,0,0,0,0,0,0,0,0,0,~
0,0,0,0,0,0,0,0,0,0,0)';$S;BIDI;
    'MHB1_CS_L0':'(0,0,0,0,0,0,0,BL12,0,0,0,0,0,0,0,0,0,0,0,0,0,0,0,0,0,0,0,0,0,~
0,0,0,0,0,0,0,0,0,0,0)';$S;OUT;
    'MHB0_CS_L1':'(0,0,0,0,0,0,0,BN12,0,0,0,0,0,0,0,0,0,0,0,0,0,0,0,0,0,0,0,0,0,~
0,0,0,0,0,0,0,0,0,0,0)';$S;OUT;
    'MHA_DQS_L1':'(0,0,0,0,0,0,0,P13,0,0,0,0,0,0,0,0,0,0,0,0,0,0,0,0,0,0,0,0,0,0~
,0,0,0,0,0,0,0,0,0,0)';$S;BIDI;
    'MHA_DATA25':'(0,0,0,0,0,0,0,AD14,0,0,0,0,0,0,0,0,0,0,0,0,0,0,0,0,0,0,0,0,0,~
0,0,0,0,0,0,0,0,0,0,0)';$S;BIDI;
    'MHA_DATA14':'(0,0,0,0,0,0,0,T13,0,0,0,0,0,0,0,0,0,0,0,0,0,0,0,0,0,0,0,0,0,0~
,0,0,0,0,0,0,0,0,0,0)';$S;BIDI;
    'MHA_CHECK5':'(0,0,0,0,0,0,0,AP14,0,0,0,0,0,0,0,0,0,0,0,0,0,0,0,0,0,0,0,0,0,~
0,0,0,0,0,0,0,0,0,0,0)';$S;BIDI;
    'MHB_DQS_H9':'(0,0,0,0,0,0,0,BV13,0,0,0,0,0,0,0,0,0,0,0,0,0,0,0,0,0,0,0,0,0,~
0,0,0,0,0,0,0,0,0,0,0)';$S;BIDI;
    'MHA_PAR':'(0,0,0,0,0,0,0,BC14,0,0,0,0,0,0,0,0,0,0,0,0,0,0,0,0,0,0,0,0,0,0,0~
,0,0,0,0,0,0,0,0,0)';$S;OUT;
    'MHB_PAR':'(0,0,0,0,0,0,0,BL14,0,0,0,0,0,0,0,0,0,0,0,0,0,0,0,0,0,0,0,0,0,0,0~
,0,0,0,0,0,0,0,0,0)';$S;OUT;
    'MH0_CLK_H':'(0,0,0,0,0,0,0,BC12,0,0,0,0,0,0,0,0,0,0,0,0,0,0,0,0,0,0,0,0,0,0~
,0,0,0,0,0,0,0,0,0,0)';$S;OUT;
    'MH0_CLK_L':'(0,0,0,0,0,0,0,BD13,0,0,0,0,0,0,0,0,0,0,0,0,0,0,0,0,0,0,0,0,0,0~
,0,0,0,0,0,0,0,0,0,0)';$S;OUT;
    'MH1_CLK_H':'(0,0,0,0,0,0,0,BF13,0,0,0,0,0,0,0,0,0,0,0,0,0,0,0,0,0,0,0,0,0,0~
,0,0,0,0,0,0,0,0,0,0)';$S;OUT;
    'MH1_CLK_L':'(0,0,0,0,0,0,0,BG12,0,0,0,0,0,0,0,0,0,0,0,0,0,0,0,0,0,0,0,0,0,0~
,0,0,0,0,0,0,0,0,0,0)';$S;OUT;
    'TEST39H':'(0,0,0,0,0,0,0,BF14,0,0,0,0,0,0,0,0,0,0,0,0,0,0,0,0,0,0,0,0,0,0,0~
,0,0,0,0,0,0,0,0,0)';$S;OUT;
    'MIB_DATA23':'(0,0,0,0,0,0,0,0,CY21,0,0,0,0,0,0,0,0,0,0,0,0,0,0,0,0,0,0,0,0,~
0,0,0,0,0,0,0,0,0,0,0)';$S;BIDI;
    'MIB_DATA12':'(0,0,0,0,0,0,0,0,CM20,0,0,0,0,0,0,0,0,0,0,0,0,0,0,0,0,0,0,0,0,~
0,0,0,0,0,0,0,0,0,0,0)';$S;BIDI;
    'MIB_DATA6':'(0,0,0,0,0,0,0,0,CG19,0,0,0,0,0,0,0,0,0,0,0,0,0,0,0,0,0,0,0,0,0~
,0,0,0,0,0,0,0,0,0,0)';$S;BIDI;
    'MIB_CHECK3':'(0,0,0,0,0,0,0,0,CB21,0,0,0,0,0,0,0,0,0,0,0,0,0,0,0,0,0,0,0,0,~
0,0,0,0,0,0,0,0,0,0,0)';$S;BIDI;
    'MIA_DQS_L5':'(0,0,0,0,0,0,0,0,H21,0,0,0,0,0,0,0,0,0,0,0,0,0,0,0,0,0,0,0,0,0~
,0,0,0,0,0,0,0,0,0,0)';$S;BIDI;
    'MIA_DQS_H1':'(0,0,0,0,0,0,0,0,N19,0,0,0,0,0,0,0,0,0,0,0,0,0,0,0,0,0,0,0,0,0~
,0,0,0,0,0,0,0,0,0,0)';$S;BIDI;
    'MIA_DATA29':'(0,0,0,0,0,0,0,0,AH21,0,0,0,0,0,0,0,0,0,0,0,0,0,0,0,0,0,0,0,0,~
0,0,0,0,0,0,0,0,0,0,0)';$S;BIDI;
    'MIA_DATA18':'(0,0,0,0,0,0,0,0,V20,0,0,0,0,0,0,0,0,0,0,0,0,0,0,0,0,0,0,0,0,0~
,0,0,0,0,0,0,0,0,0,0)';$S;BIDI;
    'MIA_DATA6':'(0,0,0,0,0,0,0,0,K20,0,0,0,0,0,0,0,0,0,0,0,0,0,0,0,0,0,0,0,0,0,~
0,0,0,0,0,0,0,0,0,0)';$S;BIDI;
    'MIB_DQS_L0':'(0,0,0,0,0,0,0,0,CE19,0,0,0,0,0,0,0,0,0,0,0,0,0,0,0,0,0,0,0,0,~
0,0,0,0,0,0,0,0,0,0,0)';$S;BIDI;
    'MIB_DATA24':'(0,0,0,0,0,0,0,0,CY20,0,0,0,0,0,0,0,0,0,0,0,0,0,0,0,0,0,0,0,0,~
0,0,0,0,0,0,0,0,0,0,0)';$S;BIDI;
    'MIB_DATA13':'(0,0,0,0,0,0,0,0,CN21,0,0,0,0,0,0,0,0,0,0,0,0,0,0,0,0,0,0,0,0,~
0,0,0,0,0,0,0,0,0,0,0)';$S;BIDI;
    'MIB_DATA7':'(0,0,0,0,0,0,0,0,CH21,0,0,0,0,0,0,0,0,0,0,0,0,0,0,0,0,0,0,0,0,0~
,0,0,0,0,0,0,0,0,0,0)';$S;BIDI;
    'MIB_CHECK4':'(0,0,0,0,0,0,0,0,BT20,0,0,0,0,0,0,0,0,0,0,0,0,0,0,0,0,0,0,0,0,~
0,0,0,0,0,0,0,0,0,0,0)';$S;BIDI;
    'MIA_DQS_L6':'(0,0,0,0,0,0,0,0,P21,0,0,0,0,0,0,0,0,0,0,0,0,0,0,0,0,0,0,0,0,0~
,0,0,0,0,0,0,0,0,0,0)';$S;BIDI;
    'MIA_DQS_H2':'(0,0,0,0,0,0,0,0,W19,0,0,0,0,0,0,0,0,0,0,0,0,0,0,0,0,0,0,0,0,0~
,0,0,0,0,0,0,0,0,0,0)';$S;BIDI;
    'MIA_DATA19':'(0,0,0,0,0,0,0,0,W21,0,0,0,0,0,0,0,0,0,0,0,0,0,0,0,0,0,0,0,0,0~
,0,0,0,0,0,0,0,0,0,0)';$S;BIDI;
    'MIA_DATA7':'(0,0,0,0,0,0,0,0,L21,0,0,0,0,0,0,0,0,0,0,0,0,0,0,0,0,0,0,0,0,0,~
0,0,0,0,0,0,0,0,0,0)';$S;BIDI;
    'MIA_CA0':'(0,0,0,0,0,0,0,0,AW19,0,0,0,0,0,0,0,0,0,0,0,0,0,0,0,0,0,0,0,0,0,0~
,0,0,0,0,0,0,0,0,0)';$S;OUT;
    'MIB_DQS_L1':'(0,0,0,0,0,0,0,0,CL19,0,0,0,0,0,0,0,0,0,0,0,0,0,0,0,0,0,0,0,0,~
0,0,0,0,0,0,0,0,0,0,0)';$S;BIDI;
    'MIB_DATA25':'(0,0,0,0,0,0,0,0,DA21,0,0,0,0,0,0,0,0,0,0,0,0,0,0,0,0,0,0,0,0,~
0,0,0,0,0,0,0,0,0,0,0)';$S;BIDI;
    'MIB_DATA14':'(0,0,0,0,0,0,0,0,CN19,0,0,0,0,0,0,0,0,0,0,0,0,0,0,0,0,0,0,0,0,~
0,0,0,0,0,0,0,0,0,0,0)';$S;BIDI;
    'MIB_DATA8':'(0,0,0,0,0,0,0,0,CH20,0,0,0,0,0,0,0,0,0,0,0,0,0,0,0,0,0,0,0,0,0~
,0,0,0,0,0,0,0,0,0,0)';$S;BIDI;
    'MIB_CHECK5':'(0,0,0,0,0,0,0,0,BU21,0,0,0,0,0,0,0,0,0,0,0,0,0,0,0,0,0,0,0,0,~
0,0,0,0,0,0,0,0,0,0,0)';$S;BIDI;
    'MIB_CA0':'(0,0,0,0,0,0,0,0,BG21,0,0,0,0,0,0,0,0,0,0,0,0,0,0,0,0,0,0,0,0,0,0~
,0,0,0,0,0,0,0,0,0)';$S;OUT;
    'MIA_DQS_L7':'(0,0,0,0,0,0,0,0,Y21,0,0,0,0,0,0,0,0,0,0,0,0,0,0,0,0,0,0,0,0,0~
,0,0,0,0,0,0,0,0,0,0)';$S;BIDI;
    'MIA_DQS_H3':'(0,0,0,0,0,0,0,0,AE19,0,0,0,0,0,0,0,0,0,0,0,0,0,0,0,0,0,0,0,0,~
0,0,0,0,0,0,0,0,0,0,0)';$S;BIDI;
    'MIA_DATA8':'(0,0,0,0,0,0,0,0,L19,0,0,0,0,0,0,0,0,0,0,0,0,0,0,0,0,0,0,0,0,0,~
0,0,0,0,0,0,0,0,0,0)';$S;BIDI;
    'MIA_CA1':'(0,0,0,0,0,0,0,0,AY20,0,0,0,0,0,0,0,0,0,0,0,0,0,0,0,0,0,0,0,0,0,0~
,0,0,0,0,0,0,0,0,0)';$S;OUT;
    'MIB_DQS_L2':'(0,0,0,0,0,0,0,0,CU19,0,0,0,0,0,0,0,0,0,0,0,0,0,0,0,0,0,0,0,0,~
0,0,0,0,0,0,0,0,0,0,0)';$S;BIDI;
    'MIB_DATA26':'(0,0,0,0,0,0,0,0,DA19,0,0,0,0,0,0,0,0,0,0,0,0,0,0,0,0,0,0,0,0,~
0,0,0,0,0,0,0,0,0,0,0)';$S;BIDI;
    'MIB_DATA15':'(0,0,0,0,0,0,0,0,CP21,0,0,0,0,0,0,0,0,0,0,0,0,0,0,0,0,0,0,0,0,~
0,0,0,0,0,0,0,0,0,0,0)';$S;BIDI;
    'MIB_DATA9':'(0,0,0,0,0,0,0,0,CJ21,0,0,0,0,0,0,0,0,0,0,0,0,0,0,0,0,0,0,0,0,0~
,0,0,0,0,0,0,0,0,0,0)';$S;BIDI;
    'MIB_CHECK6':'(0,0,0,0,0,0,0,0,BU19,0,0,0,0,0,0,0,0,0,0,0,0,0,0,0,0,0,0,0,0,~
0,0,0,0,0,0,0,0,0,0,0)';$S;BIDI;
    'MIB_CA1':'(0,0,0,0,0,0,0,0,BH21,0,0,0,0,0,0,0,0,0,0,0,0,0,0,0,0,0,0,0,0,0,0~
,0,0,0,0,0,0,0,0,0)';$S;OUT;
    'MIA_DQS_L8':'(0,0,0,0,0,0,0,0,AF21,0,0,0,0,0,0,0,0,0,0,0,0,0,0,0,0,0,0,0,0,~
0,0,0,0,0,0,0,0,0,0,0)';$S;BIDI;
    'MIA_DQS_H4':'(0,0,0,0,0,0,0,0,AL19,0,0,0,0,0,0,0,0,0,0,0,0,0,0,0,0,0,0,0,0,~
0,0,0,0,0,0,0,0,0,0,0)';$S;BIDI;
    'MIA_DATA9':'(0,0,0,0,0,0,0,0,M21,0,0,0,0,0,0,0,0,0,0,0,0,0,0,0,0,0,0,0,0,0,~
0,0,0,0,0,0,0,0,0,0)';$S;BIDI;
    'MIA_CA2':'(0,0,0,0,0,0,0,0,AY21,0,0,0,0,0,0,0,0,0,0,0,0,0,0,0,0,0,0,0,0,0,0~
,0,0,0,0,0,0,0,0,0)';$S;OUT;
    'MIB_DQS_L3':'(0,0,0,0,0,0,0,0,DC19,0,0,0,0,0,0,0,0,0,0,0,0,0,0,0,0,0,0,0,0,~
0,0,0,0,0,0,0,0,0,0,0)';$S;BIDI;
    'MIB_DATA27':'(0,0,0,0,0,0,0,0,DB21,0,0,0,0,0,0,0,0,0,0,0,0,0,0,0,0,0,0,0,0,~
0,0,0,0,0,0,0,0,0,0,0)';$S;BIDI;
    'MIB_DATA16':'(0,0,0,0,0,0,0,0,CP20,0,0,0,0,0,0,0,0,0,0,0,0,0,0,0,0,0,0,0,0,~
0,0,0,0,0,0,0,0,0,0,0)';$S;BIDI;
    'MIB_CHECK7':'(0,0,0,0,0,0,0,0,BV21,0,0,0,0,0,0,0,0,0,0,0,0,0,0,0,0,0,0,0,0,~
0,0,0,0,0,0,0,0,0,0,0)';$S;BIDI;
    'MIB_CA2':'(0,0,0,0,0,0,0,0,BH20,0,0,0,0,0,0,0,0,0,0,0,0,0,0,0,0,0,0,0,0,0,0~
,0,0,0,0,0,0,0,0,0)';$S;OUT;
    'MIB0_RSP_L':'(0,0,0,0,0,0,0,0,BP20,0,0,0,0,0,0,0,0,0,0,0,0,0,0,0,0,0,0,0,0,~
0,0,0,0,0,0,0,0,0,0,0)';$S;IN;
    'MIA_DQS_L9':'(0,0,0,0,0,0,0,0,AM21,0,0,0,0,0,0,0,0,0,0,0,0,0,0,0,0,0,0,0,0,~
0,0,0,0,0,0,0,0,0,0,0)';$S;BIDI;
    'MIA_DQS_H5':'(0,0,0,0,0,0,0,0,J21,0,0,0,0,0,0,0,0,0,0,0,0,0,0,0,0,0,0,0,0,0~
,0,0,0,0,0,0,0,0,0,0)';$S;BIDI;
    'MIA_CA3':'(0,0,0,0,0,0,0,0,BA21,0,0,0,0,0,0,0,0,0,0,0,0,0,0,0,0,0,0,0,0,0,0~
,0,0,0,0,0,0,0,0,0)';$S;OUT;
    'MIB_DQS_L4':'(0,0,0,0,0,0,0,0,BW21,0,0,0,0,0,0,0,0,0,0,0,0,0,0,0,0,0,0,0,0,~
0,0,0,0,0,0,0,0,0,0,0)';$S;BIDI;
    'MIB_DQS_H0':'(0,0,0,0,0,0,0,0,CD20,0,0,0,0,0,0,0,0,0,0,0,0,0,0,0,0,0,0,0,0,~
0,0,0,0,0,0,0,0,0,0,0)';$S;BIDI;
    'MIB_DATA28':'(0,0,0,0,0,0,0,0,DD20,0,0,0,0,0,0,0,0,0,0,0,0,0,0,0,0,0,0,0,0,~
0,0,0,0,0,0,0,0,0,0,0)';$S;BIDI;
    'MIB_DATA17':'(0,0,0,0,0,0,0,0,CR21,0,0,0,0,0,0,0,0,0,0,0,0,0,0,0,0,0,0,0,0,~
0,0,0,0,0,0,0,0,0,0,0)';$S;BIDI;
    'MIB_CA3':'(0,0,0,0,0,0,0,0,BJ19,0,0,0,0,0,0,0,0,0,0,0,0,0,0,0,0,0,0,0,0,0,0~
,0,0,0,0,0,0,0,0,0)';$S;OUT;
    'MIB1_RSP_L':'(0,0,0,0,0,0,0,0,BR19,0,0,0,0,0,0,0,0,0,0,0,0,0,0,0,0,0,0,0,0,~
0,0,0,0,0,0,0,0,0,0,0)';$S;IN;
    'MIA_DQS_H6':'(0,0,0,0,0,0,0,0,R21,0,0,0,0,0,0,0,0,0,0,0,0,0,0,0,0,0,0,0,0,0~
,0,0,0,0,0,0,0,0,0,0)';$S;BIDI;
    'MIA_CA4':'(0,0,0,0,0,0,0,0,BA19,0,0,0,0,0,0,0,0,0,0,0,0,0,0,0,0,0,0,0,0,0,0~
,0,0,0,0,0,0,0,0,0)';$S;OUT;
    'MIB_DQS_L5':'(0,0,0,0,0,0,0,0,CE21,0,0,0,0,0,0,0,0,0,0,0,0,0,0,0,0,0,0,0,0,~
0,0,0,0,0,0,0,0,0,0,0)';$S;BIDI;
    'MIB_DQS_H1':'(0,0,0,0,0,0,0,0,CK20,0,0,0,0,0,0,0,0,0,0,0,0,0,0,0,0,0,0,0,0,~
0,0,0,0,0,0,0,0,0,0,0)';$S;BIDI;
    'MIB_DATA29':'(0,0,0,0,0,0,0,0,DE21,0,0,0,0,0,0,0,0,0,0,0,0,0,0,0,0,0,0,0,0,~
0,0,0,0,0,0,0,0,0,0,0)';$S;BIDI;
    'MIB_DATA18':'(0,0,0,0,0,0,0,0,CR19,0,0,0,0,0,0,0,0,0,0,0,0,0,0,0,0,0,0,0,0,~
0,0,0,0,0,0,0,0,0,0,0)';$S;BIDI;
    'MIB_CA4':'(0,0,0,0,0,0,0,0,BJ21,0,0,0,0,0,0,0,0,0,0,0,0,0,0,0,0,0,0,0,0,0,0~
,0,0,0,0,0,0,0,0,0)';$S;OUT;
    'MIA_DQS_H7':'(0,0,0,0,0,0,0,0,AA21,0,0,0,0,0,0,0,0,0,0,0,0,0,0,0,0,0,0,0,0,~
0,0,0,0,0,0,0,0,0,0,0)';$S;BIDI;
    'MIA_CA5':'(0,0,0,0,0,0,0,0,BB20,0,0,0,0,0,0,0,0,0,0,0,0,0,0,0,0,0,0,0,0,0,0~
,0,0,0,0,0,0,0,0,0)';$S;OUT;
    'MIA1_CS_L0':'(0,0,0,0,0,0,0,0,AV20,0,0,0,0,0,0,0,0,0,0,0,0,0,0,0,0,0,0,0,0,~
0,0,0,0,0,0,0,0,0,0,0)';$S;OUT;
    'MIA0_CS_L0':'(0,0,0,0,0,0,0,0,AU19,0,0,0,0,0,0,0,0,0,0,0,0,0,0,0,0,0,0,0,0,~
0,0,0,0,0,0,0,0,0,0,0)';$S;OUT;
    'MI1_CLK_H':'(0,0,0,0,0,0,0,0,BF20,0,0,0,0,0,0,0,0,0,0,0,0,0,0,0,0,0,0,0,0,0~
,0,0,0,0,0,0,0,0,0,0)';$S;OUT;
    'MI0_CLK_H':'(0,0,0,0,0,0,0,0,BC19,0,0,0,0,0,0,0,0,0,0,0,0,0,0,0,0,0,0,0,0,0~
,0,0,0,0,0,0,0,0,0,0)';$S;OUT;
    'MIB_DQS_L6':'(0,0,0,0,0,0,0,0,CL21,0,0,0,0,0,0,0,0,0,0,0,0,0,0,0,0,0,0,0,0,~
0,0,0,0,0,0,0,0,0,0,0)';$S;BIDI;
    'MIB_DQS_H2':'(0,0,0,0,0,0,0,0,CT20,0,0,0,0,0,0,0,0,0,0,0,0,0,0,0,0,0,0,0,0,~
0,0,0,0,0,0,0,0,0,0,0)';$S;BIDI;
    'MIB_DATA19':'(0,0,0,0,0,0,0,0,CT21,0,0,0,0,0,0,0,0,0,0,0,0,0,0,0,0,0,0,0,0,~
0,0,0,0,0,0,0,0,0,0,0)';$S;BIDI;
    'MIB_CA5':'(0,0,0,0,0,0,0,0,BK21,0,0,0,0,0,0,0,0,0,0,0,0,0,0,0,0,0,0,0,0,0,0~
,0,0,0,0,0,0,0,0,0)';$S;OUT;
    'MIA_DQS_H8':'(0,0,0,0,0,0,0,0,AG21,0,0,0,0,0,0,0,0,0,0,0,0,0,0,0,0,0,0,0,0,~
0,0,0,0,0,0,0,0,0,0,0)';$S;BIDI;
    'MIA_DATA30':'(0,0,0,0,0,0,0,0,AH20,0,0,0,0,0,0,0,0,0,0,0,0,0,0,0,0,0,0,0,0,~
0,0,0,0,0,0,0,0,0,0,0)';$S;BIDI;
    'MIA_CA6':'(0,0,0,0,0,0,0,0,BB21,0,0,0,0,0,0,0,0,0,0,0,0,0,0,0,0,0,0,0,0,0,0~
,0,0,0,0,0,0,0,0,0)';$S;OUT;
    'MIA1_CS_L1':'(0,0,0,0,0,0,0,0,AW21,0,0,0,0,0,0,0,0,0,0,0,0,0,0,0,0,0,0,0,0,~
0,0,0,0,0,0,0,0,0,0,0)';$S;OUT;
    'MIA0_CS_L1':'(0,0,0,0,0,0,0,0,AV21,0,0,0,0,0,0,0,0,0,0,0,0,0,0,0,0,0,0,0,0,~
0,0,0,0,0,0,0,0,0,0,0)';$S;OUT;
    'MIB_DQS_L7':'(0,0,0,0,0,0,0,0,CU21,0,0,0,0,0,0,0,0,0,0,0,0,0,0,0,0,0,0,0,0,~
0,0,0,0,0,0,0,0,0,0,0)';$S;BIDI;
    'MIB_DQS_H3':'(0,0,0,0,0,0,0,0,DB20,0,0,0,0,0,0,0,0,0,0,0,0,0,0,0,0,0,0,0,0,~
0,0,0,0,0,0,0,0,0,0,0)';$S;BIDI;
    'MIB_CA6':'(0,0,0,0,0,0,0,0,BK20,0,0,0,0,0,0,0,0,0,0,0,0,0,0,0,0,0,0,0,0,0,0~
,0,0,0,0,0,0,0,0,0)';$S;OUT;
    'MIA_DQS_H9':'(0,0,0,0,0,0,0,0,AN21,0,0,0,0,0,0,0,0,0,0,0,0,0,0,0,0,0,0,0,0,~
0,0,0,0,0,0,0,0,0,0,0)';$S;BIDI;
    'MIA_DATA31':'(0,0,0,0,0,0,0,0,AJ21,0,0,0,0,0,0,0,0,0,0,0,0,0,0,0,0,0,0,0,0,~
0,0,0,0,0,0,0,0,0,0,0)';$S;BIDI;
    'MIA_DATA20':'(0,0,0,0,0,0,0,0,AA19,0,0,0,0,0,0,0,0,0,0,0,0,0,0,0,0,0,0,0,0,~
0,0,0,0,0,0,0,0,0,0,0)';$S;BIDI;
    'MIA_CHECK0':'(0,0,0,0,0,0,0,0,AJ19,0,0,0,0,0,0,0,0,0,0,0,0,0,0,0,0,0,0,0,0,~
0,0,0,0,0,0,0,0,0,0,0)';$S;BIDI;
    'MIB_DQS_L8':'(0,0,0,0,0,0,0,0,DC21,0,0,0,0,0,0,0,0,0,0,0,0,0,0,0,0,0,0,0,0,~
0,0,0,0,0,0,0,0,0,0,0)';$S;BIDI;
    'MIB_DQS_H4':'(0,0,0,0,0,0,0,0,BY21,0,0,0,0,0,0,0,0,0,0,0,0,0,0,0,0,0,0,0,0,~
0,0,0,0,0,0,0,0,0,0,0)';$S;BIDI;
    'MIA_DATA21':'(0,0,0,0,0,0,0,0,AB21,0,0,0,0,0,0,0,0,0,0,0,0,0,0,0,0,0,0,0,0,~
0,0,0,0,0,0,0,0,0,0,0)';$S;BIDI;
    'MIA_DATA10':'(0,0,0,0,0,0,0,0,M20,0,0,0,0,0,0,0,0,0,0,0,0,0,0,0,0,0,0,0,0,0~
,0,0,0,0,0,0,0,0,0,0)';$S;BIDI;
    'MIA_CHECK1':'(0,0,0,0,0,0,0,0,AK21,0,0,0,0,0,0,0,0,0,0,0,0,0,0,0,0,0,0,0,0,~
0,0,0,0,0,0,0,0,0,0,0)';$S;BIDI;
    'MIB_DQS_L9':'(0,0,0,0,0,0,0,0,BW19,0,0,0,0,0,0,0,0,0,0,0,0,0,0,0,0,0,0,0,0,~
0,0,0,0,0,0,0,0,0,0,0)';$S;BIDI;
    'MIB_DQS_H5':'(0,0,0,0,0,0,0,0,CF21,0,0,0,0,0,0,0,0,0,0,0,0,0,0,0,0,0,0,0,0,~
0,0,0,0,0,0,0,0,0,0,0)';$S;BIDI;
    'MIA_DATA22':'(0,0,0,0,0,0,0,0,AB20,0,0,0,0,0,0,0,0,0,0,0,0,0,0,0,0,0,0,0,0,~
0,0,0,0,0,0,0,0,0,0,0)';$S;BIDI;
    'MIA_DATA11':'(0,0,0,0,0,0,0,0,N21,0,0,0,0,0,0,0,0,0,0,0,0,0,0,0,0,0,0,0,0,0~
,0,0,0,0,0,0,0,0,0,0)';$S;BIDI;
    'MIA_CHECK2':'(0,0,0,0,0,0,0,0,AK20,0,0,0,0,0,0,0,0,0,0,0,0,0,0,0,0,0,0,0,0,~
0,0,0,0,0,0,0,0,0,0,0)';$S;BIDI;
    'MI1_CLK_L':'(0,0,0,0,0,0,0,0,BG19,0,0,0,0,0,0,0,0,0,0,0,0,0,0,0,0,0,0,0,0,0~
,0,0,0,0,0,0,0,0,0,0)';$S;OUT;
    'MI0_CLK_L':'(0,0,0,0,0,0,0,0,BD20,0,0,0,0,0,0,0,0,0,0,0,0,0,0,0,0,0,0,0,0,0~
,0,0,0,0,0,0,0,0,0,0)';$S;OUT;
    'MI_RESET_L':'(0,0,0,0,0,0,0,0,AU21,0,0,0,0,0,0,0,0,0,0,0,0,0,0,0,0,0,0,0,0,~
0,0,0,0,0,0,0,0,0,0,0)';$S;OUT;
    'MIB_DQS_H6':'(0,0,0,0,0,0,0,0,CM21,0,0,0,0,0,0,0,0,0,0,0,0,0,0,0,0,0,0,0,0,~
0,0,0,0,0,0,0,0,0,0,0)';$S;BIDI;
    'MIB_DATA0':'(0,0,0,0,0,0,0,0,CB20,0,0,0,0,0,0,0,0,0,0,0,0,0,0,0,0,0,0,0,0,0~
,0,0,0,0,0,0,0,0,0,0)';$S;BIDI;
    'MIA_DATA23':'(0,0,0,0,0,0,0,0,AC21,0,0,0,0,0,0,0,0,0,0,0,0,0,0,0,0,0,0,0,0,~
0,0,0,0,0,0,0,0,0,0,0)';$S;BIDI;
    'MIA_DATA12':'(0,0,0,0,0,0,0,0,R19,0,0,0,0,0,0,0,0,0,0,0,0,0,0,0,0,0,0,0,0,0~
,0,0,0,0,0,0,0,0,0,0)';$S;BIDI;
    'MIA_DATA0':'(0,0,0,0,0,0,0,0,E19,0,0,0,0,0,0,0,0,0,0,0,0,0,0,0,0,0,0,0,0,0,~
0,0,0,0,0,0,0,0,0,0)';$S;BIDI;
    'MIA_CHECK3':'(0,0,0,0,0,0,0,0,AL21,0,0,0,0,0,0,0,0,0,0,0,0,0,0,0,0,0,0,0,0,~
0,0,0,0,0,0,0,0,0,0,0)';$S;BIDI;
    'MIB_DQS_H7':'(0,0,0,0,0,0,0,0,CV21,0,0,0,0,0,0,0,0,0,0,0,0,0,0,0,0,0,0,0,0,~
0,0,0,0,0,0,0,0,0,0,0)';$S;BIDI;
    'MIB_DATA1':'(0,0,0,0,0,0,0,0,CC21,0,0,0,0,0,0,0,0,0,0,0,0,0,0,0,0,0,0,0,0,0~
,0,0,0,0,0,0,0,0,0,0)';$S;BIDI;
    'MIB0_CS_L0':'(0,0,0,0,0,0,0,0,BM21,0,0,0,0,0,0,0,0,0,0,0,0,0,0,0,0,0,0,0,0,~
0,0,0,0,0,0,0,0,0,0,0)';$S;OUT;
    'MIA_DQS_L0':'(0,0,0,0,0,0,0,0,H20,0,0,0,0,0,0,0,0,0,0,0,0,0,0,0,0,0,0,0,0,0~
,0,0,0,0,0,0,0,0,0,0)';$S;BIDI;
    'MIA_DATA24':'(0,0,0,0,0,0,0,0,AC19,0,0,0,0,0,0,0,0,0,0,0,0,0,0,0,0,0,0,0,0,~
0,0,0,0,0,0,0,0,0,0,0)';$S;BIDI;
    'MIA_DATA13':'(0,0,0,0,0,0,0,0,T21,0,0,0,0,0,0,0,0,0,0,0,0,0,0,0,0,0,0,0,0,0~
,0,0,0,0,0,0,0,0,0,0)';$S;BIDI;
    'MIA_DATA1':'(0,0,0,0,0,0,0,0,F21,0,0,0,0,0,0,0,0,0,0,0,0,0,0,0,0,0,0,0,0,0,~
0,0,0,0,0,0,0,0,0,0)';$S;BIDI;
    'MIA_CHECK4':'(0,0,0,0,0,0,0,0,AN19,0,0,0,0,0,0,0,0,0,0,0,0,0,0,0,0,0,0,0,0,~
0,0,0,0,0,0,0,0,0,0,0)';$S;BIDI;
    'MIB_DQS_H8':'(0,0,0,0,0,0,0,0,DD21,0,0,0,0,0,0,0,0,0,0,0,0,0,0,0,0,0,0,0,0,~
0,0,0,0,0,0,0,0,0,0,0)';$S;BIDI;
    'MIB_DATA30':'(0,0,0,0,0,0,0,0,DE19,0,0,0,0,0,0,0,0,0,0,0,0,0,0,0,0,0,0,0,0,~
0,0,0,0,0,0,0,0,0,0,0)';$S;BIDI;
    'MIB_DATA2':'(0,0,0,0,0,0,0,0,CC19,0,0,0,0,0,0,0,0,0,0,0,0,0,0,0,0,0,0,0,0,0~
,0,0,0,0,0,0,0,0,0,0)';$S;BIDI;
    'MIB1_CS_L0':'(0,0,0,0,0,0,0,0,BL19,0,0,0,0,0,0,0,0,0,0,0,0,0,0,0,0,0,0,0,0,~
0,0,0,0,0,0,0,0,0,0,0)';$S;OUT;
    'MIB0_CS_L1':'(0,0,0,0,0,0,0,0,BN19,0,0,0,0,0,0,0,0,0,0,0,0,0,0,0,0,0,0,0,0,~
0,0,0,0,0,0,0,0,0,0,0)';$S;OUT;
    'MIA_DQS_L1':'(0,0,0,0,0,0,0,0,P20,0,0,0,0,0,0,0,0,0,0,0,0,0,0,0,0,0,0,0,0,0~
,0,0,0,0,0,0,0,0,0,0)';$S;BIDI;
    'MIA_DATA25':'(0,0,0,0,0,0,0,0,AD21,0,0,0,0,0,0,0,0,0,0,0,0,0,0,0,0,0,0,0,0,~
0,0,0,0,0,0,0,0,0,0,0)';$S;BIDI;
    'MIA_DATA14':'(0,0,0,0,0,0,0,0,T20,0,0,0,0,0,0,0,0,0,0,0,0,0,0,0,0,0,0,0,0,0~
,0,0,0,0,0,0,0,0,0,0)';$S;BIDI;
    'MIA_DATA2':'(0,0,0,0,0,0,0,0,F20,0,0,0,0,0,0,0,0,0,0,0,0,0,0,0,0,0,0,0,0,0,~
0,0,0,0,0,0,0,0,0,0)';$S;BIDI;
    'MIA_CHECK5':'(0,0,0,0,0,0,0,0,AP21,0,0,0,0,0,0,0,0,0,0,0,0,0,0,0,0,0,0,0,0,~
0,0,0,0,0,0,0,0,0,0,0)';$S;BIDI;
    'MIB_DQS_H9':'(0,0,0,0,0,0,0,0,BV20,0,0,0,0,0,0,0,0,0,0,0,0,0,0,0,0,0,0,0,0,~
0,0,0,0,0,0,0,0,0,0,0)';$S;BIDI;
    'MIB_DATA31':'(0,0,0,0,0,0,0,0,DF21,0,0,0,0,0,0,0,0,0,0,0,0,0,0,0,0,0,0,0,0,~
0,0,0,0,0,0,0,0,0,0,0)';$S;BIDI;
    'MIB_DATA20':'(0,0,0,0,0,0,0,0,CV20,0,0,0,0,0,0,0,0,0,0,0,0,0,0,0,0,0,0,0,0,~
0,0,0,0,0,0,0,0,0,0,0)';$S;BIDI;
    'MIB_DATA3':'(0,0,0,0,0,0,0,0,CD21,0,0,0,0,0,0,0,0,0,0,0,0,0,0,0,0,0,0,0,0,0~
,0,0,0,0,0,0,0,0,0,0)';$S;BIDI;
    'MIB_CHECK0':'(0,0,0,0,0,0,0,0,BY20,0,0,0,0,0,0,0,0,0,0,0,0,0,0,0,0,0,0,0,0,~
0,0,0,0,0,0,0,0,0,0,0)';$S;BIDI;
    'MIB1_CS_L1':'(0,0,0,0,0,0,0,0,BM20,0,0,0,0,0,0,0,0,0,0,0,0,0,0,0,0,0,0,0,0,~
0,0,0,0,0,0,0,0,0,0,0)';$S;OUT;
    'MIA_PAR':'(0,0,0,0,0,0,0,0,BC21,0,0,0,0,0,0,0,0,0,0,0,0,0,0,0,0,0,0,0,0,0,0~
,0,0,0,0,0,0,0,0,0)';$S;OUT;
    'MIA_DQS_L2':'(0,0,0,0,0,0,0,0,Y20,0,0,0,0,0,0,0,0,0,0,0,0,0,0,0,0,0,0,0,0,0~
,0,0,0,0,0,0,0,0,0,0)';$S;BIDI;
    'MIA_DATA26':'(0,0,0,0,0,0,0,0,AD20,0,0,0,0,0,0,0,0,0,0,0,0,0,0,0,0,0,0,0,0,~
0,0,0,0,0,0,0,0,0,0,0)';$S;BIDI;
    'MIA_DATA15':'(0,0,0,0,0,0,0,0,U21,0,0,0,0,0,0,0,0,0,0,0,0,0,0,0,0,0,0,0,0,0~
,0,0,0,0,0,0,0,0,0,0)';$S;BIDI;
    'MIA_DATA3':'(0,0,0,0,0,0,0,0,G21,0,0,0,0,0,0,0,0,0,0,0,0,0,0,0,0,0,0,0,0,0,~
0,0,0,0,0,0,0,0,0,0)';$S;BIDI;
    'MIA_CHECK6':'(0,0,0,0,0,0,0,0,AP20,0,0,0,0,0,0,0,0,0,0,0,0,0,0,0,0,0,0,0,0,~
0,0,0,0,0,0,0,0,0,0,0)';$S;BIDI;
    'MIB_PAR':'(0,0,0,0,0,0,0,0,BL21,0,0,0,0,0,0,0,0,0,0,0,0,0,0,0,0,0,0,0,0,0,0~
,0,0,0,0,0,0,0,0,0)';$S;OUT;
    'MIB_DATA21':'(0,0,0,0,0,0,0,0,CW21,0,0,0,0,0,0,0,0,0,0,0,0,0,0,0,0,0,0,0,0,~
0,0,0,0,0,0,0,0,0,0,0)';$S;BIDI;
    'MIB_DATA10':'(0,0,0,0,0,0,0,0,CJ19,0,0,0,0,0,0,0,0,0,0,0,0,0,0,0,0,0,0,0,0,~
0,0,0,0,0,0,0,0,0,0,0)';$S;BIDI;
    'MIB_DATA4':'(0,0,0,0,0,0,0,0,CF20,0,0,0,0,0,0,0,0,0,0,0,0,0,0,0,0,0,0,0,0,0~
,0,0,0,0,0,0,0,0,0,0)';$S;BIDI;
    'MIB_CHECK1':'(0,0,0,0,0,0,0,0,CA21,0,0,0,0,0,0,0,0,0,0,0,0,0,0,0,0,0,0,0,0,~
0,0,0,0,0,0,0,0,0,0,0)';$S;BIDI;
    'MIA_DQS_L3':'(0,0,0,0,0,0,0,0,AF20,0,0,0,0,0,0,0,0,0,0,0,0,0,0,0,0,0,0,0,0,~
0,0,0,0,0,0,0,0,0,0,0)';$S;BIDI;
    'MIA_DATA27':'(0,0,0,0,0,0,0,0,AE21,0,0,0,0,0,0,0,0,0,0,0,0,0,0,0,0,0,0,0,0,~
0,0,0,0,0,0,0,0,0,0,0)';$S;BIDI;
    'MIA_DATA16':'(0,0,0,0,0,0,0,0,U19,0,0,0,0,0,0,0,0,0,0,0,0,0,0,0,0,0,0,0,0,0~
,0,0,0,0,0,0,0,0,0,0)';$S;BIDI;
    'MIA_DATA4':'(0,0,0,0,0,0,0,0,J19,0,0,0,0,0,0,0,0,0,0,0,0,0,0,0,0,0,0,0,0,0,~
0,0,0,0,0,0,0,0,0,0)';$S;BIDI;
    'MIA_CHECK7':'(0,0,0,0,0,0,0,0,AR21,0,0,0,0,0,0,0,0,0,0,0,0,0,0,0,0,0,0,0,0,~
0,0,0,0,0,0,0,0,0,0,0)';$S;BIDI;
    'MIA1_RSP_L':'(0,0,0,0,0,0,0,0,BP21,0,0,0,0,0,0,0,0,0,0,0,0,0,0,0,0,0,0,0,0,~
0,0,0,0,0,0,0,0,0,0,0)';$S;IN;
    'MIA0_RSP_L':'(0,0,0,0,0,0,0,0,BN21,0,0,0,0,0,0,0,0,0,0,0,0,0,0,0,0,0,0,0,0,~
0,0,0,0,0,0,0,0,0,0,0)';$S;IN;
    'MI_ALERT_L':'(0,0,0,0,0,0,0,0,AT21,0,0,0,0,0,0,0,0,0,0,0,0,0,0,0,0,0,0,0,0,~
0,0,0,0,0,0,0,0,0,0,0)';$S;IN;
    'MIB_DATA22':'(0,0,0,0,0,0,0,0,CW19,0,0,0,0,0,0,0,0,0,0,0,0,0,0,0,0,0,0,0,0,~
0,0,0,0,0,0,0,0,0,0,0)';$S;BIDI;
    'MIB_DATA11':'(0,0,0,0,0,0,0,0,CK21,0,0,0,0,0,0,0,0,0,0,0,0,0,0,0,0,0,0,0,0,~
0,0,0,0,0,0,0,0,0,0,0)';$S;BIDI;
    'MIB_DATA5':'(0,0,0,0,0,0,0,0,CG21,0,0,0,0,0,0,0,0,0,0,0,0,0,0,0,0,0,0,0,0,0~
,0,0,0,0,0,0,0,0,0,0)';$S;BIDI;
    'MIB_CHECK2':'(0,0,0,0,0,0,0,0,CA19,0,0,0,0,0,0,0,0,0,0,0,0,0,0,0,0,0,0,0,0,~
0,0,0,0,0,0,0,0,0,0,0)';$S;BIDI;
    'MIA_DQS_L4':'(0,0,0,0,0,0,0,0,AM20,0,0,0,0,0,0,0,0,0,0,0,0,0,0,0,0,0,0,0,0,~
0,0,0,0,0,0,0,0,0,0,0)';$S;BIDI;
    'MIA_DQS_H0':'(0,0,0,0,0,0,0,0,G19,0,0,0,0,0,0,0,0,0,0,0,0,0,0,0,0,0,0,0,0,0~
,0,0,0,0,0,0,0,0,0,0)';$S;BIDI;
    'MIA_DATA28':'(0,0,0,0,0,0,0,0,AG19,0,0,0,0,0,0,0,0,0,0,0,0,0,0,0,0,0,0,0,0,~
0,0,0,0,0,0,0,0,0,0,0)';$S;BIDI;
    'MIA_DATA17':'(0,0,0,0,0,0,0,0,V21,0,0,0,0,0,0,0,0,0,0,0,0,0,0,0,0,0,0,0,0,0~
,0,0,0,0,0,0,0,0,0,0)';$S;BIDI;
    'MIA_DATA5':'(0,0,0,0,0,0,0,0,K21,0,0,0,0,0,0,0,0,0,0,0,0,0,0,0,0,0,0,0,0,0,~
0,0,0,0,0,0,0,0,0,0)';$S;BIDI;
    'TEST39I':'(0,0,0,0,0,0,0,0,BF21,0,0,0,0,0,0,0,0,0,0,0,0,0,0,0,0,0,0,0,0,0,0~
,0,0,0,0,0,0,0,0,0)';$S;OUT;
    'MJ_RESET_L':'(0,0,0,0,0,0,0,0,0,AU17,0,0,0,0,0,0,0,0,0,0,0,0,0,0,0,0,0,0,0,~
0,0,0,0,0,0,0,0,0,0,0)';$S;OUT;
    'MJ_ALERT_L':'(0,0,0,0,0,0,0,0,0,AT18,0,0,0,0,0,0,0,0,0,0,0,0,0,0,0,0,0,0,0,~
0,0,0,0,0,0,0,0,0,0,0)';$S;IN;
    'MJB_PAR':'(0,0,0,0,0,0,0,0,0,BL17,0,0,0,0,0,0,0,0,0,0,0,0,0,0,0,0,0,0,0,0,0~
,0,0,0,0,0,0,0,0,0)';$S;OUT;
    'MJB_DQS_L9':'(0,0,0,0,0,0,0,0,0,BW16,0,0,0,0,0,0,0,0,0,0,0,0,0,0,0,0,0,0,0,~
0,0,0,0,0,0,0,0,0,0,0)';$S;BIDI;
    'MJB_DQS_L8':'(0,0,0,0,0,0,0,0,0,DC17,0,0,0,0,0,0,0,0,0,0,0,0,0,0,0,0,0,0,0,~
0,0,0,0,0,0,0,0,0,0,0)';$S;BIDI;
    'MJB_DQS_L7':'(0,0,0,0,0,0,0,0,0,CU17,0,0,0,0,0,0,0,0,0,0,0,0,0,0,0,0,0,0,0,~
0,0,0,0,0,0,0,0,0,0,0)';$S;BIDI;
    'MJB_DQS_L6':'(0,0,0,0,0,0,0,0,0,CL17,0,0,0,0,0,0,0,0,0,0,0,0,0,0,0,0,0,0,0,~
0,0,0,0,0,0,0,0,0,0,0)';$S;BIDI;
    'MJB_DQS_L5':'(0,0,0,0,0,0,0,0,0,CE17,0,0,0,0,0,0,0,0,0,0,0,0,0,0,0,0,0,0,0,~
0,0,0,0,0,0,0,0,0,0,0)';$S;BIDI;
    'MJB_DQS_L3':'(0,0,0,0,0,0,0,0,0,DC16,0,0,0,0,0,0,0,0,0,0,0,0,0,0,0,0,0,0,0,~
0,0,0,0,0,0,0,0,0,0,0)';$S;BIDI;
    'MJB_DQS_L2':'(0,0,0,0,0,0,0,0,0,CU16,0,0,0,0,0,0,0,0,0,0,0,0,0,0,0,0,0,0,0,~
0,0,0,0,0,0,0,0,0,0,0)';$S;BIDI;
    'MJB_DQS_L1':'(0,0,0,0,0,0,0,0,0,CL16,0,0,0,0,0,0,0,0,0,0,0,0,0,0,0,0,0,0,0,~
0,0,0,0,0,0,0,0,0,0,0)';$S;BIDI;
    'MJB_DQS_H9':'(0,0,0,0,0,0,0,0,0,BV16,0,0,0,0,0,0,0,0,0,0,0,0,0,0,0,0,0,0,0,~
0,0,0,0,0,0,0,0,0,0,0)';$S;BIDI;
    'MJB_DQS_H8':'(0,0,0,0,0,0,0,0,0,DD18,0,0,0,0,0,0,0,0,0,0,0,0,0,0,0,0,0,0,0,~
0,0,0,0,0,0,0,0,0,0,0)';$S;BIDI;
    'MJB_DQS_H7':'(0,0,0,0,0,0,0,0,0,CV18,0,0,0,0,0,0,0,0,0,0,0,0,0,0,0,0,0,0,0,~
0,0,0,0,0,0,0,0,0,0,0)';$S;BIDI;
    'MJB_DQS_H6':'(0,0,0,0,0,0,0,0,0,CM18,0,0,0,0,0,0,0,0,0,0,0,0,0,0,0,0,0,0,0,~
0,0,0,0,0,0,0,0,0,0,0)';$S;BIDI;
    'MJB_DQS_H4':'(0,0,0,0,0,0,0,0,0,BY18,0,0,0,0,0,0,0,0,0,0,0,0,0,0,0,0,0,0,0,~
0,0,0,0,0,0,0,0,0,0,0)';$S;BIDI;
    'MJB_DQS_H3':'(0,0,0,0,0,0,0,0,0,DB16,0,0,0,0,0,0,0,0,0,0,0,0,0,0,0,0,0,0,0,~
0,0,0,0,0,0,0,0,0,0,0)';$S;BIDI;
    'MJB_DQS_H2':'(0,0,0,0,0,0,0,0,0,CT16,0,0,0,0,0,0,0,0,0,0,0,0,0,0,0,0,0,0,0,~
0,0,0,0,0,0,0,0,0,0,0)';$S;BIDI;
    'MJB_DQS_H1':'(0,0,0,0,0,0,0,0,0,CK16,0,0,0,0,0,0,0,0,0,0,0,0,0,0,0,0,0,0,0,~
0,0,0,0,0,0,0,0,0,0,0)';$S;BIDI;
    'MJB_DQS_H0':'(0,0,0,0,0,0,0,0,0,CD16,0,0,0,0,0,0,0,0,0,0,0,0,0,0,0,0,0,0,0,~
0,0,0,0,0,0,0,0,0,0,0)';$S;BIDI;
    'MJB_DATA31':'(0,0,0,0,0,0,0,0,0,DF16,0,0,0,0,0,0,0,0,0,0,0,0,0,0,0,0,0,0,0,~
0,0,0,0,0,0,0,0,0,0,0)';$S;BIDI;
    'MJB_DATA30':'(0,0,0,0,0,0,0,0,0,DE16,0,0,0,0,0,0,0,0,0,0,0,0,0,0,0,0,0,0,0,~
0,0,0,0,0,0,0,0,0,0,0)';$S;BIDI;
    'MJB_DATA29':'(0,0,0,0,0,0,0,0,0,DE17,0,0,0,0,0,0,0,0,0,0,0,0,0,0,0,0,0,0,0,~
0,0,0,0,0,0,0,0,0,0,0)';$S;BIDI;
    'MJB_DATA28':'(0,0,0,0,0,0,0,0,0,DD16,0,0,0,0,0,0,0,0,0,0,0,0,0,0,0,0,0,0,0,~
0,0,0,0,0,0,0,0,0,0,0)';$S;BIDI;
    'MJB_DATA27':'(0,0,0,0,0,0,0,0,0,DB18,0,0,0,0,0,0,0,0,0,0,0,0,0,0,0,0,0,0,0,~
0,0,0,0,0,0,0,0,0,0,0)';$S;BIDI;
    'MJB_DATA26':'(0,0,0,0,0,0,0,0,0,DA16,0,0,0,0,0,0,0,0,0,0,0,0,0,0,0,0,0,0,0,~
0,0,0,0,0,0,0,0,0,0,0)';$S;BIDI;
    'MJB_DATA25':'(0,0,0,0,0,0,0,0,0,DA17,0,0,0,0,0,0,0,0,0,0,0,0,0,0,0,0,0,0,0,~
0,0,0,0,0,0,0,0,0,0,0)';$S;BIDI;
    'MJB_DATA24':'(0,0,0,0,0,0,0,0,0,CY16,0,0,0,0,0,0,0,0,0,0,0,0,0,0,0,0,0,0,0,~
0,0,0,0,0,0,0,0,0,0,0)';$S;BIDI;
    'MJB_DATA23':'(0,0,0,0,0,0,0,0,0,CY18,0,0,0,0,0,0,0,0,0,0,0,0,0,0,0,0,0,0,0,~
0,0,0,0,0,0,0,0,0,0,0)';$S;BIDI;
    'MJB_DATA22':'(0,0,0,0,0,0,0,0,0,CW16,0,0,0,0,0,0,0,0,0,0,0,0,0,0,0,0,0,0,0,~
0,0,0,0,0,0,0,0,0,0,0)';$S;BIDI;
    'MJB_DATA21':'(0,0,0,0,0,0,0,0,0,CW17,0,0,0,0,0,0,0,0,0,0,0,0,0,0,0,0,0,0,0,~
0,0,0,0,0,0,0,0,0,0,0)';$S;BIDI;
    'MJB_DATA20':'(0,0,0,0,0,0,0,0,0,CV16,0,0,0,0,0,0,0,0,0,0,0,0,0,0,0,0,0,0,0,~
0,0,0,0,0,0,0,0,0,0,0)';$S;BIDI;
    'MJB_DATA19':'(0,0,0,0,0,0,0,0,0,CT18,0,0,0,0,0,0,0,0,0,0,0,0,0,0,0,0,0,0,0,~
0,0,0,0,0,0,0,0,0,0,0)';$S;BIDI;
    'MJB_DATA18':'(0,0,0,0,0,0,0,0,0,CR16,0,0,0,0,0,0,0,0,0,0,0,0,0,0,0,0,0,0,0,~
0,0,0,0,0,0,0,0,0,0,0)';$S;BIDI;
    'MJB_DATA17':'(0,0,0,0,0,0,0,0,0,CR17,0,0,0,0,0,0,0,0,0,0,0,0,0,0,0,0,0,0,0,~
0,0,0,0,0,0,0,0,0,0,0)';$S;BIDI;
    'MJB_DATA16':'(0,0,0,0,0,0,0,0,0,CP16,0,0,0,0,0,0,0,0,0,0,0,0,0,0,0,0,0,0,0,~
0,0,0,0,0,0,0,0,0,0,0)';$S;BIDI;
    'MJB_DATA15':'(0,0,0,0,0,0,0,0,0,CP18,0,0,0,0,0,0,0,0,0,0,0,0,0,0,0,0,0,0,0,~
0,0,0,0,0,0,0,0,0,0,0)';$S;BIDI;
    'MJB_DATA14':'(0,0,0,0,0,0,0,0,0,CN16,0,0,0,0,0,0,0,0,0,0,0,0,0,0,0,0,0,0,0,~
0,0,0,0,0,0,0,0,0,0,0)';$S;BIDI;
    'MJB_DATA13':'(0,0,0,0,0,0,0,0,0,CN17,0,0,0,0,0,0,0,0,0,0,0,0,0,0,0,0,0,0,0,~
0,0,0,0,0,0,0,0,0,0,0)';$S;BIDI;
    'MJB_DATA12':'(0,0,0,0,0,0,0,0,0,CM16,0,0,0,0,0,0,0,0,0,0,0,0,0,0,0,0,0,0,0,~
0,0,0,0,0,0,0,0,0,0,0)';$S;BIDI;
    'MJB_DATA11':'(0,0,0,0,0,0,0,0,0,CK18,0,0,0,0,0,0,0,0,0,0,0,0,0,0,0,0,0,0,0,~
0,0,0,0,0,0,0,0,0,0,0)';$S;BIDI;
    'MJB_DATA10':'(0,0,0,0,0,0,0,0,0,CJ16,0,0,0,0,0,0,0,0,0,0,0,0,0,0,0,0,0,0,0,~
0,0,0,0,0,0,0,0,0,0,0)';$S;BIDI;
    'MJB_DATA9':'(0,0,0,0,0,0,0,0,0,CJ17,0,0,0,0,0,0,0,0,0,0,0,0,0,0,0,0,0,0,0,0~
,0,0,0,0,0,0,0,0,0,0)';$S;BIDI;
    'MJB_DATA8':'(0,0,0,0,0,0,0,0,0,CH16,0,0,0,0,0,0,0,0,0,0,0,0,0,0,0,0,0,0,0,0~
,0,0,0,0,0,0,0,0,0,0)';$S;BIDI;
    'MJB_DATA2':'(0,0,0,0,0,0,0,0,0,CC16,0,0,0,0,0,0,0,0,0,0,0,0,0,0,0,0,0,0,0,0~
,0,0,0,0,0,0,0,0,0,0)';$S;BIDI;
    'MJB_DATA1':'(0,0,0,0,0,0,0,0,0,CC17,0,0,0,0,0,0,0,0,0,0,0,0,0,0,0,0,0,0,0,0~
,0,0,0,0,0,0,0,0,0,0)';$S;BIDI;
    'MJB_CHECK7':'(0,0,0,0,0,0,0,0,0,BV18,0,0,0,0,0,0,0,0,0,0,0,0,0,0,0,0,0,0,0,~
0,0,0,0,0,0,0,0,0,0,0)';$S;BIDI;
    'MJB_CHECK6':'(0,0,0,0,0,0,0,0,0,BU16,0,0,0,0,0,0,0,0,0,0,0,0,0,0,0,0,0,0,0,~
0,0,0,0,0,0,0,0,0,0,0)';$S;BIDI;
    'MJB_CHECK5':'(0,0,0,0,0,0,0,0,0,BU17,0,0,0,0,0,0,0,0,0,0,0,0,0,0,0,0,0,0,0,~
0,0,0,0,0,0,0,0,0,0,0)';$S;BIDI;
    'MJB_CHECK4':'(0,0,0,0,0,0,0,0,0,BT16,0,0,0,0,0,0,0,0,0,0,0,0,0,0,0,0,0,0,0,~
0,0,0,0,0,0,0,0,0,0,0)';$S;BIDI;
    'MJB_CHECK3':'(0,0,0,0,0,0,0,0,0,CB18,0,0,0,0,0,0,0,0,0,0,0,0,0,0,0,0,0,0,0,~
0,0,0,0,0,0,0,0,0,0,0)';$S;BIDI;
    'MJB_CHECK2':'(0,0,0,0,0,0,0,0,0,CA16,0,0,0,0,0,0,0,0,0,0,0,0,0,0,0,0,0,0,0,~
0,0,0,0,0,0,0,0,0,0,0)';$S;BIDI;
    'MJB_CHECK1':'(0,0,0,0,0,0,0,0,0,CA17,0,0,0,0,0,0,0,0,0,0,0,0,0,0,0,0,0,0,0,~
0,0,0,0,0,0,0,0,0,0,0)';$S;BIDI;
    'MJB_CHECK0':'(0,0,0,0,0,0,0,0,0,BY16,0,0,0,0,0,0,0,0,0,0,0,0,0,0,0,0,0,0,0,~
0,0,0,0,0,0,0,0,0,0,0)';$S;BIDI;
    'MJB_CA6':'(0,0,0,0,0,0,0,0,0,BK16,0,0,0,0,0,0,0,0,0,0,0,0,0,0,0,0,0,0,0,0,0~
,0,0,0,0,0,0,0,0,0)';$S;OUT;
    'MJB_CA5':'(0,0,0,0,0,0,0,0,0,BK18,0,0,0,0,0,0,0,0,0,0,0,0,0,0,0,0,0,0,0,0,0~
,0,0,0,0,0,0,0,0,0)';$S;OUT;
    'MJB_CA4':'(0,0,0,0,0,0,0,0,0,BJ17,0,0,0,0,0,0,0,0,0,0,0,0,0,0,0,0,0,0,0,0,0~
,0,0,0,0,0,0,0,0,0)';$S;OUT;
    'MJB_CA3':'(0,0,0,0,0,0,0,0,0,BJ16,0,0,0,0,0,0,0,0,0,0,0,0,0,0,0,0,0,0,0,0,0~
,0,0,0,0,0,0,0,0,0)';$S;OUT;
    'MJB_CA2':'(0,0,0,0,0,0,0,0,0,BH16,0,0,0,0,0,0,0,0,0,0,0,0,0,0,0,0,0,0,0,0,0~
,0,0,0,0,0,0,0,0,0)';$S;OUT;
    'MJB_CA1':'(0,0,0,0,0,0,0,0,0,BH18,0,0,0,0,0,0,0,0,0,0,0,0,0,0,0,0,0,0,0,0,0~
,0,0,0,0,0,0,0,0,0)';$S;OUT;
    'MJB_CA0':'(0,0,0,0,0,0,0,0,0,BG17,0,0,0,0,0,0,0,0,0,0,0,0,0,0,0,0,0,0,0,0,0~
,0,0,0,0,0,0,0,0,0)';$S;OUT;
    'MJB1_RSP_L':'(0,0,0,0,0,0,0,0,0,BR16,0,0,0,0,0,0,0,0,0,0,0,0,0,0,0,0,0,0,0,~
0,0,0,0,0,0,0,0,0,0,0)';$S;IN;
    'MJB1_CS_L1':'(0,0,0,0,0,0,0,0,0,BM16,0,0,0,0,0,0,0,0,0,0,0,0,0,0,0,0,0,0,0,~
0,0,0,0,0,0,0,0,0,0,0)';$S;OUT;
    'MJB1_CS_L0':'(0,0,0,0,0,0,0,0,0,BL16,0,0,0,0,0,0,0,0,0,0,0,0,0,0,0,0,0,0,0,~
0,0,0,0,0,0,0,0,0,0,0)';$S;OUT;
    'MJB0_RSP_L':'(0,0,0,0,0,0,0,0,0,BP16,0,0,0,0,0,0,0,0,0,0,0,0,0,0,0,0,0,0,0,~
0,0,0,0,0,0,0,0,0,0,0)';$S;IN;
    'MJB0_CS_L1':'(0,0,0,0,0,0,0,0,0,BN16,0,0,0,0,0,0,0,0,0,0,0,0,0,0,0,0,0,0,0,~
0,0,0,0,0,0,0,0,0,0,0)';$S;OUT;
    'MJB0_CS_L0':'(0,0,0,0,0,0,0,0,0,BM18,0,0,0,0,0,0,0,0,0,0,0,0,0,0,0,0,0,0,0,~
0,0,0,0,0,0,0,0,0,0,0)';$S;OUT;
    'MJA_PAR':'(0,0,0,0,0,0,0,0,0,BC17,0,0,0,0,0,0,0,0,0,0,0,0,0,0,0,0,0,0,0,0,0~
,0,0,0,0,0,0,0,0,0)';$S;OUT;
    'MJA_DQS_L9':'(0,0,0,0,0,0,0,0,0,AM18,0,0,0,0,0,0,0,0,0,0,0,0,0,0,0,0,0,0,0,~
0,0,0,0,0,0,0,0,0,0,0)';$S;BIDI;
    'MJA_DQS_L8':'(0,0,0,0,0,0,0,0,0,AF18,0,0,0,0,0,0,0,0,0,0,0,0,0,0,0,0,0,0,0,~
0,0,0,0,0,0,0,0,0,0,0)';$S;BIDI;
    'MJA_DQS_L6':'(0,0,0,0,0,0,0,0,0,P18,0,0,0,0,0,0,0,0,0,0,0,0,0,0,0,0,0,0,0,0~
,0,0,0,0,0,0,0,0,0,0)';$S;BIDI;
    'MJA_DQS_L3':'(0,0,0,0,0,0,0,0,0,AF16,0,0,0,0,0,0,0,0,0,0,0,0,0,0,0,0,0,0,0,~
0,0,0,0,0,0,0,0,0,0,0)';$S;BIDI;
    'MJA_DQS_L2':'(0,0,0,0,0,0,0,0,0,Y16,0,0,0,0,0,0,0,0,0,0,0,0,0,0,0,0,0,0,0,0~
,0,0,0,0,0,0,0,0,0,0)';$S;BIDI;
    'MJA_DQS_L1':'(0,0,0,0,0,0,0,0,0,P16,0,0,0,0,0,0,0,0,0,0,0,0,0,0,0,0,0,0,0,0~
,0,0,0,0,0,0,0,0,0,0)';$S;BIDI;
    'MJA_DQS_L0':'(0,0,0,0,0,0,0,0,0,H16,0,0,0,0,0,0,0,0,0,0,0,0,0,0,0,0,0,0,0,0~
,0,0,0,0,0,0,0,0,0,0)';$S;BIDI;
    'MJA_DQS_H9':'(0,0,0,0,0,0,0,0,0,AN17,0,0,0,0,0,0,0,0,0,0,0,0,0,0,0,0,0,0,0,~
0,0,0,0,0,0,0,0,0,0,0)';$S;BIDI;
    'MJA_DQS_H7':'(0,0,0,0,0,0,0,0,0,AA17,0,0,0,0,0,0,0,0,0,0,0,0,0,0,0,0,0,0,0,~
0,0,0,0,0,0,0,0,0,0,0)';$S;BIDI;
    'MJA_DQS_H6':'(0,0,0,0,0,0,0,0,0,R17,0,0,0,0,0,0,0,0,0,0,0,0,0,0,0,0,0,0,0,0~
,0,0,0,0,0,0,0,0,0,0)';$S;BIDI;
    'MJA_DQS_H5':'(0,0,0,0,0,0,0,0,0,J17,0,0,0,0,0,0,0,0,0,0,0,0,0,0,0,0,0,0,0,0~
,0,0,0,0,0,0,0,0,0,0)';$S;BIDI;
    'MJA_DQS_H3':'(0,0,0,0,0,0,0,0,0,AE16,0,0,0,0,0,0,0,0,0,0,0,0,0,0,0,0,0,0,0,~
0,0,0,0,0,0,0,0,0,0,0)';$S;BIDI;
    'MJA_DQS_H2':'(0,0,0,0,0,0,0,0,0,W16,0,0,0,0,0,0,0,0,0,0,0,0,0,0,0,0,0,0,0,0~
,0,0,0,0,0,0,0,0,0,0)';$S;BIDI;
    'MJA_DQS_H1':'(0,0,0,0,0,0,0,0,0,N16,0,0,0,0,0,0,0,0,0,0,0,0,0,0,0,0,0,0,0,0~
,0,0,0,0,0,0,0,0,0,0)';$S;BIDI;
    'MJA_DQS_H0':'(0,0,0,0,0,0,0,0,0,G16,0,0,0,0,0,0,0,0,0,0,0,0,0,0,0,0,0,0,0,0~
,0,0,0,0,0,0,0,0,0,0)';$S;BIDI;
    'MJA_DATA30':'(0,0,0,0,0,0,0,0,0,AH16,0,0,0,0,0,0,0,0,0,0,0,0,0,0,0,0,0,0,0,~
0,0,0,0,0,0,0,0,0,0,0)';$S;BIDI;
    'MJA_DATA29':'(0,0,0,0,0,0,0,0,0,AH18,0,0,0,0,0,0,0,0,0,0,0,0,0,0,0,0,0,0,0,~
0,0,0,0,0,0,0,0,0,0,0)';$S;BIDI;
    'MJA_DATA28':'(0,0,0,0,0,0,0,0,0,AG16,0,0,0,0,0,0,0,0,0,0,0,0,0,0,0,0,0,0,0,~
0,0,0,0,0,0,0,0,0,0,0)';$S;BIDI;
    'MJA_DATA27':'(0,0,0,0,0,0,0,0,0,AE17,0,0,0,0,0,0,0,0,0,0,0,0,0,0,0,0,0,0,0,~
0,0,0,0,0,0,0,0,0,0,0)';$S;BIDI;
    'MJA_DATA26':'(0,0,0,0,0,0,0,0,0,AD16,0,0,0,0,0,0,0,0,0,0,0,0,0,0,0,0,0,0,0,~
0,0,0,0,0,0,0,0,0,0,0)';$S;BIDI;
    'MJA_DATA25':'(0,0,0,0,0,0,0,0,0,AD18,0,0,0,0,0,0,0,0,0,0,0,0,0,0,0,0,0,0,0,~
0,0,0,0,0,0,0,0,0,0,0)';$S;BIDI;
    'MJA_DATA24':'(0,0,0,0,0,0,0,0,0,AC16,0,0,0,0,0,0,0,0,0,0,0,0,0,0,0,0,0,0,0,~
0,0,0,0,0,0,0,0,0,0,0)';$S;BIDI;
    'MJA_DATA23':'(0,0,0,0,0,0,0,0,0,AC17,0,0,0,0,0,0,0,0,0,0,0,0,0,0,0,0,0,0,0,~
0,0,0,0,0,0,0,0,0,0,0)';$S;BIDI;
    'MJA_DATA21':'(0,0,0,0,0,0,0,0,0,AB18,0,0,0,0,0,0,0,0,0,0,0,0,0,0,0,0,0,0,0,~
0,0,0,0,0,0,0,0,0,0,0)';$S;BIDI;
    'MJA_DATA20':'(0,0,0,0,0,0,0,0,0,AA16,0,0,0,0,0,0,0,0,0,0,0,0,0,0,0,0,0,0,0,~
0,0,0,0,0,0,0,0,0,0,0)';$S;BIDI;
    'MJA_DATA19':'(0,0,0,0,0,0,0,0,0,W17,0,0,0,0,0,0,0,0,0,0,0,0,0,0,0,0,0,0,0,0~
,0,0,0,0,0,0,0,0,0,0)';$S;BIDI;
    'MJA_DATA18':'(0,0,0,0,0,0,0,0,0,V16,0,0,0,0,0,0,0,0,0,0,0,0,0,0,0,0,0,0,0,0~
,0,0,0,0,0,0,0,0,0,0)';$S;BIDI;
    'MJA_DATA17':'(0,0,0,0,0,0,0,0,0,V18,0,0,0,0,0,0,0,0,0,0,0,0,0,0,0,0,0,0,0,0~
,0,0,0,0,0,0,0,0,0,0)';$S;BIDI;
    'MJA_DATA16':'(0,0,0,0,0,0,0,0,0,U16,0,0,0,0,0,0,0,0,0,0,0,0,0,0,0,0,0,0,0,0~
,0,0,0,0,0,0,0,0,0,0)';$S;BIDI;
    'MJA_DATA15':'(0,0,0,0,0,0,0,0,0,U17,0,0,0,0,0,0,0,0,0,0,0,0,0,0,0,0,0,0,0,0~
,0,0,0,0,0,0,0,0,0,0)';$S;BIDI;
    'MJA_DATA14':'(0,0,0,0,0,0,0,0,0,T16,0,0,0,0,0,0,0,0,0,0,0,0,0,0,0,0,0,0,0,0~
,0,0,0,0,0,0,0,0,0,0)';$S;BIDI;
    'MJA_DATA13':'(0,0,0,0,0,0,0,0,0,T18,0,0,0,0,0,0,0,0,0,0,0,0,0,0,0,0,0,0,0,0~
,0,0,0,0,0,0,0,0,0,0)';$S;BIDI;
    'MJA_DATA12':'(0,0,0,0,0,0,0,0,0,R16,0,0,0,0,0,0,0,0,0,0,0,0,0,0,0,0,0,0,0,0~
,0,0,0,0,0,0,0,0,0,0)';$S;BIDI;
    'MJA_DATA11':'(0,0,0,0,0,0,0,0,0,N17,0,0,0,0,0,0,0,0,0,0,0,0,0,0,0,0,0,0,0,0~
,0,0,0,0,0,0,0,0,0,0)';$S;BIDI;
    'MJA_DATA10':'(0,0,0,0,0,0,0,0,0,M16,0,0,0,0,0,0,0,0,0,0,0,0,0,0,0,0,0,0,0,0~
,0,0,0,0,0,0,0,0,0,0)';$S;BIDI;
    'MJA_DATA9':'(0,0,0,0,0,0,0,0,0,M18,0,0,0,0,0,0,0,0,0,0,0,0,0,0,0,0,0,0,0,0,~
0,0,0,0,0,0,0,0,0,0)';$S;BIDI;
    'MJA_DATA8':'(0,0,0,0,0,0,0,0,0,L16,0,0,0,0,0,0,0,0,0,0,0,0,0,0,0,0,0,0,0,0,~
0,0,0,0,0,0,0,0,0,0)';$S;BIDI;
    'MJA_DATA7':'(0,0,0,0,0,0,0,0,0,L17,0,0,0,0,0,0,0,0,0,0,0,0,0,0,0,0,0,0,0,0,~
0,0,0,0,0,0,0,0,0,0)';$S;BIDI;
    'MJA_DATA6':'(0,0,0,0,0,0,0,0,0,K16,0,0,0,0,0,0,0,0,0,0,0,0,0,0,0,0,0,0,0,0,~
0,0,0,0,0,0,0,0,0,0)';$S;BIDI;
    'MJA_DATA5':'(0,0,0,0,0,0,0,0,0,K18,0,0,0,0,0,0,0,0,0,0,0,0,0,0,0,0,0,0,0,0,~
0,0,0,0,0,0,0,0,0,0)';$S;BIDI;
    'MJA_DATA4':'(0,0,0,0,0,0,0,0,0,J16,0,0,0,0,0,0,0,0,0,0,0,0,0,0,0,0,0,0,0,0,~
0,0,0,0,0,0,0,0,0,0)';$S;BIDI;
    'MJA_DATA3':'(0,0,0,0,0,0,0,0,0,G17,0,0,0,0,0,0,0,0,0,0,0,0,0,0,0,0,0,0,0,0,~
0,0,0,0,0,0,0,0,0,0)';$S;BIDI;
    'MJA_DATA2':'(0,0,0,0,0,0,0,0,0,F16,0,0,0,0,0,0,0,0,0,0,0,0,0,0,0,0,0,0,0,0,~
0,0,0,0,0,0,0,0,0,0)';$S;BIDI;
    'MJA_DATA1':'(0,0,0,0,0,0,0,0,0,F18,0,0,0,0,0,0,0,0,0,0,0,0,0,0,0,0,0,0,0,0,~
0,0,0,0,0,0,0,0,0,0)';$S;BIDI;
    'MJA_DATA0':'(0,0,0,0,0,0,0,0,0,E16,0,0,0,0,0,0,0,0,0,0,0,0,0,0,0,0,0,0,0,0,~
0,0,0,0,0,0,0,0,0,0)';$S;BIDI;
    'MJA_CHECK7':'(0,0,0,0,0,0,0,0,0,AR17,0,0,0,0,0,0,0,0,0,0,0,0,0,0,0,0,0,0,0,~
0,0,0,0,0,0,0,0,0,0,0)';$S;BIDI;
    'MJA_CHECK6':'(0,0,0,0,0,0,0,0,0,AP16,0,0,0,0,0,0,0,0,0,0,0,0,0,0,0,0,0,0,0,~
0,0,0,0,0,0,0,0,0,0,0)';$S;BIDI;
    'MJA_CHECK5':'(0,0,0,0,0,0,0,0,0,AP18,0,0,0,0,0,0,0,0,0,0,0,0,0,0,0,0,0,0,0,~
0,0,0,0,0,0,0,0,0,0,0)';$S;BIDI;
    'MJA_CHECK4':'(0,0,0,0,0,0,0,0,0,AN16,0,0,0,0,0,0,0,0,0,0,0,0,0,0,0,0,0,0,0,~
0,0,0,0,0,0,0,0,0,0,0)';$S;BIDI;
    'MJA_CHECK3':'(0,0,0,0,0,0,0,0,0,AL17,0,0,0,0,0,0,0,0,0,0,0,0,0,0,0,0,0,0,0,~
0,0,0,0,0,0,0,0,0,0,0)';$S;BIDI;
    'MJA_CHECK2':'(0,0,0,0,0,0,0,0,0,AK16,0,0,0,0,0,0,0,0,0,0,0,0,0,0,0,0,0,0,0,~
0,0,0,0,0,0,0,0,0,0,0)';$S;BIDI;
    'MJA_CHECK1':'(0,0,0,0,0,0,0,0,0,AK18,0,0,0,0,0,0,0,0,0,0,0,0,0,0,0,0,0,0,0,~
0,0,0,0,0,0,0,0,0,0,0)';$S;BIDI;
    'MJA_CHECK0':'(0,0,0,0,0,0,0,0,0,AJ16,0,0,0,0,0,0,0,0,0,0,0,0,0,0,0,0,0,0,0,~
0,0,0,0,0,0,0,0,0,0,0)';$S;BIDI;
    'MJA_CA4':'(0,0,0,0,0,0,0,0,0,BA16,0,0,0,0,0,0,0,0,0,0,0,0,0,0,0,0,0,0,0,0,0~
,0,0,0,0,0,0,0,0,0)';$S;OUT;
    'MJA_CA3':'(0,0,0,0,0,0,0,0,0,BA17,0,0,0,0,0,0,0,0,0,0,0,0,0,0,0,0,0,0,0,0,0~
,0,0,0,0,0,0,0,0,0)';$S;OUT;
    'MJA_CA2':'(0,0,0,0,0,0,0,0,0,AY18,0,0,0,0,0,0,0,0,0,0,0,0,0,0,0,0,0,0,0,0,0~
,0,0,0,0,0,0,0,0,0)';$S;OUT;
    'MJA_CA1':'(0,0,0,0,0,0,0,0,0,AY16,0,0,0,0,0,0,0,0,0,0,0,0,0,0,0,0,0,0,0,0,0~
,0,0,0,0,0,0,0,0,0)';$S;OUT;
    'MJA_CA0':'(0,0,0,0,0,0,0,0,0,AW16,0,0,0,0,0,0,0,0,0,0,0,0,0,0,0,0,0,0,0,0,0~
,0,0,0,0,0,0,0,0,0)';$S;OUT;
    'MJA1_RSP_L':'(0,0,0,0,0,0,0,0,0,BP18,0,0,0,0,0,0,0,0,0,0,0,0,0,0,0,0,0,0,0,~
0,0,0,0,0,0,0,0,0,0,0)';$S;IN;
    'MJA1_CS_L1':'(0,0,0,0,0,0,0,0,0,AW17,0,0,0,0,0,0,0,0,0,0,0,0,0,0,0,0,0,0,0,~
0,0,0,0,0,0,0,0,0,0,0)';$S;OUT;
    'MJA1_CS_L0':'(0,0,0,0,0,0,0,0,0,AV16,0,0,0,0,0,0,0,0,0,0,0,0,0,0,0,0,0,0,0,~
0,0,0,0,0,0,0,0,0,0,0)';$S;OUT;
    'MJA0_RSP_L':'(0,0,0,0,0,0,0,0,0,BN17,0,0,0,0,0,0,0,0,0,0,0,0,0,0,0,0,0,0,0,~
0,0,0,0,0,0,0,0,0,0,0)';$S;IN;
    'MJA0_CS_L1':'(0,0,0,0,0,0,0,0,0,AV18,0,0,0,0,0,0,0,0,0,0,0,0,0,0,0,0,0,0,0,~
0,0,0,0,0,0,0,0,0,0,0)';$S;OUT;
    'MJA0_CS_L0':'(0,0,0,0,0,0,0,0,0,AU16,0,0,0,0,0,0,0,0,0,0,0,0,0,0,0,0,0,0,0,~
0,0,0,0,0,0,0,0,0,0,0)';$S;OUT;
    'MJ1_CLK_L':'(0,0,0,0,0,0,0,0,0,BG16,0,0,0,0,0,0,0,0,0,0,0,0,0,0,0,0,0,0,0,0~
,0,0,0,0,0,0,0,0,0,0)';$S;OUT;
    'MJ1_CLK_H':'(0,0,0,0,0,0,0,0,0,BF16,0,0,0,0,0,0,0,0,0,0,0,0,0,0,0,0,0,0,0,0~
,0,0,0,0,0,0,0,0,0,0)';$S;OUT;
    'MJ0_CLK_L':'(0,0,0,0,0,0,0,0,0,BD16,0,0,0,0,0,0,0,0,0,0,0,0,0,0,0,0,0,0,0,0~
,0,0,0,0,0,0,0,0,0,0)';$S;OUT;
    'MJ0_CLK_H':'(0,0,0,0,0,0,0,0,0,BC16,0,0,0,0,0,0,0,0,0,0,0,0,0,0,0,0,0,0,0,0~
,0,0,0,0,0,0,0,0,0,0)';$S;OUT;
    'MJA_CA6':'(0,0,0,0,0,0,0,0,0,BB18,0,0,0,0,0,0,0,0,0,0,0,0,0,0,0,0,0,0,0,0,0~
,0,0,0,0,0,0,0,0,0)';$S;OUT;
    'MJA_CA5':'(0,0,0,0,0,0,0,0,0,BB16,0,0,0,0,0,0,0,0,0,0,0,0,0,0,0,0,0,0,0,0,0~
,0,0,0,0,0,0,0,0,0)';$S;OUT;
    'MJA_DATA22':'(0,0,0,0,0,0,0,0,0,AB16,0,0,0,0,0,0,0,0,0,0,0,0,0,0,0,0,0,0,0,~
0,0,0,0,0,0,0,0,0,0,0)';$S;BIDI;
    'MJA_DQS_L7':'(0,0,0,0,0,0,0,0,0,Y18,0,0,0,0,0,0,0,0,0,0,0,0,0,0,0,0,0,0,0,0~
,0,0,0,0,0,0,0,0,0,0)';$S;BIDI;
    'MJA_DQS_L5':'(0,0,0,0,0,0,0,0,0,H18,0,0,0,0,0,0,0,0,0,0,0,0,0,0,0,0,0,0,0,0~
,0,0,0,0,0,0,0,0,0,0)';$S;BIDI;
    'MJA_DQS_L4':'(0,0,0,0,0,0,0,0,0,AM16,0,0,0,0,0,0,0,0,0,0,0,0,0,0,0,0,0,0,0,~
0,0,0,0,0,0,0,0,0,0,0)';$S;BIDI;
    'MJA_DQS_H8':'(0,0,0,0,0,0,0,0,0,AG17,0,0,0,0,0,0,0,0,0,0,0,0,0,0,0,0,0,0,0,~
0,0,0,0,0,0,0,0,0,0,0)';$S;BIDI;
    'MJA_DQS_H4':'(0,0,0,0,0,0,0,0,0,AL16,0,0,0,0,0,0,0,0,0,0,0,0,0,0,0,0,0,0,0,~
0,0,0,0,0,0,0,0,0,0,0)';$S;BIDI;
    'MJB_DATA4':'(0,0,0,0,0,0,0,0,0,CF16,0,0,0,0,0,0,0,0,0,0,0,0,0,0,0,0,0,0,0,0~
,0,0,0,0,0,0,0,0,0,0)';$S;BIDI;
    'MJB_DATA3':'(0,0,0,0,0,0,0,0,0,CD18,0,0,0,0,0,0,0,0,0,0,0,0,0,0,0,0,0,0,0,0~
,0,0,0,0,0,0,0,0,0,0)';$S;BIDI;
    'MJB_DATA0':'(0,0,0,0,0,0,0,0,0,CB16,0,0,0,0,0,0,0,0,0,0,0,0,0,0,0,0,0,0,0,0~
,0,0,0,0,0,0,0,0,0,0)';$S;BIDI;
    'MJA_DATA31':'(0,0,0,0,0,0,0,0,0,AJ17,0,0,0,0,0,0,0,0,0,0,0,0,0,0,0,0,0,0,0,~
0,0,0,0,0,0,0,0,0,0,0)';$S;BIDI;
    'MJB_DQS_L0':'(0,0,0,0,0,0,0,0,0,CE16,0,0,0,0,0,0,0,0,0,0,0,0,0,0,0,0,0,0,0,~
0,0,0,0,0,0,0,0,0,0,0)';$S;BIDI;
    'MJB_DQS_L4':'(0,0,0,0,0,0,0,0,0,BW17,0,0,0,0,0,0,0,0,0,0,0,0,0,0,0,0,0,0,0,~
0,0,0,0,0,0,0,0,0,0,0)';$S;BIDI;
    'MJB_DQS_H5':'(0,0,0,0,0,0,0,0,0,CF18,0,0,0,0,0,0,0,0,0,0,0,0,0,0,0,0,0,0,0,~
0,0,0,0,0,0,0,0,0,0,0)';$S;BIDI;
    'MJB_DATA5':'(0,0,0,0,0,0,0,0,0,CG17,0,0,0,0,0,0,0,0,0,0,0,0,0,0,0,0,0,0,0,0~
,0,0,0,0,0,0,0,0,0,0)';$S;BIDI;
    'MJB_DATA6':'(0,0,0,0,0,0,0,0,0,CG16,0,0,0,0,0,0,0,0,0,0,0,0,0,0,0,0,0,0,0,0~
,0,0,0,0,0,0,0,0,0,0)';$S;BIDI;
    'MJB_DATA7':'(0,0,0,0,0,0,0,0,0,CH18,0,0,0,0,0,0,0,0,0,0,0,0,0,0,0,0,0,0,0,0~
,0,0,0,0,0,0,0,0,0,0)';$S;BIDI;
    'TEST39J':'(0,0,0,0,0,0,0,0,0,BF18,0,0,0,0,0,0,0,0,0,0,0,0,0,0,0,0,0,0,0,0,0~
,0,0,0,0,0,0,0,0,0)';$S;OUT;
    'G0_RXN0':'(0,0,0,0,0,0,0,0,0,0,M40,0,0,0,0,0,0,0,0,0,0,0,0,0,0,0,0,0,0,0,0,~
0,0,0,0,0,0,0,0,0)';$S;IN;
    'G0_RXN1':'(0,0,0,0,0,0,0,0,0,0,K40,0,0,0,0,0,0,0,0,0,0,0,0,0,0,0,0,0,0,0,0,~
0,0,0,0,0,0,0,0,0)';$S;IN;
    'G0_RXN2':'(0,0,0,0,0,0,0,0,0,0,H40,0,0,0,0,0,0,0,0,0,0,0,0,0,0,0,0,0,0,0,0,~
0,0,0,0,0,0,0,0,0)';$S;IN;
    'G0_RXN3':'(0,0,0,0,0,0,0,0,0,0,L43,0,0,0,0,0,0,0,0,0,0,0,0,0,0,0,0,0,0,0,0,~
0,0,0,0,0,0,0,0,0)';$S;IN;
    'G0_RXN4':'(0,0,0,0,0,0,0,0,0,0,G43,0,0,0,0,0,0,0,0,0,0,0,0,0,0,0,0,0,0,0,0,~
0,0,0,0,0,0,0,0,0)';$S;IN;
    'G0_RXN5':'(0,0,0,0,0,0,0,0,0,0,J43,0,0,0,0,0,0,0,0,0,0,0,0,0,0,0,0,0,0,0,0,~
0,0,0,0,0,0,0,0,0)';$S;IN;
    'G0_RXN6':'(0,0,0,0,0,0,0,0,0,0,L46,0,0,0,0,0,0,0,0,0,0,0,0,0,0,0,0,0,0,0,0,~
0,0,0,0,0,0,0,0,0)';$S;IN;
    'G0_RXN7':'(0,0,0,0,0,0,0,0,0,0,G46,0,0,0,0,0,0,0,0,0,0,0,0,0,0,0,0,0,0,0,0,~
0,0,0,0,0,0,0,0,0)';$S;IN;
    'G0_RXN8':'(0,0,0,0,0,0,0,0,0,0,J46,0,0,0,0,0,0,0,0,0,0,0,0,0,0,0,0,0,0,0,0,~
0,0,0,0,0,0,0,0,0)';$S;IN;
    'G0_RXN9':'(0,0,0,0,0,0,0,0,0,0,L49,0,0,0,0,0,0,0,0,0,0,0,0,0,0,0,0,0,0,0,0,~
0,0,0,0,0,0,0,0,0)';$S;IN;
    'G0_RXN10':'(0,0,0,0,0,0,0,0,0,0,G49,0,0,0,0,0,0,0,0,0,0,0,0,0,0,0,0,0,0,0,0~
,0,0,0,0,0,0,0,0,0)';$S;IN;
    'G0_RXN11':'(0,0,0,0,0,0,0,0,0,0,J49,0,0,0,0,0,0,0,0,0,0,0,0,0,0,0,0,0,0,0,0~
,0,0,0,0,0,0,0,0,0)';$S;IN;
    'G0_RXN12':'(0,0,0,0,0,0,0,0,0,0,L52,0,0,0,0,0,0,0,0,0,0,0,0,0,0,0,0,0,0,0,0~
,0,0,0,0,0,0,0,0,0)';$S;IN;
    'G0_RXN13':'(0,0,0,0,0,0,0,0,0,0,G52,0,0,0,0,0,0,0,0,0,0,0,0,0,0,0,0,0,0,0,0~
,0,0,0,0,0,0,0,0,0)';$S;IN;
    'G0_RXN14':'(0,0,0,0,0,0,0,0,0,0,J52,0,0,0,0,0,0,0,0,0,0,0,0,0,0,0,0,0,0,0,0~
,0,0,0,0,0,0,0,0,0)';$S;IN;
    'G0_RXN15':'(0,0,0,0,0,0,0,0,0,0,N52,0,0,0,0,0,0,0,0,0,0,0,0,0,0,0,0,0,0,0,0~
,0,0,0,0,0,0,0,0,0)';$S;IN;
    'G0_RXP0':'(0,0,0,0,0,0,0,0,0,0,M41,0,0,0,0,0,0,0,0,0,0,0,0,0,0,0,0,0,0,0,0,~
0,0,0,0,0,0,0,0,0)';$S;IN;
    'G0_RXP1':'(0,0,0,0,0,0,0,0,0,0,K41,0,0,0,0,0,0,0,0,0,0,0,0,0,0,0,0,0,0,0,0,~
0,0,0,0,0,0,0,0,0)';$S;IN;
    'G0_RXP2':'(0,0,0,0,0,0,0,0,0,0,H41,0,0,0,0,0,0,0,0,0,0,0,0,0,0,0,0,0,0,0,0,~
0,0,0,0,0,0,0,0,0)';$S;IN;
    'G0_RXP3':'(0,0,0,0,0,0,0,0,0,0,L44,0,0,0,0,0,0,0,0,0,0,0,0,0,0,0,0,0,0,0,0,~
0,0,0,0,0,0,0,0,0)';$S;IN;
    'G0_RXP4':'(0,0,0,0,0,0,0,0,0,0,G44,0,0,0,0,0,0,0,0,0,0,0,0,0,0,0,0,0,0,0,0,~
0,0,0,0,0,0,0,0,0)';$S;IN;
    'G0_RXP5':'(0,0,0,0,0,0,0,0,0,0,J44,0,0,0,0,0,0,0,0,0,0,0,0,0,0,0,0,0,0,0,0,~
0,0,0,0,0,0,0,0,0)';$S;IN;
    'G0_RXP6':'(0,0,0,0,0,0,0,0,0,0,L47,0,0,0,0,0,0,0,0,0,0,0,0,0,0,0,0,0,0,0,0,~
0,0,0,0,0,0,0,0,0)';$S;IN;
    'G0_RXP7':'(0,0,0,0,0,0,0,0,0,0,G47,0,0,0,0,0,0,0,0,0,0,0,0,0,0,0,0,0,0,0,0,~
0,0,0,0,0,0,0,0,0)';$S;IN;
    'G0_RXP8':'(0,0,0,0,0,0,0,0,0,0,J47,0,0,0,0,0,0,0,0,0,0,0,0,0,0,0,0,0,0,0,0,~
0,0,0,0,0,0,0,0,0)';$S;IN;
    'G0_RXP9':'(0,0,0,0,0,0,0,0,0,0,L50,0,0,0,0,0,0,0,0,0,0,0,0,0,0,0,0,0,0,0,0,~
0,0,0,0,0,0,0,0,0)';$S;IN;
    'G0_RXP10':'(0,0,0,0,0,0,0,0,0,0,G50,0,0,0,0,0,0,0,0,0,0,0,0,0,0,0,0,0,0,0,0~
,0,0,0,0,0,0,0,0,0)';$S;IN;
    'G0_RXP11':'(0,0,0,0,0,0,0,0,0,0,J50,0,0,0,0,0,0,0,0,0,0,0,0,0,0,0,0,0,0,0,0~
,0,0,0,0,0,0,0,0,0)';$S;IN;
    'G0_RXP12':'(0,0,0,0,0,0,0,0,0,0,L53,0,0,0,0,0,0,0,0,0,0,0,0,0,0,0,0,0,0,0,0~
,0,0,0,0,0,0,0,0,0)';$S;IN;
    'G0_RXP13':'(0,0,0,0,0,0,0,0,0,0,G53,0,0,0,0,0,0,0,0,0,0,0,0,0,0,0,0,0,0,0,0~
,0,0,0,0,0,0,0,0,0)';$S;IN;
    'G0_RXP14':'(0,0,0,0,0,0,0,0,0,0,J53,0,0,0,0,0,0,0,0,0,0,0,0,0,0,0,0,0,0,0,0~
,0,0,0,0,0,0,0,0,0)';$S;IN;
    'G0_RXP15':'(0,0,0,0,0,0,0,0,0,0,N53,0,0,0,0,0,0,0,0,0,0,0,0,0,0,0,0,0,0,0,0~
,0,0,0,0,0,0,0,0,0)';$S;IN;
    'G0_TXN0':'(0,0,0,0,0,0,0,0,0,0,AF41,0,0,0,0,0,0,0,0,0,0,0,0,0,0,0,0,0,0,0,0~
,0,0,0,0,0,0,0,0,0)';$S;OUT;
    'G0_TXN1':'(0,0,0,0,0,0,0,0,0,0,AD41,0,0,0,0,0,0,0,0,0,0,0,0,0,0,0,0,0,0,0,0~
,0,0,0,0,0,0,0,0,0)';$S;OUT;
    'G0_TXN2':'(0,0,0,0,0,0,0,0,0,0,AB41,0,0,0,0,0,0,0,0,0,0,0,0,0,0,0,0,0,0,0,0~
,0,0,0,0,0,0,0,0,0)';$S;OUT;
    'G0_TXN3':'(0,0,0,0,0,0,0,0,0,0,AG44,0,0,0,0,0,0,0,0,0,0,0,0,0,0,0,0,0,0,0,0~
,0,0,0,0,0,0,0,0,0)';$S;OUT;
    'G0_TXN4':'(0,0,0,0,0,0,0,0,0,0,AA44,0,0,0,0,0,0,0,0,0,0,0,0,0,0,0,0,0,0,0,0~
,0,0,0,0,0,0,0,0,0)';$S;OUT;
    'G0_TXN5':'(0,0,0,0,0,0,0,0,0,0,AC44,0,0,0,0,0,0,0,0,0,0,0,0,0,0,0,0,0,0,0,0~
,0,0,0,0,0,0,0,0,0)';$S;OUT;
    'G0_TXN6':'(0,0,0,0,0,0,0,0,0,0,AE44,0,0,0,0,0,0,0,0,0,0,0,0,0,0,0,0,0,0,0,0~
,0,0,0,0,0,0,0,0,0)';$S;OUT;
    'G0_TXN7':'(0,0,0,0,0,0,0,0,0,0,AG47,0,0,0,0,0,0,0,0,0,0,0,0,0,0,0,0,0,0,0,0~
,0,0,0,0,0,0,0,0,0)';$S;OUT;
    'G0_TXN8':'(0,0,0,0,0,0,0,0,0,0,AC47,0,0,0,0,0,0,0,0,0,0,0,0,0,0,0,0,0,0,0,0~
,0,0,0,0,0,0,0,0,0)';$S;OUT;
    'G0_TXN9':'(0,0,0,0,0,0,0,0,0,0,AE47,0,0,0,0,0,0,0,0,0,0,0,0,0,0,0,0,0,0,0,0~
,0,0,0,0,0,0,0,0,0)';$S;OUT;
    'G0_TXN10':'(0,0,0,0,0,0,0,0,0,0,AG50,0,0,0,0,0,0,0,0,0,0,0,0,0,0,0,0,0,0,0,~
0,0,0,0,0,0,0,0,0,0)';$S;OUT;
    'G0_TXN11':'(0,0,0,0,0,0,0,0,0,0,AC50,0,0,0,0,0,0,0,0,0,0,0,0,0,0,0,0,0,0,0,~
0,0,0,0,0,0,0,0,0,0)';$S;OUT;
    'G0_TXN12':'(0,0,0,0,0,0,0,0,0,0,AE50,0,0,0,0,0,0,0,0,0,0,0,0,0,0,0,0,0,0,0,~
0,0,0,0,0,0,0,0,0,0)';$S;OUT;
    'G0_TXN13':'(0,0,0,0,0,0,0,0,0,0,AG53,0,0,0,0,0,0,0,0,0,0,0,0,0,0,0,0,0,0,0,~
0,0,0,0,0,0,0,0,0,0)';$S;OUT;
    'G0_TXN14':'(0,0,0,0,0,0,0,0,0,0,AC53,0,0,0,0,0,0,0,0,0,0,0,0,0,0,0,0,0,0,0,~
0,0,0,0,0,0,0,0,0,0)';$S;OUT;
    'G0_TXN15':'(0,0,0,0,0,0,0,0,0,0,AE53,0,0,0,0,0,0,0,0,0,0,0,0,0,0,0,0,0,0,0,~
0,0,0,0,0,0,0,0,0,0)';$S;OUT;
    'G0_TXP0':'(0,0,0,0,0,0,0,0,0,0,AF40,0,0,0,0,0,0,0,0,0,0,0,0,0,0,0,0,0,0,0,0~
,0,0,0,0,0,0,0,0,0)';$S;OUT;
    'G0_TXP1':'(0,0,0,0,0,0,0,0,0,0,AD40,0,0,0,0,0,0,0,0,0,0,0,0,0,0,0,0,0,0,0,0~
,0,0,0,0,0,0,0,0,0)';$S;OUT;
    'G0_TXP2':'(0,0,0,0,0,0,0,0,0,0,AB40,0,0,0,0,0,0,0,0,0,0,0,0,0,0,0,0,0,0,0,0~
,0,0,0,0,0,0,0,0,0)';$S;OUT;
    'G0_TXP3':'(0,0,0,0,0,0,0,0,0,0,AG43,0,0,0,0,0,0,0,0,0,0,0,0,0,0,0,0,0,0,0,0~
,0,0,0,0,0,0,0,0,0)';$S;OUT;
    'G0_TXP4':'(0,0,0,0,0,0,0,0,0,0,AA43,0,0,0,0,0,0,0,0,0,0,0,0,0,0,0,0,0,0,0,0~
,0,0,0,0,0,0,0,0,0)';$S;OUT;
    'G0_TXP5':'(0,0,0,0,0,0,0,0,0,0,AC43,0,0,0,0,0,0,0,0,0,0,0,0,0,0,0,0,0,0,0,0~
,0,0,0,0,0,0,0,0,0)';$S;OUT;
    'G0_TXP6':'(0,0,0,0,0,0,0,0,0,0,AE43,0,0,0,0,0,0,0,0,0,0,0,0,0,0,0,0,0,0,0,0~
,0,0,0,0,0,0,0,0,0)';$S;OUT;
    'G0_TXP7':'(0,0,0,0,0,0,0,0,0,0,AG46,0,0,0,0,0,0,0,0,0,0,0,0,0,0,0,0,0,0,0,0~
,0,0,0,0,0,0,0,0,0)';$S;OUT;
    'G0_TXP8':'(0,0,0,0,0,0,0,0,0,0,AC46,0,0,0,0,0,0,0,0,0,0,0,0,0,0,0,0,0,0,0,0~
,0,0,0,0,0,0,0,0,0)';$S;OUT;
    'G0_TXP9':'(0,0,0,0,0,0,0,0,0,0,AE46,0,0,0,0,0,0,0,0,0,0,0,0,0,0,0,0,0,0,0,0~
,0,0,0,0,0,0,0,0,0)';$S;OUT;
    'G0_TXP10':'(0,0,0,0,0,0,0,0,0,0,AG49,0,0,0,0,0,0,0,0,0,0,0,0,0,0,0,0,0,0,0,~
0,0,0,0,0,0,0,0,0,0)';$S;OUT;
    'G0_TXP11':'(0,0,0,0,0,0,0,0,0,0,AC49,0,0,0,0,0,0,0,0,0,0,0,0,0,0,0,0,0,0,0,~
0,0,0,0,0,0,0,0,0,0)';$S;OUT;
    'G0_TXP12':'(0,0,0,0,0,0,0,0,0,0,AE49,0,0,0,0,0,0,0,0,0,0,0,0,0,0,0,0,0,0,0,~
0,0,0,0,0,0,0,0,0,0)';$S;OUT;
    'G0_TXP13':'(0,0,0,0,0,0,0,0,0,0,AG52,0,0,0,0,0,0,0,0,0,0,0,0,0,0,0,0,0,0,0,~
0,0,0,0,0,0,0,0,0,0)';$S;OUT;
    'G0_TXP14':'(0,0,0,0,0,0,0,0,0,0,AC52,0,0,0,0,0,0,0,0,0,0,0,0,0,0,0,0,0,0,0,~
0,0,0,0,0,0,0,0,0,0)';$S;OUT;
    'G0_TXP15':'(0,0,0,0,0,0,0,0,0,0,AE52,0,0,0,0,0,0,0,0,0,0,0,0,0,0,0,0,0,0,0,~
0,0,0,0,0,0,0,0,0,0)';$S;OUT;
    'G1_TXP15':'(0,0,0,0,0,0,0,0,0,0,0,AL52,0,0,0,0,0,0,0,0,0,0,0,0,0,0,0,0,0,0,~
0,0,0,0,0,0,0,0,0,0)';$S;OUT;
    'G1_TXP14':'(0,0,0,0,0,0,0,0,0,0,0,AJ52,0,0,0,0,0,0,0,0,0,0,0,0,0,0,0,0,0,0,~
0,0,0,0,0,0,0,0,0,0)';$S;OUT;
    'G1_TXP13':'(0,0,0,0,0,0,0,0,0,0,0,AN52,0,0,0,0,0,0,0,0,0,0,0,0,0,0,0,0,0,0,~
0,0,0,0,0,0,0,0,0,0)';$S;OUT;
    'G1_TXP12':'(0,0,0,0,0,0,0,0,0,0,0,AL49,0,0,0,0,0,0,0,0,0,0,0,0,0,0,0,0,0,0,~
0,0,0,0,0,0,0,0,0,0)';$S;OUT;
    'G1_TXP11':'(0,0,0,0,0,0,0,0,0,0,0,AJ49,0,0,0,0,0,0,0,0,0,0,0,0,0,0,0,0,0,0,~
0,0,0,0,0,0,0,0,0,0)';$S;OUT;
    'G1_TXP10':'(0,0,0,0,0,0,0,0,0,0,0,AN49,0,0,0,0,0,0,0,0,0,0,0,0,0,0,0,0,0,0,~
0,0,0,0,0,0,0,0,0,0)';$S;OUT;
    'G1_TXP9':'(0,0,0,0,0,0,0,0,0,0,0,AL46,0,0,0,0,0,0,0,0,0,0,0,0,0,0,0,0,0,0,0~
,0,0,0,0,0,0,0,0,0)';$S;OUT;
    'G1_TXP8':'(0,0,0,0,0,0,0,0,0,0,0,AJ46,0,0,0,0,0,0,0,0,0,0,0,0,0,0,0,0,0,0,0~
,0,0,0,0,0,0,0,0,0)';$S;OUT;
    'G1_TXN15':'(0,0,0,0,0,0,0,0,0,0,0,AL53,0,0,0,0,0,0,0,0,0,0,0,0,0,0,0,0,0,0,~
0,0,0,0,0,0,0,0,0,0)';$S;OUT;
    'G1_TXN14':'(0,0,0,0,0,0,0,0,0,0,0,AJ53,0,0,0,0,0,0,0,0,0,0,0,0,0,0,0,0,0,0,~
0,0,0,0,0,0,0,0,0,0)';$S;OUT;
    'G1_TXN13':'(0,0,0,0,0,0,0,0,0,0,0,AN53,0,0,0,0,0,0,0,0,0,0,0,0,0,0,0,0,0,0,~
0,0,0,0,0,0,0,0,0,0)';$S;OUT;
    'G1_TXN12':'(0,0,0,0,0,0,0,0,0,0,0,AL50,0,0,0,0,0,0,0,0,0,0,0,0,0,0,0,0,0,0,~
0,0,0,0,0,0,0,0,0,0)';$S;OUT;
    'G1_TXN11':'(0,0,0,0,0,0,0,0,0,0,0,AJ50,0,0,0,0,0,0,0,0,0,0,0,0,0,0,0,0,0,0,~
0,0,0,0,0,0,0,0,0,0)';$S;OUT;
    'G1_TXN10':'(0,0,0,0,0,0,0,0,0,0,0,AN50,0,0,0,0,0,0,0,0,0,0,0,0,0,0,0,0,0,0,~
0,0,0,0,0,0,0,0,0,0)';$S;OUT;
    'G1_TXN9':'(0,0,0,0,0,0,0,0,0,0,0,AL47,0,0,0,0,0,0,0,0,0,0,0,0,0,0,0,0,0,0,0~
,0,0,0,0,0,0,0,0,0)';$S;OUT;
    'G1_TXN8':'(0,0,0,0,0,0,0,0,0,0,0,AJ47,0,0,0,0,0,0,0,0,0,0,0,0,0,0,0,0,0,0,0~
,0,0,0,0,0,0,0,0,0)';$S;OUT;
    'G1_RXP15':'(0,0,0,0,0,0,0,0,0,0,0,U53,0,0,0,0,0,0,0,0,0,0,0,0,0,0,0,0,0,0,0~
,0,0,0,0,0,0,0,0,0)';$S;IN;
    'G1_RXP14':'(0,0,0,0,0,0,0,0,0,0,0,R53,0,0,0,0,0,0,0,0,0,0,0,0,0,0,0,0,0,0,0~
,0,0,0,0,0,0,0,0,0)';$S;IN;
    'G1_RXP13':'(0,0,0,0,0,0,0,0,0,0,0,W53,0,0,0,0,0,0,0,0,0,0,0,0,0,0,0,0,0,0,0~
,0,0,0,0,0,0,0,0,0)';$S;IN;
    'G1_RXP12':'(0,0,0,0,0,0,0,0,0,0,0,U50,0,0,0,0,0,0,0,0,0,0,0,0,0,0,0,0,0,0,0~
,0,0,0,0,0,0,0,0,0)';$S;IN;
    'G1_RXP11':'(0,0,0,0,0,0,0,0,0,0,0,R50,0,0,0,0,0,0,0,0,0,0,0,0,0,0,0,0,0,0,0~
,0,0,0,0,0,0,0,0,0)';$S;IN;
    'G1_RXP10':'(0,0,0,0,0,0,0,0,0,0,0,N50,0,0,0,0,0,0,0,0,0,0,0,0,0,0,0,0,0,0,0~
,0,0,0,0,0,0,0,0,0)';$S;IN;
    'G1_RXP9':'(0,0,0,0,0,0,0,0,0,0,0,W50,0,0,0,0,0,0,0,0,0,0,0,0,0,0,0,0,0,0,0,~
0,0,0,0,0,0,0,0,0)';$S;IN;
    'G1_RXP8':'(0,0,0,0,0,0,0,0,0,0,0,R47,0,0,0,0,0,0,0,0,0,0,0,0,0,0,0,0,0,0,0,~
0,0,0,0,0,0,0,0,0)';$S;IN;
    'G1_RXN15':'(0,0,0,0,0,0,0,0,0,0,0,U52,0,0,0,0,0,0,0,0,0,0,0,0,0,0,0,0,0,0,0~
,0,0,0,0,0,0,0,0,0)';$S;IN;
    'G1_RXN14':'(0,0,0,0,0,0,0,0,0,0,0,R52,0,0,0,0,0,0,0,0,0,0,0,0,0,0,0,0,0,0,0~
,0,0,0,0,0,0,0,0,0)';$S;IN;
    'G1_RXN13':'(0,0,0,0,0,0,0,0,0,0,0,W52,0,0,0,0,0,0,0,0,0,0,0,0,0,0,0,0,0,0,0~
,0,0,0,0,0,0,0,0,0)';$S;IN;
    'G1_RXN12':'(0,0,0,0,0,0,0,0,0,0,0,U49,0,0,0,0,0,0,0,0,0,0,0,0,0,0,0,0,0,0,0~
,0,0,0,0,0,0,0,0,0)';$S;IN;
    'G1_RXN11':'(0,0,0,0,0,0,0,0,0,0,0,R49,0,0,0,0,0,0,0,0,0,0,0,0,0,0,0,0,0,0,0~
,0,0,0,0,0,0,0,0,0)';$S;IN;
    'G1_RXN10':'(0,0,0,0,0,0,0,0,0,0,0,N49,0,0,0,0,0,0,0,0,0,0,0,0,0,0,0,0,0,0,0~
,0,0,0,0,0,0,0,0,0)';$S;IN;
    'G1_RXN9':'(0,0,0,0,0,0,0,0,0,0,0,W49,0,0,0,0,0,0,0,0,0,0,0,0,0,0,0,0,0,0,0,~
0,0,0,0,0,0,0,0,0)';$S;IN;
    'G1_RXN8':'(0,0,0,0,0,0,0,0,0,0,0,R46,0,0,0,0,0,0,0,0,0,0,0,0,0,0,0,0,0,0,0,~
0,0,0,0,0,0,0,0,0)';$S;IN;
    'G1_TXP0':'(0,0,0,0,0,0,0,0,0,0,0,AP40,0,0,0,0,0,0,0,0,0,0,0,0,0,0,0,0,0,0,0~
,0,0,0,0,0,0,0,0,0)';$S;OUT;
    'G1_TXP1':'(0,0,0,0,0,0,0,0,0,0,0,AM40,0,0,0,0,0,0,0,0,0,0,0,0,0,0,0,0,0,0,0~
,0,0,0,0,0,0,0,0,0)';$S;OUT;
    'G1_TXP2':'(0,0,0,0,0,0,0,0,0,0,0,AH40,0,0,0,0,0,0,0,0,0,0,0,0,0,0,0,0,0,0,0~
,0,0,0,0,0,0,0,0,0)';$S;OUT;
    'G1_TXN0':'(0,0,0,0,0,0,0,0,0,0,0,AP41,0,0,0,0,0,0,0,0,0,0,0,0,0,0,0,0,0,0,0~
,0,0,0,0,0,0,0,0,0)';$S;OUT;
    'G1_RXP0':'(0,0,0,0,0,0,0,0,0,0,0,V41,0,0,0,0,0,0,0,0,0,0,0,0,0,0,0,0,0,0,0,~
0,0,0,0,0,0,0,0,0)';$S;IN;
    'G1_TXP3':'(0,0,0,0,0,0,0,0,0,0,0,AK40,0,0,0,0,0,0,0,0,0,0,0,0,0,0,0,0,0,0,0~
,0,0,0,0,0,0,0,0,0)';$S;OUT;
    'G1_TXN1':'(0,0,0,0,0,0,0,0,0,0,0,AM41,0,0,0,0,0,0,0,0,0,0,0,0,0,0,0,0,0,0,0~
,0,0,0,0,0,0,0,0,0)';$S;OUT;
    'G1_RXP1':'(0,0,0,0,0,0,0,0,0,0,0,T41,0,0,0,0,0,0,0,0,0,0,0,0,0,0,0,0,0,0,0,~
0,0,0,0,0,0,0,0,0)';$S;IN;
    'G1_TXP4':'(0,0,0,0,0,0,0,0,0,0,0,AN43,0,0,0,0,0,0,0,0,0,0,0,0,0,0,0,0,0,0,0~
,0,0,0,0,0,0,0,0,0)';$S;OUT;
    'G1_TXN2':'(0,0,0,0,0,0,0,0,0,0,0,AH41,0,0,0,0,0,0,0,0,0,0,0,0,0,0,0,0,0,0,0~
,0,0,0,0,0,0,0,0,0)';$S;OUT;
    'G1_RXP2':'(0,0,0,0,0,0,0,0,0,0,0,P41,0,0,0,0,0,0,0,0,0,0,0,0,0,0,0,0,0,0,0,~
0,0,0,0,0,0,0,0,0)';$S;IN;
    'G1_RXN0':'(0,0,0,0,0,0,0,0,0,0,0,V40,0,0,0,0,0,0,0,0,0,0,0,0,0,0,0,0,0,0,0,~
0,0,0,0,0,0,0,0,0)';$S;IN;
    'G1_TXP5':'(0,0,0,0,0,0,0,0,0,0,0,AJ43,0,0,0,0,0,0,0,0,0,0,0,0,0,0,0,0,0,0,0~
,0,0,0,0,0,0,0,0,0)';$S;OUT;
    'G1_TXN3':'(0,0,0,0,0,0,0,0,0,0,0,AK41,0,0,0,0,0,0,0,0,0,0,0,0,0,0,0,0,0,0,0~
,0,0,0,0,0,0,0,0,0)';$S;OUT;
    'G1_RXP3':'(0,0,0,0,0,0,0,0,0,0,0,U44,0,0,0,0,0,0,0,0,0,0,0,0,0,0,0,0,0,0,0,~
0,0,0,0,0,0,0,0,0)';$S;IN;
    'G1_RXN1':'(0,0,0,0,0,0,0,0,0,0,0,T40,0,0,0,0,0,0,0,0,0,0,0,0,0,0,0,0,0,0,0,~
0,0,0,0,0,0,0,0,0)';$S;IN;
    'G1_TXP6':'(0,0,0,0,0,0,0,0,0,0,0,AL43,0,0,0,0,0,0,0,0,0,0,0,0,0,0,0,0,0,0,0~
,0,0,0,0,0,0,0,0,0)';$S;OUT;
    'G1_TXN4':'(0,0,0,0,0,0,0,0,0,0,0,AN44,0,0,0,0,0,0,0,0,0,0,0,0,0,0,0,0,0,0,0~
,0,0,0,0,0,0,0,0,0)';$S;OUT;
    'G1_RXP4':'(0,0,0,0,0,0,0,0,0,0,0,N44,0,0,0,0,0,0,0,0,0,0,0,0,0,0,0,0,0,0,0,~
0,0,0,0,0,0,0,0,0)';$S;IN;
    'G1_RXN2':'(0,0,0,0,0,0,0,0,0,0,0,P40,0,0,0,0,0,0,0,0,0,0,0,0,0,0,0,0,0,0,0,~
0,0,0,0,0,0,0,0,0)';$S;IN;
    'G1_TXP7':'(0,0,0,0,0,0,0,0,0,0,0,AN46,0,0,0,0,0,0,0,0,0,0,0,0,0,0,0,0,0,0,0~
,0,0,0,0,0,0,0,0,0)';$S;OUT;
    'G1_TXN5':'(0,0,0,0,0,0,0,0,0,0,0,AJ44,0,0,0,0,0,0,0,0,0,0,0,0,0,0,0,0,0,0,0~
,0,0,0,0,0,0,0,0,0)';$S;OUT;
    'G1_RXP5':'(0,0,0,0,0,0,0,0,0,0,0,R44,0,0,0,0,0,0,0,0,0,0,0,0,0,0,0,0,0,0,0,~
0,0,0,0,0,0,0,0,0)';$S;IN;
    'G1_RXN3':'(0,0,0,0,0,0,0,0,0,0,0,U43,0,0,0,0,0,0,0,0,0,0,0,0,0,0,0,0,0,0,0,~
0,0,0,0,0,0,0,0,0)';$S;IN;
    'G1_TXN6':'(0,0,0,0,0,0,0,0,0,0,0,AL44,0,0,0,0,0,0,0,0,0,0,0,0,0,0,0,0,0,0,0~
,0,0,0,0,0,0,0,0,0)';$S;OUT;
    'G1_RXP6':'(0,0,0,0,0,0,0,0,0,0,0,U47,0,0,0,0,0,0,0,0,0,0,0,0,0,0,0,0,0,0,0,~
0,0,0,0,0,0,0,0,0)';$S;IN;
    'G1_RXN4':'(0,0,0,0,0,0,0,0,0,0,0,N43,0,0,0,0,0,0,0,0,0,0,0,0,0,0,0,0,0,0,0,~
0,0,0,0,0,0,0,0,0)';$S;IN;
    'G1_TXN7':'(0,0,0,0,0,0,0,0,0,0,0,AN47,0,0,0,0,0,0,0,0,0,0,0,0,0,0,0,0,0,0,0~
,0,0,0,0,0,0,0,0,0)';$S;OUT;
    'G1_RXP7':'(0,0,0,0,0,0,0,0,0,0,0,N47,0,0,0,0,0,0,0,0,0,0,0,0,0,0,0,0,0,0,0,~
0,0,0,0,0,0,0,0,0)';$S;IN;
    'G1_RXN5':'(0,0,0,0,0,0,0,0,0,0,0,R43,0,0,0,0,0,0,0,0,0,0,0,0,0,0,0,0,0,0,0,~
0,0,0,0,0,0,0,0,0)';$S;IN;
    'G1_RXN6':'(0,0,0,0,0,0,0,0,0,0,0,U46,0,0,0,0,0,0,0,0,0,0,0,0,0,0,0,0,0,0,0,~
0,0,0,0,0,0,0,0,0)';$S;IN;
    'G1_RXN7':'(0,0,0,0,0,0,0,0,0,0,0,N46,0,0,0,0,0,0,0,0,0,0,0,0,0,0,0,0,0,0,0,~
0,0,0,0,0,0,0,0,0)';$S;IN;
    'G2_TXP8':'(0,0,0,0,0,0,0,0,0,0,0,0,G29,0,0,0,0,0,0,0,0,0,0,0,0,0,0,0,0,0,0,~
0,0,0,0,0,0,0,0,0)';$S;OUT;
    'G2_TXN8':'(0,0,0,0,0,0,0,0,0,0,0,0,G30,0,0,0,0,0,0,0,0,0,0,0,0,0,0,0,0,0,0,~
0,0,0,0,0,0,0,0,0)';$S;OUT;
    'G2_TXP10':'(0,0,0,0,0,0,0,0,0,0,0,0,J32,0,0,0,0,0,0,0,0,0,0,0,0,0,0,0,0,0,0~
,0,0,0,0,0,0,0,0,0)';$S;OUT;
    'G2_TXN10':'(0,0,0,0,0,0,0,0,0,0,0,0,J33,0,0,0,0,0,0,0,0,0,0,0,0,0,0,0,0,0,0~
,0,0,0,0,0,0,0,0,0)';$S;OUT;
    'G2_TXP12':'(0,0,0,0,0,0,0,0,0,0,0,0,L32,0,0,0,0,0,0,0,0,0,0,0,0,0,0,0,0,0,0~
,0,0,0,0,0,0,0,0,0)';$S;OUT;
    'G2_TXN12':'(0,0,0,0,0,0,0,0,0,0,0,0,L33,0,0,0,0,0,0,0,0,0,0,0,0,0,0,0,0,0,0~
,0,0,0,0,0,0,0,0,0)';$S;OUT;
    'G2_TXP14':'(0,0,0,0,0,0,0,0,0,0,0,0,K35,0,0,0,0,0,0,0,0,0,0,0,0,0,0,0,0,0,0~
,0,0,0,0,0,0,0,0,0)';$S;OUT;
    'G2_TXN14':'(0,0,0,0,0,0,0,0,0,0,0,0,K36,0,0,0,0,0,0,0,0,0,0,0,0,0,0,0,0,0,0~
,0,0,0,0,0,0,0,0,0)';$S;OUT;
    'G2_TXP9':'(0,0,0,0,0,0,0,0,0,0,0,0,L29,0,0,0,0,0,0,0,0,0,0,0,0,0,0,0,0,0,0,~
0,0,0,0,0,0,0,0,0)';$S;OUT;
    'G2_TXN9':'(0,0,0,0,0,0,0,0,0,0,0,0,L30,0,0,0,0,0,0,0,0,0,0,0,0,0,0,0,0,0,0,~
0,0,0,0,0,0,0,0,0)';$S;OUT;
    'G2_TXP11':'(0,0,0,0,0,0,0,0,0,0,0,0,G32,0,0,0,0,0,0,0,0,0,0,0,0,0,0,0,0,0,0~
,0,0,0,0,0,0,0,0,0)';$S;OUT;
    'G2_TXN11':'(0,0,0,0,0,0,0,0,0,0,0,0,G33,0,0,0,0,0,0,0,0,0,0,0,0,0,0,0,0,0,0~
,0,0,0,0,0,0,0,0,0)';$S;OUT;
    'G2_TXP13':'(0,0,0,0,0,0,0,0,0,0,0,0,H35,0,0,0,0,0,0,0,0,0,0,0,0,0,0,0,0,0,0~
,0,0,0,0,0,0,0,0,0)';$S;OUT;
    'G2_TXN13':'(0,0,0,0,0,0,0,0,0,0,0,0,H36,0,0,0,0,0,0,0,0,0,0,0,0,0,0,0,0,0,0~
,0,0,0,0,0,0,0,0,0)';$S;OUT;
    'G2_TXP15':'(0,0,0,0,0,0,0,0,0,0,0,0,M35,0,0,0,0,0,0,0,0,0,0,0,0,0,0,0,0,0,0~
,0,0,0,0,0,0,0,0,0)';$S;OUT;
    'G2_TXN15':'(0,0,0,0,0,0,0,0,0,0,0,0,M36,0,0,0,0,0,0,0,0,0,0,0,0,0,0,0,0,0,0~
,0,0,0,0,0,0,0,0,0)';$S;OUT;
    'G2_RXP8':'(0,0,0,0,0,0,0,0,0,0,0,0,AG30,0,0,0,0,0,0,0,0,0,0,0,0,0,0,0,0,0,0~
,0,0,0,0,0,0,0,0,0)';$S;IN;
    'G2_RXN8':'(0,0,0,0,0,0,0,0,0,0,0,0,AG29,0,0,0,0,0,0,0,0,0,0,0,0,0,0,0,0,0,0~
,0,0,0,0,0,0,0,0,0)';$S;IN;
    'G2_RXP10':'(0,0,0,0,0,0,0,0,0,0,0,0,AC33,0,0,0,0,0,0,0,0,0,0,0,0,0,0,0,0,0,~
0,0,0,0,0,0,0,0,0,0)';$S;IN;
    'G2_RXN10':'(0,0,0,0,0,0,0,0,0,0,0,0,AC32,0,0,0,0,0,0,0,0,0,0,0,0,0,0,0,0,0,~
0,0,0,0,0,0,0,0,0,0)';$S;IN;
    'G2_RXP12':'(0,0,0,0,0,0,0,0,0,0,0,0,AG33,0,0,0,0,0,0,0,0,0,0,0,0,0,0,0,0,0,~
0,0,0,0,0,0,0,0,0,0)';$S;IN;
    'G2_RXN12':'(0,0,0,0,0,0,0,0,0,0,0,0,AG32,0,0,0,0,0,0,0,0,0,0,0,0,0,0,0,0,0,~
0,0,0,0,0,0,0,0,0,0)';$S;IN;
    'G2_RXP14':'(0,0,0,0,0,0,0,0,0,0,0,0,AD36,0,0,0,0,0,0,0,0,0,0,0,0,0,0,0,0,0,~
0,0,0,0,0,0,0,0,0,0)';$S;IN;
    'G2_RXN14':'(0,0,0,0,0,0,0,0,0,0,0,0,AD35,0,0,0,0,0,0,0,0,0,0,0,0,0,0,0,0,0,~
0,0,0,0,0,0,0,0,0,0)';$S;IN;
    'G2_RXP9':'(0,0,0,0,0,0,0,0,0,0,0,0,AE33,0,0,0,0,0,0,0,0,0,0,0,0,0,0,0,0,0,0~
,0,0,0,0,0,0,0,0,0)';$S;IN;
    'G2_RXN9':'(0,0,0,0,0,0,0,0,0,0,0,0,AE32,0,0,0,0,0,0,0,0,0,0,0,0,0,0,0,0,0,0~
,0,0,0,0,0,0,0,0,0)';$S;IN;
    'G2_RXP11':'(0,0,0,0,0,0,0,0,0,0,0,0,AA33,0,0,0,0,0,0,0,0,0,0,0,0,0,0,0,0,0,~
0,0,0,0,0,0,0,0,0,0)';$S;IN;
    'G2_RXN11':'(0,0,0,0,0,0,0,0,0,0,0,0,AA32,0,0,0,0,0,0,0,0,0,0,0,0,0,0,0,0,0,~
0,0,0,0,0,0,0,0,0,0)';$S;IN;
    'G2_RXP13':'(0,0,0,0,0,0,0,0,0,0,0,0,AB36,0,0,0,0,0,0,0,0,0,0,0,0,0,0,0,0,0,~
0,0,0,0,0,0,0,0,0,0)';$S;IN;
    'G2_RXN13':'(0,0,0,0,0,0,0,0,0,0,0,0,AB35,0,0,0,0,0,0,0,0,0,0,0,0,0,0,0,0,0,~
0,0,0,0,0,0,0,0,0,0)';$S;IN;
    'G2_RXP15':'(0,0,0,0,0,0,0,0,0,0,0,0,AF36,0,0,0,0,0,0,0,0,0,0,0,0,0,0,0,0,0,~
0,0,0,0,0,0,0,0,0,0)';$S;IN;
    'G2_RXN15':'(0,0,0,0,0,0,0,0,0,0,0,0,AF35,0,0,0,0,0,0,0,0,0,0,0,0,0,0,0,0,0,~
0,0,0,0,0,0,0,0,0,0)';$S;IN;
    'G2_TXP1':'(0,0,0,0,0,0,0,0,0,0,0,0,J23,0,0,0,0,0,0,0,0,0,0,0,0,0,0,0,0,0,0,~
0,0,0,0,0,0,0,0,0)';$S;OUT;
    'G2_TXP2':'(0,0,0,0,0,0,0,0,0,0,0,0,G23,0,0,0,0,0,0,0,0,0,0,0,0,0,0,0,0,0,0,~
0,0,0,0,0,0,0,0,0)';$S;OUT;
    'G2_TXN0':'(0,0,0,0,0,0,0,0,0,0,0,0,N24,0,0,0,0,0,0,0,0,0,0,0,0,0,0,0,0,0,0,~
0,0,0,0,0,0,0,0,0)';$S;OUT;
    'G2_RXP0':'(0,0,0,0,0,0,0,0,0,0,0,0,AE24,0,0,0,0,0,0,0,0,0,0,0,0,0,0,0,0,0,0~
,0,0,0,0,0,0,0,0,0)';$S;IN;
    'G2_TXP3':'(0,0,0,0,0,0,0,0,0,0,0,0,L23,0,0,0,0,0,0,0,0,0,0,0,0,0,0,0,0,0,0,~
0,0,0,0,0,0,0,0,0)';$S;OUT;
    'G2_TXN1':'(0,0,0,0,0,0,0,0,0,0,0,0,J24,0,0,0,0,0,0,0,0,0,0,0,0,0,0,0,0,0,0,~
0,0,0,0,0,0,0,0,0)';$S;OUT;
    'G2_RXP1':'(0,0,0,0,0,0,0,0,0,0,0,0,AC24,0,0,0,0,0,0,0,0,0,0,0,0,0,0,0,0,0,0~
,0,0,0,0,0,0,0,0,0)';$S;IN;
    'G2_TXP4':'(0,0,0,0,0,0,0,0,0,0,0,0,J26,0,0,0,0,0,0,0,0,0,0,0,0,0,0,0,0,0,0,~
0,0,0,0,0,0,0,0,0)';$S;OUT;
    'G2_TXN2':'(0,0,0,0,0,0,0,0,0,0,0,0,G24,0,0,0,0,0,0,0,0,0,0,0,0,0,0,0,0,0,0,~
0,0,0,0,0,0,0,0,0)';$S;OUT;
    'G2_RXP2':'(0,0,0,0,0,0,0,0,0,0,0,0,AG24,0,0,0,0,0,0,0,0,0,0,0,0,0,0,0,0,0,0~
,0,0,0,0,0,0,0,0,0)';$S;IN;
    'G2_RXN0':'(0,0,0,0,0,0,0,0,0,0,0,0,AE23,0,0,0,0,0,0,0,0,0,0,0,0,0,0,0,0,0,0~
,0,0,0,0,0,0,0,0,0)';$S;IN;
    'G2_TXP5':'(0,0,0,0,0,0,0,0,0,0,0,0,G26,0,0,0,0,0,0,0,0,0,0,0,0,0,0,0,0,0,0,~
0,0,0,0,0,0,0,0,0)';$S;OUT;
    'G2_TXN3':'(0,0,0,0,0,0,0,0,0,0,0,0,L24,0,0,0,0,0,0,0,0,0,0,0,0,0,0,0,0,0,0,~
0,0,0,0,0,0,0,0,0)';$S;OUT;
    'G2_RXP3':'(0,0,0,0,0,0,0,0,0,0,0,0,AE27,0,0,0,0,0,0,0,0,0,0,0,0,0,0,0,0,0,0~
,0,0,0,0,0,0,0,0,0)';$S;IN;
    'G2_RXN1':'(0,0,0,0,0,0,0,0,0,0,0,0,AC23,0,0,0,0,0,0,0,0,0,0,0,0,0,0,0,0,0,0~
,0,0,0,0,0,0,0,0,0)';$S;IN;
    'G2_TXP6':'(0,0,0,0,0,0,0,0,0,0,0,0,L26,0,0,0,0,0,0,0,0,0,0,0,0,0,0,0,0,0,0,~
0,0,0,0,0,0,0,0,0)';$S;OUT;
    'G2_TXN4':'(0,0,0,0,0,0,0,0,0,0,0,0,J27,0,0,0,0,0,0,0,0,0,0,0,0,0,0,0,0,0,0,~
0,0,0,0,0,0,0,0,0)';$S;OUT;
    'G2_RXP4':'(0,0,0,0,0,0,0,0,0,0,0,0,AC27,0,0,0,0,0,0,0,0,0,0,0,0,0,0,0,0,0,0~
,0,0,0,0,0,0,0,0,0)';$S;IN;
    'G2_RXN2':'(0,0,0,0,0,0,0,0,0,0,0,0,AG23,0,0,0,0,0,0,0,0,0,0,0,0,0,0,0,0,0,0~
,0,0,0,0,0,0,0,0,0)';$S;IN;
    'G2_TXP7':'(0,0,0,0,0,0,0,0,0,0,0,0,J29,0,0,0,0,0,0,0,0,0,0,0,0,0,0,0,0,0,0,~
0,0,0,0,0,0,0,0,0)';$S;OUT;
    'G2_TXN5':'(0,0,0,0,0,0,0,0,0,0,0,0,G27,0,0,0,0,0,0,0,0,0,0,0,0,0,0,0,0,0,0,~
0,0,0,0,0,0,0,0,0)';$S;OUT;
    'G2_RXP5':'(0,0,0,0,0,0,0,0,0,0,0,0,AG27,0,0,0,0,0,0,0,0,0,0,0,0,0,0,0,0,0,0~
,0,0,0,0,0,0,0,0,0)';$S;IN;
    'G2_RXN3':'(0,0,0,0,0,0,0,0,0,0,0,0,AE26,0,0,0,0,0,0,0,0,0,0,0,0,0,0,0,0,0,0~
,0,0,0,0,0,0,0,0,0)';$S;IN;
    'G2_TXN6':'(0,0,0,0,0,0,0,0,0,0,0,0,L27,0,0,0,0,0,0,0,0,0,0,0,0,0,0,0,0,0,0,~
0,0,0,0,0,0,0,0,0)';$S;OUT;
    'G2_RXP6':'(0,0,0,0,0,0,0,0,0,0,0,0,AE30,0,0,0,0,0,0,0,0,0,0,0,0,0,0,0,0,0,0~
,0,0,0,0,0,0,0,0,0)';$S;IN;
    'G2_RXN4':'(0,0,0,0,0,0,0,0,0,0,0,0,AC26,0,0,0,0,0,0,0,0,0,0,0,0,0,0,0,0,0,0~
,0,0,0,0,0,0,0,0,0)';$S;IN;
    'G2_TXN7':'(0,0,0,0,0,0,0,0,0,0,0,0,J30,0,0,0,0,0,0,0,0,0,0,0,0,0,0,0,0,0,0,~
0,0,0,0,0,0,0,0,0)';$S;OUT;
    'G2_RXP7':'(0,0,0,0,0,0,0,0,0,0,0,0,AC30,0,0,0,0,0,0,0,0,0,0,0,0,0,0,0,0,0,0~
,0,0,0,0,0,0,0,0,0)';$S;IN;
    'G2_RXN5':'(0,0,0,0,0,0,0,0,0,0,0,0,AG26,0,0,0,0,0,0,0,0,0,0,0,0,0,0,0,0,0,0~
,0,0,0,0,0,0,0,0,0)';$S;IN;
    'G2_RXN6':'(0,0,0,0,0,0,0,0,0,0,0,0,AE29,0,0,0,0,0,0,0,0,0,0,0,0,0,0,0,0,0,0~
,0,0,0,0,0,0,0,0,0)';$S;IN;
    'G2_RXN7':'(0,0,0,0,0,0,0,0,0,0,0,0,AC29,0,0,0,0,0,0,0,0,0,0,0,0,0,0,0,0,0,0~
,0,0,0,0,0,0,0,0,0)';$S;IN;
    'G2_TXP0':'(0,0,0,0,0,0,0,0,0,0,0,0,N23,0,0,0,0,0,0,0,0,0,0,0,0,0,0,0,0,0,0,~
0,0,0,0,0,0,0,0,0)';$S;OUT;
    'G3_TXP13||SATA35_TXP':'(0,0,0,0,0,0,0,0,0,0,0,0,0,P35,0,0,0,0,0,0,0,0,0,0,0~
,0,0,0,0,0,0,0,0,0,0,0,0,0,0,0)';$S;OUT;
    'G3_TXP10||SATA32_TXP':'(0,0,0,0,0,0,0,0,0,0,0,0,0,R32,0,0,0,0,0,0,0,0,0,0,0~
,0,0,0,0,0,0,0,0,0,0,0,0,0,0,0)';$S;OUT;
    'G3_RXN5||SATA25_RXN':'(0,0,0,0,0,0,0,0,0,0,0,0,0,AN26,0,0,0,0,0,0,0,0,0,0,0~
,0,0,0,0,0,0,0,0,0,0,0,0,0,0,0)';$S;IN;
    'G3_TXN2||SATA22_TXN':'(0,0,0,0,0,0,0,0,0,0,0,0,0,W24,0,0,0,0,0,0,0,0,0,0,0,~
0,0,0,0,0,0,0,0,0,0,0,0,0,0,0)';$S;OUT;
    'G3_RXP12||SATA34_RXP':'(0,0,0,0,0,0,0,0,0,0,0,0,0,AK36,0,0,0,0,0,0,0,0,0,0,~
0,0,0,0,0,0,0,0,0,0,0,0,0,0,0,0)';$S;IN;
    'G3_RXP0||SATA20_RXP':'(0,0,0,0,0,0,0,0,0,0,0,0,0,AL24,0,0,0,0,0,0,0,0,0,0,0~
,0,0,0,0,0,0,0,0,0,0,0,0,0,0,0)';$S;IN;
    'G3_TXN14||SATA36_TXN':'(0,0,0,0,0,0,0,0,0,0,0,0,0,T36,0,0,0,0,0,0,0,0,0,0,0~
,0,0,0,0,0,0,0,0,0,0,0,0,0,0,0)';$S;OUT;
    'G3_TXN11||SATA33_TXN':'(0,0,0,0,0,0,0,0,0,0,0,0,0,N33,0,0,0,0,0,0,0,0,0,0,0~
,0,0,0,0,0,0,0,0,0,0,0,0,0,0,0)';$S;OUT;
    'G3_TXN5||SATA25_TXN':'(0,0,0,0,0,0,0,0,0,0,0,0,0,N27,0,0,0,0,0,0,0,0,0,0,0,~
0,0,0,0,0,0,0,0,0,0,0,0,0,0,0)';$S;OUT;
    'G3_RXP15||SATA37_RXP':'(0,0,0,0,0,0,0,0,0,0,0,0,0,AP36,0,0,0,0,0,0,0,0,0,0,~
0,0,0,0,0,0,0,0,0,0,0,0,0,0,0,0)';$S;IN;
    'G3_RXP6||SATA26_RXP':'(0,0,0,0,0,0,0,0,0,0,0,0,0,AL30,0,0,0,0,0,0,0,0,0,0,0~
,0,0,0,0,0,0,0,0,0,0,0,0,0,0,0)';$S;IN;
    'G3_RXP3||SATA23_RXP':'(0,0,0,0,0,0,0,0,0,0,0,0,0,AL27,0,0,0,0,0,0,0,0,0,0,0~
,0,0,0,0,0,0,0,0,0,0,0,0,0,0,0)';$S;IN;
    'G3_TXP3||SATA23_TXP':'(0,0,0,0,0,0,0,0,0,0,0,0,0,U26,0,0,0,0,0,0,0,0,0,0,0,~
0,0,0,0,0,0,0,0,0,0,0,0,0,0,0)';$S;OUT;
    'G3_TXP0||SATA20_TXP':'(0,0,0,0,0,0,0,0,0,0,0,0,0,U23,0,0,0,0,0,0,0,0,0,0,0,~
0,0,0,0,0,0,0,0,0,0,0,0,0,0,0)';$S;OUT;
    'G3_RXN10||SATA32_RXN':'(0,0,0,0,0,0,0,0,0,0,0,0,0,AJ32,0,0,0,0,0,0,0,0,0,0,~
0,0,0,0,0,0,0,0,0,0,0,0,0,0,0,0)';$S;IN;
    'G3_TXP6||SATA26_TXP':'(0,0,0,0,0,0,0,0,0,0,0,0,0,W26,0,0,0,0,0,0,0,0,0,0,0,~
0,0,0,0,0,0,0,0,0,0,0,0,0,0,0)';$S;OUT;
    'G3_RXN13||SATA35_RXN':'(0,0,0,0,0,0,0,0,0,0,0,0,0,AH35,0,0,0,0,0,0,0,0,0,0,~
0,0,0,0,0,0,0,0,0,0,0,0,0,0,0,0)';$S;IN;
    'G3_TXP11||SATA33_TXP':'(0,0,0,0,0,0,0,0,0,0,0,0,0,N32,0,0,0,0,0,0,0,0,0,0,0~
,0,0,0,0,0,0,0,0,0,0,0,0,0,0,0)';$S;OUT;
    'G3_RXP8||SATA30_RXP':'(0,0,0,0,0,0,0,0,0,0,0,0,0,AN30,0,0,0,0,0,0,0,0,0,0,0~
,0,0,0,0,0,0,0,0,0,0,0,0,0,0,0)';$S;IN;
    'G3_RXN3||SATA23_RXN':'(0,0,0,0,0,0,0,0,0,0,0,0,0,AL26,0,0,0,0,0,0,0,0,0,0,0~
,0,0,0,0,0,0,0,0,0,0,0,0,0,0,0)';$S;IN;
    'G3_RXN0||SATA20_RXN':'(0,0,0,0,0,0,0,0,0,0,0,0,0,AL23,0,0,0,0,0,0,0,0,0,0,0~
,0,0,0,0,0,0,0,0,0,0,0,0,0,0,0)';$S;IN;
    'G3_TXP14||SATA36_TXP':'(0,0,0,0,0,0,0,0,0,0,0,0,0,T35,0,0,0,0,0,0,0,0,0,0,0~
,0,0,0,0,0,0,0,0,0,0,0,0,0,0,0)';$S;OUT;
    'G3_TXP8||SATA30_TXP':'(0,0,0,0,0,0,0,0,0,0,0,0,0,N29,0,0,0,0,0,0,0,0,0,0,0,~
0,0,0,0,0,0,0,0,0,0,0,0,0,0,0)';$S;OUT;
    'G3_TXN0||SATA20_TXN':'(0,0,0,0,0,0,0,0,0,0,0,0,0,U24,0,0,0,0,0,0,0,0,0,0,0,~
0,0,0,0,0,0,0,0,0,0,0,0,0,0,0)';$S;OUT;
    'G3_RXN6||SATA26_RXN':'(0,0,0,0,0,0,0,0,0,0,0,0,0,AL29,0,0,0,0,0,0,0,0,0,0,0~
,0,0,0,0,0,0,0,0,0,0,0,0,0,0,0)';$S;IN;
    'G3_TXN6||SATA26_TXN':'(0,0,0,0,0,0,0,0,0,0,0,0,0,W27,0,0,0,0,0,0,0,0,0,0,0,~
0,0,0,0,0,0,0,0,0,0,0,0,0,0,0)';$S;OUT;
    'G3_TXN3||SATA23_TXN':'(0,0,0,0,0,0,0,0,0,0,0,0,0,U27,0,0,0,0,0,0,0,0,0,0,0,~
0,0,0,0,0,0,0,0,0,0,0,0,0,0,0)';$S;OUT;
    'G3_RXP13||SATA35_RXP':'(0,0,0,0,0,0,0,0,0,0,0,0,0,AH36,0,0,0,0,0,0,0,0,0,0,~
0,0,0,0,0,0,0,0,0,0,0,0,0,0,0,0)';$S;IN;
    'G3_RXP10||SATA32_RXP':'(0,0,0,0,0,0,0,0,0,0,0,0,0,AJ33,0,0,0,0,0,0,0,0,0,0,~
0,0,0,0,0,0,0,0,0,0,0,0,0,0,0,0)';$S;IN;
    'G3_RXP4||SATA24_RXP':'(0,0,0,0,0,0,0,0,0,0,0,0,0,AJ27,0,0,0,0,0,0,0,0,0,0,0~
,0,0,0,0,0,0,0,0,0,0,0,0,0,0,0)';$S;IN;
    'G3_RXP1||SATA21_RXP':'(0,0,0,0,0,0,0,0,0,0,0,0,0,AJ24,0,0,0,0,0,0,0,0,0,0,0~
,0,0,0,0,0,0,0,0,0,0,0,0,0,0,0)';$S;IN;
    'G3_TXN15||SATA37_TXN':'(0,0,0,0,0,0,0,0,0,0,0,0,0,V36,0,0,0,0,0,0,0,0,0,0,0~
,0,0,0,0,0,0,0,0,0,0,0,0,0,0,0)';$S;OUT;
    'G3_TXN12||SATA34_TXN':'(0,0,0,0,0,0,0,0,0,0,0,0,0,U33,0,0,0,0,0,0,0,0,0,0,0~
,0,0,0,0,0,0,0,0,0,0,0,0,0,0,0)';$S;OUT;
    'G3_RXN8||SATA30_RXN':'(0,0,0,0,0,0,0,0,0,0,0,0,0,AN29,0,0,0,0,0,0,0,0,0,0,0~
,0,0,0,0,0,0,0,0,0,0,0,0,0,0,0)';$S;IN;
    'G3_RXP7||SATA27_RXP':'(0,0,0,0,0,0,0,0,0,0,0,0,0,AJ30,0,0,0,0,0,0,0,0,0,0,0~
,0,0,0,0,0,0,0,0,0,0,0,0,0,0,0)';$S;IN;
    'G3_TXP4||SATA24_TXP':'(0,0,0,0,0,0,0,0,0,0,0,0,0,R26,0,0,0,0,0,0,0,0,0,0,0,~
0,0,0,0,0,0,0,0,0,0,0,0,0,0,0)';$S;OUT;
    'G3_TXP1||SATA21_TXP':'(0,0,0,0,0,0,0,0,0,0,0,0,0,R23,0,0,0,0,0,0,0,0,0,0,0,~
0,0,0,0,0,0,0,0,0,0,0,0,0,0,0)';$S;OUT;
    'G3_RXN14||SATA36_RXN':'(0,0,0,0,0,0,0,0,0,0,0,0,0,AM35,0,0,0,0,0,0,0,0,0,0,~
0,0,0,0,0,0,0,0,0,0,0,0,0,0,0,0)';$S;IN;
    'G3_RXN11||SATA33_RXN':'(0,0,0,0,0,0,0,0,0,0,0,0,0,AN32,0,0,0,0,0,0,0,0,0,0,~
0,0,0,0,0,0,0,0,0,0,0,0,0,0,0,0)';$S;IN;
    'G3_TXN8||SATA30_TXN':'(0,0,0,0,0,0,0,0,0,0,0,0,0,N30,0,0,0,0,0,0,0,0,0,0,0,~
0,0,0,0,0,0,0,0,0,0,0,0,0,0,0)';$S;OUT;
    'G3_TXP7||SATA27_TXP':'(0,0,0,0,0,0,0,0,0,0,0,0,0,R29,0,0,0,0,0,0,0,0,0,0,0,~
0,0,0,0,0,0,0,0,0,0,0,0,0,0,0)';$S;OUT;
    'G3_RXP9||SATA31_RXP':'(0,0,0,0,0,0,0,0,0,0,0,0,0,AL33,0,0,0,0,0,0,0,0,0,0,0~
,0,0,0,0,0,0,0,0,0,0,0,0,0,0,0)';$S;IN;
    'G3_TXP12||SATA34_TXP':'(0,0,0,0,0,0,0,0,0,0,0,0,0,U32,0,0,0,0,0,0,0,0,0,0,0~
,0,0,0,0,0,0,0,0,0,0,0,0,0,0,0)';$S;OUT;
    'G3_RXN7||SATA27_RXN':'(0,0,0,0,0,0,0,0,0,0,0,0,0,AJ29,0,0,0,0,0,0,0,0,0,0,0~
,0,0,0,0,0,0,0,0,0,0,0,0,0,0,0)';$S;IN;
    'G3_RXN4||SATA24_RXN':'(0,0,0,0,0,0,0,0,0,0,0,0,0,AJ26,0,0,0,0,0,0,0,0,0,0,0~
,0,0,0,0,0,0,0,0,0,0,0,0,0,0,0)';$S;IN;
    'G3_RXN1||SATA21_RXN':'(0,0,0,0,0,0,0,0,0,0,0,0,0,AJ23,0,0,0,0,0,0,0,0,0,0,0~
,0,0,0,0,0,0,0,0,0,0,0,0,0,0,0)';$S;IN;
    'G3_TXP15||SATA37_TXP':'(0,0,0,0,0,0,0,0,0,0,0,0,0,V35,0,0,0,0,0,0,0,0,0,0,0~
,0,0,0,0,0,0,0,0,0,0,0,0,0,0,0)';$S;OUT;
    'G3_TXP9||SATA31_TXP':'(0,0,0,0,0,0,0,0,0,0,0,0,0,U29,0,0,0,0,0,0,0,0,0,0,0,~
0,0,0,0,0,0,0,0,0,0,0,0,0,0,0)';$S;OUT;
    'G3_TXN1||SATA21_TXN':'(0,0,0,0,0,0,0,0,0,0,0,0,0,R24,0,0,0,0,0,0,0,0,0,0,0,~
0,0,0,0,0,0,0,0,0,0,0,0,0,0,0)';$S;OUT;
    'G3_RXP11||SATA33_RXP':'(0,0,0,0,0,0,0,0,0,0,0,0,0,AN33,0,0,0,0,0,0,0,0,0,0,~
0,0,0,0,0,0,0,0,0,0,0,0,0,0,0,0)';$S;IN;
    'G3_TXN13||SATA35_TXN':'(0,0,0,0,0,0,0,0,0,0,0,0,0,P36,0,0,0,0,0,0,0,0,0,0,0~
,0,0,0,0,0,0,0,0,0,0,0,0,0,0,0)';$S;OUT;
    'G3_TXN10||SATA32_TXN':'(0,0,0,0,0,0,0,0,0,0,0,0,0,R33,0,0,0,0,0,0,0,0,0,0,0~
,0,0,0,0,0,0,0,0,0,0,0,0,0,0,0)';$S;OUT;
    'G3_TXN7||SATA27_TXN':'(0,0,0,0,0,0,0,0,0,0,0,0,0,R30,0,0,0,0,0,0,0,0,0,0,0,~
0,0,0,0,0,0,0,0,0,0,0,0,0,0,0)';$S;OUT;
    'G3_TXN4||SATA24_TXN':'(0,0,0,0,0,0,0,0,0,0,0,0,0,R27,0,0,0,0,0,0,0,0,0,0,0,~
0,0,0,0,0,0,0,0,0,0,0,0,0,0,0)';$S;OUT;
    'G3_RXP14||SATA36_RXP':'(0,0,0,0,0,0,0,0,0,0,0,0,0,AM36,0,0,0,0,0,0,0,0,0,0,~
0,0,0,0,0,0,0,0,0,0,0,0,0,0,0,0)';$S;IN;
    'G3_RXP5||SATA25_RXP':'(0,0,0,0,0,0,0,0,0,0,0,0,0,AN27,0,0,0,0,0,0,0,0,0,0,0~
,0,0,0,0,0,0,0,0,0,0,0,0,0,0,0)';$S;IN;
    'G3_RXP2||SATA22_RXP':'(0,0,0,0,0,0,0,0,0,0,0,0,0,AN24,0,0,0,0,0,0,0,0,0,0,0~
,0,0,0,0,0,0,0,0,0,0,0,0,0,0,0)';$S;IN;
    'G3_TXP2||SATA22_TXP':'(0,0,0,0,0,0,0,0,0,0,0,0,0,W23,0,0,0,0,0,0,0,0,0,0,0,~
0,0,0,0,0,0,0,0,0,0,0,0,0,0,0)';$S;OUT;
    'G3_RXN9||SATA31_RXN':'(0,0,0,0,0,0,0,0,0,0,0,0,0,AL32,0,0,0,0,0,0,0,0,0,0,0~
,0,0,0,0,0,0,0,0,0,0,0,0,0,0,0)';$S;IN;
    'G3_TXP5||SATA25_TXP':'(0,0,0,0,0,0,0,0,0,0,0,0,0,N26,0,0,0,0,0,0,0,0,0,0,0,~
0,0,0,0,0,0,0,0,0,0,0,0,0,0,0)';$S;OUT;
    'G3_RXN15||SATA37_RXN':'(0,0,0,0,0,0,0,0,0,0,0,0,0,AP35,0,0,0,0,0,0,0,0,0,0,~
0,0,0,0,0,0,0,0,0,0,0,0,0,0,0,0)';$S;IN;
    'G3_RXN12||SATA34_RXN':'(0,0,0,0,0,0,0,0,0,0,0,0,0,AK35,0,0,0,0,0,0,0,0,0,0,~
0,0,0,0,0,0,0,0,0,0,0,0,0,0,0,0)';$S;IN;
    'G3_TXN9||SATA31_TXN':'(0,0,0,0,0,0,0,0,0,0,0,0,0,U30,0,0,0,0,0,0,0,0,0,0,0,~
0,0,0,0,0,0,0,0,0,0,0,0,0,0,0)';$S;OUT;
    'G3_RXN2||SATA22_RXN':'(0,0,0,0,0,0,0,0,0,0,0,0,0,AN23,0,0,0,0,0,0,0,0,0,0,0~
,0,0,0,0,0,0,0,0,0,0,0,0,0,0,0)';$S;IN;
    'P0_RXN0||SATA00_RXN':'(0,0,0,0,0,0,0,0,0,0,0,0,0,0,BW53,0,0,0,0,0,0,0,0,0,0~
,0,0,0,0,0,0,0,0,0,0,0,0,0,0,0)';$S;IN;
    'P0_RXN6||SATA06_RXN':'(0,0,0,0,0,0,0,0,0,0,0,0,0,0,BW47,0,0,0,0,0,0,0,0,0,0~
,0,0,0,0,0,0,0,0,0,0,0,0,0,0,0)';$S;IN;
    'P0_RXN3||SATA03_RXN':'(0,0,0,0,0,0,0,0,0,0,0,0,0,0,BW50,0,0,0,0,0,0,0,0,0,0~
,0,0,0,0,0,0,0,0,0,0,0,0,0,0,0)';$S;IN;
    'P0_TXN3||SATA03_TXN':'(0,0,0,0,0,0,0,0,0,0,0,0,0,0,CN49,0,0,0,0,0,0,0,0,0,0~
,0,0,0,0,0,0,0,0,0,0,0,0,0,0,0)';$S;OUT;
    'P0_TXN0||SATA00_TXN':'(0,0,0,0,0,0,0,0,0,0,0,0,0,0,CN52,0,0,0,0,0,0,0,0,0,0~
,0,0,0,0,0,0,0,0,0,0,0,0,0,0,0)';$S;OUT;
    'P0_RXP1||SATA01_RXP':'(0,0,0,0,0,0,0,0,0,0,0,0,0,0,CA52,0,0,0,0,0,0,0,0,0,0~
,0,0,0,0,0,0,0,0,0,0,0,0,0,0,0)';$S;IN;
    'P0_TXN6||SATA06_TXN':'(0,0,0,0,0,0,0,0,0,0,0,0,0,0,CL49,0,0,0,0,0,0,0,0,0,0~
,0,0,0,0,0,0,0,0,0,0,0,0,0,0,0)';$S;OUT;
    'P0_RXP7||SATA07_RXP':'(0,0,0,0,0,0,0,0,0,0,0,0,0,0,CA46,0,0,0,0,0,0,0,0,0,0~
,0,0,0,0,0,0,0,0,0,0,0,0,0,0,0)';$S;IN;
    'P0_RXP4||SATA04_RXP':'(0,0,0,0,0,0,0,0,0,0,0,0,0,0,CA49,0,0,0,0,0,0,0,0,0,0~
,0,0,0,0,0,0,0,0,0,0,0,0,0,0,0)';$S;IN;
    'P0_TXP4||SATA04_TXP':'(0,0,0,0,0,0,0,0,0,0,0,0,0,0,CR50,0,0,0,0,0,0,0,0,0,0~
,0,0,0,0,0,0,0,0,0,0,0,0,0,0,0)';$S;OUT;
    'P0_TXP1||SATA01_TXP':'(0,0,0,0,0,0,0,0,0,0,0,0,0,0,CR53,0,0,0,0,0,0,0,0,0,0~
,0,0,0,0,0,0,0,0,0,0,0,0,0,0,0)';$S;OUT;
    'P0_TXP7||SATA07_TXP':'(0,0,0,0,0,0,0,0,0,0,0,0,0,0,CR47,0,0,0,0,0,0,0,0,0,0~
,0,0,0,0,0,0,0,0,0,0,0,0,0,0,0)';$S;OUT;
    'P0_RXN4||SATA04_RXN':'(0,0,0,0,0,0,0,0,0,0,0,0,0,0,CA50,0,0,0,0,0,0,0,0,0,0~
,0,0,0,0,0,0,0,0,0,0,0,0,0,0,0)';$S;IN;
    'P0_RXN1||SATA01_RXN':'(0,0,0,0,0,0,0,0,0,0,0,0,0,0,CA53,0,0,0,0,0,0,0,0,0,0~
,0,0,0,0,0,0,0,0,0,0,0,0,0,0,0)';$S;IN;
    'P0_RXN7||SATA07_RXN':'(0,0,0,0,0,0,0,0,0,0,0,0,0,0,CA47,0,0,0,0,0,0,0,0,0,0~
,0,0,0,0,0,0,0,0,0,0,0,0,0,0,0)';$S;IN;
    'P0_TXN4||SATA04_TXN':'(0,0,0,0,0,0,0,0,0,0,0,0,0,0,CR49,0,0,0,0,0,0,0,0,0,0~
,0,0,0,0,0,0,0,0,0,0,0,0,0,0,0)';$S;OUT;
    'P0_TXN7||SATA07_TXN':'(0,0,0,0,0,0,0,0,0,0,0,0,0,0,CR46,0,0,0,0,0,0,0,0,0,0~
,0,0,0,0,0,0,0,0,0,0,0,0,0,0,0)';$S;OUT;
    'P0_TXN1||SATA01_TXN':'(0,0,0,0,0,0,0,0,0,0,0,0,0,0,CR52,0,0,0,0,0,0,0,0,0,0~
,0,0,0,0,0,0,0,0,0,0,0,0,0,0,0)';$S;OUT;
    'P0_RXP2||SATA02_RXP':'(0,0,0,0,0,0,0,0,0,0,0,0,0,0,BU52,0,0,0,0,0,0,0,0,0,0~
,0,0,0,0,0,0,0,0,0,0,0,0,0,0,0)';$S;IN;
    'P0_RXP5||SATA05_RXP':'(0,0,0,0,0,0,0,0,0,0,0,0,0,0,BU49,0,0,0,0,0,0,0,0,0,0~
,0,0,0,0,0,0,0,0,0,0,0,0,0,0,0)';$S;IN;
    'P0_TXP5||SATA05_TXP':'(0,0,0,0,0,0,0,0,0,0,0,0,0,0,CU50,0,0,0,0,0,0,0,0,0,0~
,0,0,0,0,0,0,0,0,0,0,0,0,0,0,0)';$S;OUT;
    'P0_TXP2||SATA02_TXP':'(0,0,0,0,0,0,0,0,0,0,0,0,0,0,CL53,0,0,0,0,0,0,0,0,0,0~
,0,0,0,0,0,0,0,0,0,0,0,0,0,0,0)';$S;OUT;
    'P0_RXN5||SATA05_RXN':'(0,0,0,0,0,0,0,0,0,0,0,0,0,0,BU50,0,0,0,0,0,0,0,0,0,0~
,0,0,0,0,0,0,0,0,0,0,0,0,0,0,0)';$S;IN;
    'P0_RXN2||SATA02_RXN':'(0,0,0,0,0,0,0,0,0,0,0,0,0,0,BU53,0,0,0,0,0,0,0,0,0,0~
,0,0,0,0,0,0,0,0,0,0,0,0,0,0,0)';$S;IN;
    'P0_TXN2||SATA02_TXN':'(0,0,0,0,0,0,0,0,0,0,0,0,0,0,CL52,0,0,0,0,0,0,0,0,0,0~
,0,0,0,0,0,0,0,0,0,0,0,0,0,0,0)';$S;OUT;
    'P0_RXP0||SATA00_RXP':'(0,0,0,0,0,0,0,0,0,0,0,0,0,0,BW52,0,0,0,0,0,0,0,0,0,0~
,0,0,0,0,0,0,0,0,0,0,0,0,0,0,0)';$S;IN;
    'P0_TXN5||SATA05_TXN':'(0,0,0,0,0,0,0,0,0,0,0,0,0,0,CU49,0,0,0,0,0,0,0,0,0,0~
,0,0,0,0,0,0,0,0,0,0,0,0,0,0,0)';$S;OUT;
    'P0_RXP6||SATA06_RXP':'(0,0,0,0,0,0,0,0,0,0,0,0,0,0,BW46,0,0,0,0,0,0,0,0,0,0~
,0,0,0,0,0,0,0,0,0,0,0,0,0,0,0)';$S;IN;
    'P0_RXP3||SATA03_RXP':'(0,0,0,0,0,0,0,0,0,0,0,0,0,0,BW49,0,0,0,0,0,0,0,0,0,0~
,0,0,0,0,0,0,0,0,0,0,0,0,0,0,0)';$S;IN;
    'P0_TXP0||SATA00_TXP':'(0,0,0,0,0,0,0,0,0,0,0,0,0,0,CN53,0,0,0,0,0,0,0,0,0,0~
,0,0,0,0,0,0,0,0,0,0,0,0,0,0,0)';$S;OUT;
    'P0_TXP6||SATA06_TXP':'(0,0,0,0,0,0,0,0,0,0,0,0,0,0,CL50,0,0,0,0,0,0,0,0,0,0~
,0,0,0,0,0,0,0,0,0,0,0,0,0,0,0)';$S;OUT;
    'P0_TXP3||SATA03_TXP':'(0,0,0,0,0,0,0,0,0,0,0,0,0,0,CN50,0,0,0,0,0,0,0,0,0,0~
,0,0,0,0,0,0,0,0,0,0,0,0,0,0,0)';$S;OUT;
    'P0_TXN13||SATA15_TXN':'(0,0,0,0,0,0,0,0,0,0,0,0,0,0,CT40,0,0,0,0,0,0,0,0,0,~
0,0,0,0,0,0,0,0,0,0,0,0,0,0,0,0)';$S;OUT;
    'P0_TXN10||SATA12_TXN':'(0,0,0,0,0,0,0,0,0,0,0,0,0,0,CR43,0,0,0,0,0,0,0,0,0,~
0,0,0,0,0,0,0,0,0,0,0,0,0,0,0,0)';$S;OUT;
    'P0_RXP14||SATA16_RXP':'(0,0,0,0,0,0,0,0,0,0,0,0,0,0,BV40,0,0,0,0,0,0,0,0,0,~
0,0,0,0,0,0,0,0,0,0,0,0,0,0,0,0)';$S;IN;
    'P0_RXP8||SATA10_RXP':'(0,0,0,0,0,0,0,0,0,0,0,0,0,0,BU46,0,0,0,0,0,0,0,0,0,0~
,0,0,0,0,0,0,0,0,0,0,0,0,0,0,0)';$S;IN;
    'P0_RXN12||SATA14_RXN':'(0,0,0,0,0,0,0,0,0,0,0,0,0,0,BY41,0,0,0,0,0,0,0,0,0,~
0,0,0,0,0,0,0,0,0,0,0,0,0,0,0,0)';$S;IN;
    'P0_TXP8||SATA10_TXP':'(0,0,0,0,0,0,0,0,0,0,0,0,0,0,CU47,0,0,0,0,0,0,0,0,0,0~
,0,0,0,0,0,0,0,0,0,0,0,0,0,0,0)';$S;OUT;
    'P0_RXN15||SATA17_RXN':'(0,0,0,0,0,0,0,0,0,0,0,0,0,0,BT41,0,0,0,0,0,0,0,0,0,~
0,0,0,0,0,0,0,0,0,0,0,0,0,0,0,0)';$S;IN;
    'P0_TXP10||SATA12_TXP':'(0,0,0,0,0,0,0,0,0,0,0,0,0,0,CR44,0,0,0,0,0,0,0,0,0,~
0,0,0,0,0,0,0,0,0,0,0,0,0,0,0,0)';$S;OUT;
    'P0_TXP13||SATA15_TXP':'(0,0,0,0,0,0,0,0,0,0,0,0,0,0,CT41,0,0,0,0,0,0,0,0,0,~
0,0,0,0,0,0,0,0,0,0,0,0,0,0,0,0)';$S;OUT;
    'P0_RXN8||SATA10_RXN':'(0,0,0,0,0,0,0,0,0,0,0,0,0,0,BU47,0,0,0,0,0,0,0,0,0,0~
,0,0,0,0,0,0,0,0,0,0,0,0,0,0,0)';$S;IN;
    'P0_TXN11||SATA13_TXN':'(0,0,0,0,0,0,0,0,0,0,0,0,0,0,CU43,0,0,0,0,0,0,0,0,0,~
0,0,0,0,0,0,0,0,0,0,0,0,0,0,0,0)';$S;OUT;
    'P0_TXN8||SATA10_TXN':'(0,0,0,0,0,0,0,0,0,0,0,0,0,0,CU46,0,0,0,0,0,0,0,0,0,0~
,0,0,0,0,0,0,0,0,0,0,0,0,0,0,0)';$S;OUT;
    'P0_RXP15||SATA17_RXP':'(0,0,0,0,0,0,0,0,0,0,0,0,0,0,BT40,0,0,0,0,0,0,0,0,0,~
0,0,0,0,0,0,0,0,0,0,0,0,0,0,0,0)';$S;IN;
    'P0_RXP12||SATA14_RXP':'(0,0,0,0,0,0,0,0,0,0,0,0,0,0,BY40,0,0,0,0,0,0,0,0,0,~
0,0,0,0,0,0,0,0,0,0,0,0,0,0,0,0)';$S;IN;
    'P0_TXN14||SATA16_TXN':'(0,0,0,0,0,0,0,0,0,0,0,0,0,0,CP40,0,0,0,0,0,0,0,0,0,~
0,0,0,0,0,0,0,0,0,0,0,0,0,0,0,0)';$S;OUT;
    'P0_RXP9||SATA11_RXP':'(0,0,0,0,0,0,0,0,0,0,0,0,0,0,BW43,0,0,0,0,0,0,0,0,0,0~
,0,0,0,0,0,0,0,0,0,0,0,0,0,0,0)';$S;IN;
    'P0_TXP9||SATA11_TXP':'(0,0,0,0,0,0,0,0,0,0,0,0,0,0,CN47,0,0,0,0,0,0,0,0,0,0~
,0,0,0,0,0,0,0,0,0,0,0,0,0,0,0)';$S;OUT;
    'P0_RXN13||SATA15_RXN':'(0,0,0,0,0,0,0,0,0,0,0,0,0,0,CB41,0,0,0,0,0,0,0,0,0,~
0,0,0,0,0,0,0,0,0,0,0,0,0,0,0,0)';$S;IN;
    'P0_RXN10||SATA12_RXN':'(0,0,0,0,0,0,0,0,0,0,0,0,0,0,CA44,0,0,0,0,0,0,0,0,0,~
0,0,0,0,0,0,0,0,0,0,0,0,0,0,0,0)';$S;IN;
    'P0_TXP14||SATA16_TXP':'(0,0,0,0,0,0,0,0,0,0,0,0,0,0,CP41,0,0,0,0,0,0,0,0,0,~
0,0,0,0,0,0,0,0,0,0,0,0,0,0,0,0)';$S;OUT;
    'P0_TXP11||SATA13_TXP':'(0,0,0,0,0,0,0,0,0,0,0,0,0,0,CU44,0,0,0,0,0,0,0,0,0,~
0,0,0,0,0,0,0,0,0,0,0,0,0,0,0,0)';$S;OUT;
    'P0_RXN9||SATA11_RXN':'(0,0,0,0,0,0,0,0,0,0,0,0,0,0,BW44,0,0,0,0,0,0,0,0,0,0~
,0,0,0,0,0,0,0,0,0,0,0,0,0,0,0)';$S;IN;
    'P0_RXP10||SATA12_RXP':'(0,0,0,0,0,0,0,0,0,0,0,0,0,0,CA43,0,0,0,0,0,0,0,0,0,~
0,0,0,0,0,0,0,0,0,0,0,0,0,0,0,0)';$S;IN;
    'P0_TXN12||SATA14_TXN':'(0,0,0,0,0,0,0,0,0,0,0,0,0,0,CN43,0,0,0,0,0,0,0,0,0,~
0,0,0,0,0,0,0,0,0,0,0,0,0,0,0,0)';$S;OUT;
    'P0_TXN9||SATA11_TXN':'(0,0,0,0,0,0,0,0,0,0,0,0,0,0,CN46,0,0,0,0,0,0,0,0,0,0~
,0,0,0,0,0,0,0,0,0,0,0,0,0,0,0)';$S;OUT;
    'P0_RXP13||SATA15_RXP':'(0,0,0,0,0,0,0,0,0,0,0,0,0,0,CB40,0,0,0,0,0,0,0,0,0,~
0,0,0,0,0,0,0,0,0,0,0,0,0,0,0,0)';$S;IN;
    'P0_TXN15||SATA17_TXN':'(0,0,0,0,0,0,0,0,0,0,0,0,0,0,CM40,0,0,0,0,0,0,0,0,0,~
0,0,0,0,0,0,0,0,0,0,0,0,0,0,0,0)';$S;OUT;
    'P0_RXN14||SATA16_RXN':'(0,0,0,0,0,0,0,0,0,0,0,0,0,0,BV41,0,0,0,0,0,0,0,0,0,~
0,0,0,0,0,0,0,0,0,0,0,0,0,0,0,0)';$S;IN;
    'P0_RXN11||SATA13_RXN':'(0,0,0,0,0,0,0,0,0,0,0,0,0,0,BU44,0,0,0,0,0,0,0,0,0,~
0,0,0,0,0,0,0,0,0,0,0,0,0,0,0,0)';$S;IN;
    'P0_TXP15||SATA17_TXP':'(0,0,0,0,0,0,0,0,0,0,0,0,0,0,CM41,0,0,0,0,0,0,0,0,0,~
0,0,0,0,0,0,0,0,0,0,0,0,0,0,0,0)';$S;OUT;
    'P0_TXP12||SATA14_TXP':'(0,0,0,0,0,0,0,0,0,0,0,0,0,0,CN44,0,0,0,0,0,0,0,0,0,~
0,0,0,0,0,0,0,0,0,0,0,0,0,0,0,0)';$S;OUT;
    'P0_RXP11||SATA13_RXP':'(0,0,0,0,0,0,0,0,0,0,0,0,0,0,BU43,0,0,0,0,0,0,0,0,0,~
0,0,0,0,0,0,0,0,0,0,0,0,0,0,0,0)';$S;IN;
    'P1_RXP8':'(0,0,0,0,0,0,0,0,0,0,0,0,0,0,0,CC46,0,0,0,0,0,0,0,0,0,0,0,0,0,0,0~
,0,0,0,0,0,0,0,0,0)';$S;IN;
    'P1_RXN8':'(0,0,0,0,0,0,0,0,0,0,0,0,0,0,0,CC47,0,0,0,0,0,0,0,0,0,0,0,0,0,0,0~
,0,0,0,0,0,0,0,0,0)';$S;IN;
    'P1_RXP9':'(0,0,0,0,0,0,0,0,0,0,0,0,0,0,0,CE43,0,0,0,0,0,0,0,0,0,0,0,0,0,0,0~
,0,0,0,0,0,0,0,0,0)';$S;IN;
    'P1_RXN9':'(0,0,0,0,0,0,0,0,0,0,0,0,0,0,0,CE44,0,0,0,0,0,0,0,0,0,0,0,0,0,0,0~
,0,0,0,0,0,0,0,0,0)';$S;IN;
    'P1_RXP10':'(0,0,0,0,0,0,0,0,0,0,0,0,0,0,0,CG43,0,0,0,0,0,0,0,0,0,0,0,0,0,0,~
0,0,0,0,0,0,0,0,0,0)';$S;IN;
    'P1_RXN10':'(0,0,0,0,0,0,0,0,0,0,0,0,0,0,0,CG44,0,0,0,0,0,0,0,0,0,0,0,0,0,0,~
0,0,0,0,0,0,0,0,0,0)';$S;IN;
    'P1_RXP11':'(0,0,0,0,0,0,0,0,0,0,0,0,0,0,0,CJ43,0,0,0,0,0,0,0,0,0,0,0,0,0,0,~
0,0,0,0,0,0,0,0,0,0)';$S;IN;
    'P1_RXN11':'(0,0,0,0,0,0,0,0,0,0,0,0,0,0,0,CJ44,0,0,0,0,0,0,0,0,0,0,0,0,0,0,~
0,0,0,0,0,0,0,0,0,0)';$S;IN;
    'P1_RXP12':'(0,0,0,0,0,0,0,0,0,0,0,0,0,0,0,CC43,0,0,0,0,0,0,0,0,0,0,0,0,0,0,~
0,0,0,0,0,0,0,0,0,0)';$S;IN;
    'P1_RXN12':'(0,0,0,0,0,0,0,0,0,0,0,0,0,0,0,CC44,0,0,0,0,0,0,0,0,0,0,0,0,0,0,~
0,0,0,0,0,0,0,0,0,0)';$S;IN;
    'P1_RXP13':'(0,0,0,0,0,0,0,0,0,0,0,0,0,0,0,CH40,0,0,0,0,0,0,0,0,0,0,0,0,0,0,~
0,0,0,0,0,0,0,0,0,0)';$S;IN;
    'P1_RXN13':'(0,0,0,0,0,0,0,0,0,0,0,0,0,0,0,CH41,0,0,0,0,0,0,0,0,0,0,0,0,0,0,~
0,0,0,0,0,0,0,0,0,0)';$S;IN;
    'P1_RXP14':'(0,0,0,0,0,0,0,0,0,0,0,0,0,0,0,CF40,0,0,0,0,0,0,0,0,0,0,0,0,0,0,~
0,0,0,0,0,0,0,0,0,0)';$S;IN;
    'P1_RXN14':'(0,0,0,0,0,0,0,0,0,0,0,0,0,0,0,CF41,0,0,0,0,0,0,0,0,0,0,0,0,0,0,~
0,0,0,0,0,0,0,0,0,0)';$S;IN;
    'P1_RXP15':'(0,0,0,0,0,0,0,0,0,0,0,0,0,0,0,CD40,0,0,0,0,0,0,0,0,0,0,0,0,0,0,~
0,0,0,0,0,0,0,0,0,0)';$S;IN;
    'P1_RXN15':'(0,0,0,0,0,0,0,0,0,0,0,0,0,0,0,CD41,0,0,0,0,0,0,0,0,0,0,0,0,0,0,~
0,0,0,0,0,0,0,0,0,0)';$S;IN;
    'P1_TXP8':'(0,0,0,0,0,0,0,0,0,0,0,0,0,0,0,DC47,0,0,0,0,0,0,0,0,0,0,0,0,0,0,0~
,0,0,0,0,0,0,0,0,0)';$S;OUT;
    'P1_TXN8':'(0,0,0,0,0,0,0,0,0,0,0,0,0,0,0,DC46,0,0,0,0,0,0,0,0,0,0,0,0,0,0,0~
,0,0,0,0,0,0,0,0,0)';$S;OUT;
    'P1_TXP9':'(0,0,0,0,0,0,0,0,0,0,0,0,0,0,0,CW47,0,0,0,0,0,0,0,0,0,0,0,0,0,0,0~
,0,0,0,0,0,0,0,0,0)';$S;OUT;
    'P1_TXN9':'(0,0,0,0,0,0,0,0,0,0,0,0,0,0,0,CW46,0,0,0,0,0,0,0,0,0,0,0,0,0,0,0~
,0,0,0,0,0,0,0,0,0)';$S;OUT;
    'P1_TXP10':'(0,0,0,0,0,0,0,0,0,0,0,0,0,0,0,DA44,0,0,0,0,0,0,0,0,0,0,0,0,0,0,~
0,0,0,0,0,0,0,0,0,0)';$S;OUT;
    'P1_TXN10':'(0,0,0,0,0,0,0,0,0,0,0,0,0,0,0,DA43,0,0,0,0,0,0,0,0,0,0,0,0,0,0,~
0,0,0,0,0,0,0,0,0,0)';$S;OUT;
    'P1_TXP11':'(0,0,0,0,0,0,0,0,0,0,0,0,0,0,0,DC44,0,0,0,0,0,0,0,0,0,0,0,0,0,0,~
0,0,0,0,0,0,0,0,0,0)';$S;OUT;
    'P1_TXN11':'(0,0,0,0,0,0,0,0,0,0,0,0,0,0,0,DC43,0,0,0,0,0,0,0,0,0,0,0,0,0,0,~
0,0,0,0,0,0,0,0,0,0)';$S;OUT;
    'P1_TXP12':'(0,0,0,0,0,0,0,0,0,0,0,0,0,0,0,CW44,0,0,0,0,0,0,0,0,0,0,0,0,0,0,~
0,0,0,0,0,0,0,0,0,0)';$S;OUT;
    'P1_TXN12':'(0,0,0,0,0,0,0,0,0,0,0,0,0,0,0,CW43,0,0,0,0,0,0,0,0,0,0,0,0,0,0,~
0,0,0,0,0,0,0,0,0,0)';$S;OUT;
    'P1_TXP13':'(0,0,0,0,0,0,0,0,0,0,0,0,0,0,0,DB41,0,0,0,0,0,0,0,0,0,0,0,0,0,0,~
0,0,0,0,0,0,0,0,0,0)';$S;OUT;
    'P1_TXN13':'(0,0,0,0,0,0,0,0,0,0,0,0,0,0,0,DB40,0,0,0,0,0,0,0,0,0,0,0,0,0,0,~
0,0,0,0,0,0,0,0,0,0)';$S;OUT;
    'P1_TXP14':'(0,0,0,0,0,0,0,0,0,0,0,0,0,0,0,CY41,0,0,0,0,0,0,0,0,0,0,0,0,0,0,~
0,0,0,0,0,0,0,0,0,0)';$S;OUT;
    'P1_TXN14':'(0,0,0,0,0,0,0,0,0,0,0,0,0,0,0,CY40,0,0,0,0,0,0,0,0,0,0,0,0,0,0,~
0,0,0,0,0,0,0,0,0,0)';$S;OUT;
    'P1_TXP15':'(0,0,0,0,0,0,0,0,0,0,0,0,0,0,0,CV41,0,0,0,0,0,0,0,0,0,0,0,0,0,0,~
0,0,0,0,0,0,0,0,0,0)';$S;OUT;
    'P1_TXN15':'(0,0,0,0,0,0,0,0,0,0,0,0,0,0,0,CV40,0,0,0,0,0,0,0,0,0,0,0,0,0,0,~
0,0,0,0,0,0,0,0,0,0)';$S;OUT;
    'P1_RXN7':'(0,0,0,0,0,0,0,0,0,0,0,0,0,0,0,CG47,0,0,0,0,0,0,0,0,0,0,0,0,0,0,0~
,0,0,0,0,0,0,0,0,0)';$S;IN;
    'P1_TXP0':'(0,0,0,0,0,0,0,0,0,0,0,0,0,0,0,CU53,0,0,0,0,0,0,0,0,0,0,0,0,0,0,0~
,0,0,0,0,0,0,0,0,0)';$S;OUT;
    'P1_TXP1':'(0,0,0,0,0,0,0,0,0,0,0,0,0,0,0,DA53,0,0,0,0,0,0,0,0,0,0,0,0,0,0,0~
,0,0,0,0,0,0,0,0,0)';$S;OUT;
    'P1_TXP2':'(0,0,0,0,0,0,0,0,0,0,0,0,0,0,0,DC53,0,0,0,0,0,0,0,0,0,0,0,0,0,0,0~
,0,0,0,0,0,0,0,0,0)';$S;OUT;
    'P1_TXN0':'(0,0,0,0,0,0,0,0,0,0,0,0,0,0,0,CU52,0,0,0,0,0,0,0,0,0,0,0,0,0,0,0~
,0,0,0,0,0,0,0,0,0)';$S;OUT;
    'P1_RXP0':'(0,0,0,0,0,0,0,0,0,0,0,0,0,0,0,CE52,0,0,0,0,0,0,0,0,0,0,0,0,0,0,0~
,0,0,0,0,0,0,0,0,0)';$S;IN;
    'P1_TXP3':'(0,0,0,0,0,0,0,0,0,0,0,0,0,0,0,CW53,0,0,0,0,0,0,0,0,0,0,0,0,0,0,0~
,0,0,0,0,0,0,0,0,0)';$S;OUT;
    'P1_TXN1':'(0,0,0,0,0,0,0,0,0,0,0,0,0,0,0,DA52,0,0,0,0,0,0,0,0,0,0,0,0,0,0,0~
,0,0,0,0,0,0,0,0,0)';$S;OUT;
    'P1_RXP1':'(0,0,0,0,0,0,0,0,0,0,0,0,0,0,0,CG52,0,0,0,0,0,0,0,0,0,0,0,0,0,0,0~
,0,0,0,0,0,0,0,0,0)';$S;IN;
    'P1_TXP4':'(0,0,0,0,0,0,0,0,0,0,0,0,0,0,0,DA50,0,0,0,0,0,0,0,0,0,0,0,0,0,0,0~
,0,0,0,0,0,0,0,0,0)';$S;OUT;
    'P1_TXN2':'(0,0,0,0,0,0,0,0,0,0,0,0,0,0,0,DC52,0,0,0,0,0,0,0,0,0,0,0,0,0,0,0~
,0,0,0,0,0,0,0,0,0)';$S;OUT;
    'P1_RXP2':'(0,0,0,0,0,0,0,0,0,0,0,0,0,0,0,CC52,0,0,0,0,0,0,0,0,0,0,0,0,0,0,0~
,0,0,0,0,0,0,0,0,0)';$S;IN;
    'P1_RXN0':'(0,0,0,0,0,0,0,0,0,0,0,0,0,0,0,CE53,0,0,0,0,0,0,0,0,0,0,0,0,0,0,0~
,0,0,0,0,0,0,0,0,0)';$S;IN;
    'P1_TXP5':'(0,0,0,0,0,0,0,0,0,0,0,0,0,0,0,DC50,0,0,0,0,0,0,0,0,0,0,0,0,0,0,0~
,0,0,0,0,0,0,0,0,0)';$S;OUT;
    'P1_TXN3':'(0,0,0,0,0,0,0,0,0,0,0,0,0,0,0,CW52,0,0,0,0,0,0,0,0,0,0,0,0,0,0,0~
,0,0,0,0,0,0,0,0,0)';$S;OUT;
    'P1_RXP3':'(0,0,0,0,0,0,0,0,0,0,0,0,0,0,0,CE49,0,0,0,0,0,0,0,0,0,0,0,0,0,0,0~
,0,0,0,0,0,0,0,0,0)';$S;IN;
    'P1_RXN1':'(0,0,0,0,0,0,0,0,0,0,0,0,0,0,0,CG53,0,0,0,0,0,0,0,0,0,0,0,0,0,0,0~
,0,0,0,0,0,0,0,0,0)';$S;IN;
    'P1_TXP6':'(0,0,0,0,0,0,0,0,0,0,0,0,0,0,0,CW50,0,0,0,0,0,0,0,0,0,0,0,0,0,0,0~
,0,0,0,0,0,0,0,0,0)';$S;OUT;
    'P1_TXN4':'(0,0,0,0,0,0,0,0,0,0,0,0,0,0,0,DA49,0,0,0,0,0,0,0,0,0,0,0,0,0,0,0~
,0,0,0,0,0,0,0,0,0)';$S;OUT;
    'P1_RXP4':'(0,0,0,0,0,0,0,0,0,0,0,0,0,0,0,CG49,0,0,0,0,0,0,0,0,0,0,0,0,0,0,0~
,0,0,0,0,0,0,0,0,0)';$S;IN;
    'P1_RXN2':'(0,0,0,0,0,0,0,0,0,0,0,0,0,0,0,CC53,0,0,0,0,0,0,0,0,0,0,0,0,0,0,0~
,0,0,0,0,0,0,0,0,0)';$S;IN;
    'P1_TXP7':'(0,0,0,0,0,0,0,0,0,0,0,0,0,0,0,DA47,0,0,0,0,0,0,0,0,0,0,0,0,0,0,0~
,0,0,0,0,0,0,0,0,0)';$S;OUT;
    'P1_TXN5':'(0,0,0,0,0,0,0,0,0,0,0,0,0,0,0,DC49,0,0,0,0,0,0,0,0,0,0,0,0,0,0,0~
,0,0,0,0,0,0,0,0,0)';$S;OUT;
    'P1_RXP5':'(0,0,0,0,0,0,0,0,0,0,0,0,0,0,0,CC49,0,0,0,0,0,0,0,0,0,0,0,0,0,0,0~
,0,0,0,0,0,0,0,0,0)';$S;IN;
    'P1_RXN3':'(0,0,0,0,0,0,0,0,0,0,0,0,0,0,0,CE50,0,0,0,0,0,0,0,0,0,0,0,0,0,0,0~
,0,0,0,0,0,0,0,0,0)';$S;IN;
    'P1_TXN6':'(0,0,0,0,0,0,0,0,0,0,0,0,0,0,0,CW49,0,0,0,0,0,0,0,0,0,0,0,0,0,0,0~
,0,0,0,0,0,0,0,0,0)';$S;OUT;
    'P1_RXP6':'(0,0,0,0,0,0,0,0,0,0,0,0,0,0,0,CE46,0,0,0,0,0,0,0,0,0,0,0,0,0,0,0~
,0,0,0,0,0,0,0,0,0)';$S;IN;
    'P1_RXN4':'(0,0,0,0,0,0,0,0,0,0,0,0,0,0,0,CG50,0,0,0,0,0,0,0,0,0,0,0,0,0,0,0~
,0,0,0,0,0,0,0,0,0)';$S;IN;
    'P1_TXN7':'(0,0,0,0,0,0,0,0,0,0,0,0,0,0,0,DA46,0,0,0,0,0,0,0,0,0,0,0,0,0,0,0~
,0,0,0,0,0,0,0,0,0)';$S;OUT;
    'P1_RXP7':'(0,0,0,0,0,0,0,0,0,0,0,0,0,0,0,CG46,0,0,0,0,0,0,0,0,0,0,0,0,0,0,0~
,0,0,0,0,0,0,0,0,0)';$S;IN;
    'P1_RXN5':'(0,0,0,0,0,0,0,0,0,0,0,0,0,0,0,CC50,0,0,0,0,0,0,0,0,0,0,0,0,0,0,0~
,0,0,0,0,0,0,0,0,0)';$S;IN;
    'P1_RXN6':'(0,0,0,0,0,0,0,0,0,0,0,0,0,0,0,CE47,0,0,0,0,0,0,0,0,0,0,0,0,0,0,0~
,0,0,0,0,0,0,0,0,0)';$S;IN;
    'P2_RXP8':'(0,0,0,0,0,0,0,0,0,0,0,0,0,0,0,0,CR29,0,0,0,0,0,0,0,0,0,0,0,0,0,0~
,0,0,0,0,0,0,0,0,0)';$S;IN;
    'P2_RXN8':'(0,0,0,0,0,0,0,0,0,0,0,0,0,0,0,0,CR30,0,0,0,0,0,0,0,0,0,0,0,0,0,0~
,0,0,0,0,0,0,0,0,0)';$S;IN;
    'P2_RXP9':'(0,0,0,0,0,0,0,0,0,0,0,0,0,0,0,0,CL26,0,0,0,0,0,0,0,0,0,0,0,0,0,0~
,0,0,0,0,0,0,0,0,0)';$S;IN;
    'P2_RXN9':'(0,0,0,0,0,0,0,0,0,0,0,0,0,0,0,0,CL27,0,0,0,0,0,0,0,0,0,0,0,0,0,0~
,0,0,0,0,0,0,0,0,0)';$S;IN;
    'P2_RXP10':'(0,0,0,0,0,0,0,0,0,0,0,0,0,0,0,0,CU26,0,0,0,0,0,0,0,0,0,0,0,0,0,~
0,0,0,0,0,0,0,0,0,0)';$S;IN;
    'P2_RXN10':'(0,0,0,0,0,0,0,0,0,0,0,0,0,0,0,0,CU27,0,0,0,0,0,0,0,0,0,0,0,0,0,~
0,0,0,0,0,0,0,0,0,0)';$S;IN;
    'P2_RXP11':'(0,0,0,0,0,0,0,0,0,0,0,0,0,0,0,0,CR26,0,0,0,0,0,0,0,0,0,0,0,0,0,~
0,0,0,0,0,0,0,0,0,0)';$S;IN;
    'P2_RXN11':'(0,0,0,0,0,0,0,0,0,0,0,0,0,0,0,0,CR27,0,0,0,0,0,0,0,0,0,0,0,0,0,~
0,0,0,0,0,0,0,0,0,0)';$S;IN;
    'P2_RXP12':'(0,0,0,0,0,0,0,0,0,0,0,0,0,0,0,0,CN26,0,0,0,0,0,0,0,0,0,0,0,0,0,~
0,0,0,0,0,0,0,0,0,0)';$S;IN;
    'P2_RXN12':'(0,0,0,0,0,0,0,0,0,0,0,0,0,0,0,0,CN27,0,0,0,0,0,0,0,0,0,0,0,0,0,~
0,0,0,0,0,0,0,0,0,0)';$S;IN;
    'P2_RXP13':'(0,0,0,0,0,0,0,0,0,0,0,0,0,0,0,0,CL23,0,0,0,0,0,0,0,0,0,0,0,0,0,~
0,0,0,0,0,0,0,0,0,0)';$S;IN;
    'P2_RXN13':'(0,0,0,0,0,0,0,0,0,0,0,0,0,0,0,0,CL24,0,0,0,0,0,0,0,0,0,0,0,0,0,~
0,0,0,0,0,0,0,0,0,0)';$S;IN;
    'P2_RXP14':'(0,0,0,0,0,0,0,0,0,0,0,0,0,0,0,0,CR23,0,0,0,0,0,0,0,0,0,0,0,0,0,~
0,0,0,0,0,0,0,0,0,0)';$S;IN;
    'P2_RXN14':'(0,0,0,0,0,0,0,0,0,0,0,0,0,0,0,0,CR24,0,0,0,0,0,0,0,0,0,0,0,0,0,~
0,0,0,0,0,0,0,0,0,0)';$S;IN;
    'P2_RXP15':'(0,0,0,0,0,0,0,0,0,0,0,0,0,0,0,0,CN23,0,0,0,0,0,0,0,0,0,0,0,0,0,~
0,0,0,0,0,0,0,0,0,0)';$S;IN;
    'P2_RXN15':'(0,0,0,0,0,0,0,0,0,0,0,0,0,0,0,0,CN24,0,0,0,0,0,0,0,0,0,0,0,0,0,~
0,0,0,0,0,0,0,0,0,0)';$S;IN;
    'P2_TXP8':'(0,0,0,0,0,0,0,0,0,0,0,0,0,0,0,0,CA30,0,0,0,0,0,0,0,0,0,0,0,0,0,0~
,0,0,0,0,0,0,0,0,0)';$S;OUT;
    'P2_TXN8':'(0,0,0,0,0,0,0,0,0,0,0,0,0,0,0,0,CA29,0,0,0,0,0,0,0,0,0,0,0,0,0,0~
,0,0,0,0,0,0,0,0,0)';$S;OUT;
    'P2_TXP9':'(0,0,0,0,0,0,0,0,0,0,0,0,0,0,0,0,BW30,0,0,0,0,0,0,0,0,0,0,0,0,0,0~
,0,0,0,0,0,0,0,0,0)';$S;OUT;
    'P2_TXN9':'(0,0,0,0,0,0,0,0,0,0,0,0,0,0,0,0,BW29,0,0,0,0,0,0,0,0,0,0,0,0,0,0~
,0,0,0,0,0,0,0,0,0)';$S;OUT;
    'P2_TXP10':'(0,0,0,0,0,0,0,0,0,0,0,0,0,0,0,0,BU27,0,0,0,0,0,0,0,0,0,0,0,0,0,~
0,0,0,0,0,0,0,0,0,0)';$S;OUT;
    'P2_TXN10':'(0,0,0,0,0,0,0,0,0,0,0,0,0,0,0,0,BU26,0,0,0,0,0,0,0,0,0,0,0,0,0,~
0,0,0,0,0,0,0,0,0,0)';$S;OUT;
    'P2_TXP11':'(0,0,0,0,0,0,0,0,0,0,0,0,0,0,0,0,CA27,0,0,0,0,0,0,0,0,0,0,0,0,0,~
0,0,0,0,0,0,0,0,0,0)';$S;OUT;
    'P2_TXN11':'(0,0,0,0,0,0,0,0,0,0,0,0,0,0,0,0,CA26,0,0,0,0,0,0,0,0,0,0,0,0,0,~
0,0,0,0,0,0,0,0,0,0)';$S;OUT;
    'P2_TXP12':'(0,0,0,0,0,0,0,0,0,0,0,0,0,0,0,0,BW27,0,0,0,0,0,0,0,0,0,0,0,0,0,~
0,0,0,0,0,0,0,0,0,0)';$S;OUT;
    'P2_TXN12':'(0,0,0,0,0,0,0,0,0,0,0,0,0,0,0,0,BW26,0,0,0,0,0,0,0,0,0,0,0,0,0,~
0,0,0,0,0,0,0,0,0,0)';$S;OUT;
    'P2_TXP13':'(0,0,0,0,0,0,0,0,0,0,0,0,0,0,0,0,BU24,0,0,0,0,0,0,0,0,0,0,0,0,0,~
0,0,0,0,0,0,0,0,0,0)';$S;OUT;
    'P2_TXN13':'(0,0,0,0,0,0,0,0,0,0,0,0,0,0,0,0,BU23,0,0,0,0,0,0,0,0,0,0,0,0,0,~
0,0,0,0,0,0,0,0,0,0)';$S;OUT;
    'P2_TXP14':'(0,0,0,0,0,0,0,0,0,0,0,0,0,0,0,0,CA24,0,0,0,0,0,0,0,0,0,0,0,0,0,~
0,0,0,0,0,0,0,0,0,0)';$S;OUT;
    'P2_TXN14':'(0,0,0,0,0,0,0,0,0,0,0,0,0,0,0,0,CA23,0,0,0,0,0,0,0,0,0,0,0,0,0,~
0,0,0,0,0,0,0,0,0,0)';$S;OUT;
    'P2_TXP15':'(0,0,0,0,0,0,0,0,0,0,0,0,0,0,0,0,BW24,0,0,0,0,0,0,0,0,0,0,0,0,0,~
0,0,0,0,0,0,0,0,0,0)';$S;OUT;
    'P2_TXN15':'(0,0,0,0,0,0,0,0,0,0,0,0,0,0,0,0,BW23,0,0,0,0,0,0,0,0,0,0,0,0,0,~
0,0,0,0,0,0,0,0,0,0)';$S;OUT;
    'P2_TXP0':'(0,0,0,0,0,0,0,0,0,0,0,0,0,0,0,0,BT36,0,0,0,0,0,0,0,0,0,0,0,0,0,0~
,0,0,0,0,0,0,0,0,0)';$S;OUT;
    'P2_TXP1':'(0,0,0,0,0,0,0,0,0,0,0,0,0,0,0,0,BV36,0,0,0,0,0,0,0,0,0,0,0,0,0,0~
,0,0,0,0,0,0,0,0,0)';$S;OUT;
    'P2_TXP2':'(0,0,0,0,0,0,0,0,0,0,0,0,0,0,0,0,CB36,0,0,0,0,0,0,0,0,0,0,0,0,0,0~
,0,0,0,0,0,0,0,0,0)';$S;OUT;
    'P2_TXN0':'(0,0,0,0,0,0,0,0,0,0,0,0,0,0,0,0,BT35,0,0,0,0,0,0,0,0,0,0,0,0,0,0~
,0,0,0,0,0,0,0,0,0)';$S;OUT;
    'P2_RXP0':'(0,0,0,0,0,0,0,0,0,0,0,0,0,0,0,0,CM35,0,0,0,0,0,0,0,0,0,0,0,0,0,0~
,0,0,0,0,0,0,0,0,0)';$S;IN;
    'P2_TXP3':'(0,0,0,0,0,0,0,0,0,0,0,0,0,0,0,0,BY36,0,0,0,0,0,0,0,0,0,0,0,0,0,0~
,0,0,0,0,0,0,0,0,0)';$S;OUT;
    'P2_TXN1':'(0,0,0,0,0,0,0,0,0,0,0,0,0,0,0,0,BV35,0,0,0,0,0,0,0,0,0,0,0,0,0,0~
,0,0,0,0,0,0,0,0,0)';$S;OUT;
    'P2_RXP1':'(0,0,0,0,0,0,0,0,0,0,0,0,0,0,0,0,CP35,0,0,0,0,0,0,0,0,0,0,0,0,0,0~
,0,0,0,0,0,0,0,0,0)';$S;IN;
    'P2_TXP4':'(0,0,0,0,0,0,0,0,0,0,0,0,0,0,0,0,BU33,0,0,0,0,0,0,0,0,0,0,0,0,0,0~
,0,0,0,0,0,0,0,0,0)';$S;OUT;
    'P2_TXN2':'(0,0,0,0,0,0,0,0,0,0,0,0,0,0,0,0,CB35,0,0,0,0,0,0,0,0,0,0,0,0,0,0~
,0,0,0,0,0,0,0,0,0)';$S;OUT;
    'P2_RXP2':'(0,0,0,0,0,0,0,0,0,0,0,0,0,0,0,0,CT35,0,0,0,0,0,0,0,0,0,0,0,0,0,0~
,0,0,0,0,0,0,0,0,0)';$S;IN;
    'P2_RXN0':'(0,0,0,0,0,0,0,0,0,0,0,0,0,0,0,0,CM36,0,0,0,0,0,0,0,0,0,0,0,0,0,0~
,0,0,0,0,0,0,0,0,0)';$S;IN;
    'P2_TXP5':'(0,0,0,0,0,0,0,0,0,0,0,0,0,0,0,0,CA33,0,0,0,0,0,0,0,0,0,0,0,0,0,0~
,0,0,0,0,0,0,0,0,0)';$S;OUT;
    'P2_TXN3':'(0,0,0,0,0,0,0,0,0,0,0,0,0,0,0,0,BY35,0,0,0,0,0,0,0,0,0,0,0,0,0,0~
,0,0,0,0,0,0,0,0,0)';$S;OUT;
    'P2_RXP3':'(0,0,0,0,0,0,0,0,0,0,0,0,0,0,0,0,CN32,0,0,0,0,0,0,0,0,0,0,0,0,0,0~
,0,0,0,0,0,0,0,0,0)';$S;IN;
    'P2_RXN1':'(0,0,0,0,0,0,0,0,0,0,0,0,0,0,0,0,CP36,0,0,0,0,0,0,0,0,0,0,0,0,0,0~
,0,0,0,0,0,0,0,0,0)';$S;IN;
    'P2_TXP6':'(0,0,0,0,0,0,0,0,0,0,0,0,0,0,0,0,BW33,0,0,0,0,0,0,0,0,0,0,0,0,0,0~
,0,0,0,0,0,0,0,0,0)';$S;OUT;
    'P2_TXN4':'(0,0,0,0,0,0,0,0,0,0,0,0,0,0,0,0,BU32,0,0,0,0,0,0,0,0,0,0,0,0,0,0~
,0,0,0,0,0,0,0,0,0)';$S;OUT;
    'P2_RXP4':'(0,0,0,0,0,0,0,0,0,0,0,0,0,0,0,0,CU32,0,0,0,0,0,0,0,0,0,0,0,0,0,0~
,0,0,0,0,0,0,0,0,0)';$S;IN;
    'P2_RXN2':'(0,0,0,0,0,0,0,0,0,0,0,0,0,0,0,0,CT36,0,0,0,0,0,0,0,0,0,0,0,0,0,0~
,0,0,0,0,0,0,0,0,0)';$S;IN;
    'P2_TXP7':'(0,0,0,0,0,0,0,0,0,0,0,0,0,0,0,0,BU30,0,0,0,0,0,0,0,0,0,0,0,0,0,0~
,0,0,0,0,0,0,0,0,0)';$S;OUT;
    'P2_TXN5':'(0,0,0,0,0,0,0,0,0,0,0,0,0,0,0,0,CA32,0,0,0,0,0,0,0,0,0,0,0,0,0,0~
,0,0,0,0,0,0,0,0,0)';$S;OUT;
    'P2_RXP5':'(0,0,0,0,0,0,0,0,0,0,0,0,0,0,0,0,CR32,0,0,0,0,0,0,0,0,0,0,0,0,0,0~
,0,0,0,0,0,0,0,0,0)';$S;IN;
    'P2_RXN3':'(0,0,0,0,0,0,0,0,0,0,0,0,0,0,0,0,CN33,0,0,0,0,0,0,0,0,0,0,0,0,0,0~
,0,0,0,0,0,0,0,0,0)';$S;IN;
    'P2_TXN6':'(0,0,0,0,0,0,0,0,0,0,0,0,0,0,0,0,BW32,0,0,0,0,0,0,0,0,0,0,0,0,0,0~
,0,0,0,0,0,0,0,0,0)';$S;OUT;
    'P2_RXP6':'(0,0,0,0,0,0,0,0,0,0,0,0,0,0,0,0,CN29,0,0,0,0,0,0,0,0,0,0,0,0,0,0~
,0,0,0,0,0,0,0,0,0)';$S;IN;
    'P2_RXN4':'(0,0,0,0,0,0,0,0,0,0,0,0,0,0,0,0,CU33,0,0,0,0,0,0,0,0,0,0,0,0,0,0~
,0,0,0,0,0,0,0,0,0)';$S;IN;
    'P2_TXN7':'(0,0,0,0,0,0,0,0,0,0,0,0,0,0,0,0,BU29,0,0,0,0,0,0,0,0,0,0,0,0,0,0~
,0,0,0,0,0,0,0,0,0)';$S;OUT;
    'P2_RXP7':'(0,0,0,0,0,0,0,0,0,0,0,0,0,0,0,0,CU29,0,0,0,0,0,0,0,0,0,0,0,0,0,0~
,0,0,0,0,0,0,0,0,0)';$S;IN;
    'P2_RXN5':'(0,0,0,0,0,0,0,0,0,0,0,0,0,0,0,0,CR33,0,0,0,0,0,0,0,0,0,0,0,0,0,0~
,0,0,0,0,0,0,0,0,0)';$S;IN;
    'P2_RXN6':'(0,0,0,0,0,0,0,0,0,0,0,0,0,0,0,0,CN30,0,0,0,0,0,0,0,0,0,0,0,0,0,0~
,0,0,0,0,0,0,0,0,0)';$S;IN;
    'P2_RXN7':'(0,0,0,0,0,0,0,0,0,0,0,0,0,0,0,0,CU30,0,0,0,0,0,0,0,0,0,0,0,0,0,0~
,0,0,0,0,0,0,0,0,0)';$S;IN;
    'P3_RXP0':'(0,0,0,0,0,0,0,0,0,0,0,0,0,0,0,0,0,CV35,0,0,0,0,0,0,0,0,0,0,0,0,0~
,0,0,0,0,0,0,0,0,0)';$S;IN;
    'P3_RXN0':'(0,0,0,0,0,0,0,0,0,0,0,0,0,0,0,0,0,CV36,0,0,0,0,0,0,0,0,0,0,0,0,0~
,0,0,0,0,0,0,0,0,0)';$S;IN;
    'P3_RXP1':'(0,0,0,0,0,0,0,0,0,0,0,0,0,0,0,0,0,CY35,0,0,0,0,0,0,0,0,0,0,0,0,0~
,0,0,0,0,0,0,0,0,0)';$S;IN;
    'P3_RXN1':'(0,0,0,0,0,0,0,0,0,0,0,0,0,0,0,0,0,CY36,0,0,0,0,0,0,0,0,0,0,0,0,0~
,0,0,0,0,0,0,0,0,0)';$S;IN;
    'P3_RXP2':'(0,0,0,0,0,0,0,0,0,0,0,0,0,0,0,0,0,DB35,0,0,0,0,0,0,0,0,0,0,0,0,0~
,0,0,0,0,0,0,0,0,0)';$S;IN;
    'P3_RXN2':'(0,0,0,0,0,0,0,0,0,0,0,0,0,0,0,0,0,DB36,0,0,0,0,0,0,0,0,0,0,0,0,0~
,0,0,0,0,0,0,0,0,0)';$S;IN;
    'P3_RXP3':'(0,0,0,0,0,0,0,0,0,0,0,0,0,0,0,0,0,CW32,0,0,0,0,0,0,0,0,0,0,0,0,0~
,0,0,0,0,0,0,0,0,0)';$S;IN;
    'P3_RXN3':'(0,0,0,0,0,0,0,0,0,0,0,0,0,0,0,0,0,CW33,0,0,0,0,0,0,0,0,0,0,0,0,0~
,0,0,0,0,0,0,0,0,0)';$S;IN;
    'P3_RXP4':'(0,0,0,0,0,0,0,0,0,0,0,0,0,0,0,0,0,DC32,0,0,0,0,0,0,0,0,0,0,0,0,0~
,0,0,0,0,0,0,0,0,0)';$S;IN;
    'P3_RXN4':'(0,0,0,0,0,0,0,0,0,0,0,0,0,0,0,0,0,DC33,0,0,0,0,0,0,0,0,0,0,0,0,0~
,0,0,0,0,0,0,0,0,0)';$S;IN;
    'P3_RXP5':'(0,0,0,0,0,0,0,0,0,0,0,0,0,0,0,0,0,DA32,0,0,0,0,0,0,0,0,0,0,0,0,0~
,0,0,0,0,0,0,0,0,0)';$S;IN;
    'P3_RXN5':'(0,0,0,0,0,0,0,0,0,0,0,0,0,0,0,0,0,DA33,0,0,0,0,0,0,0,0,0,0,0,0,0~
,0,0,0,0,0,0,0,0,0)';$S;IN;
    'P3_RXP6':'(0,0,0,0,0,0,0,0,0,0,0,0,0,0,0,0,0,CW29,0,0,0,0,0,0,0,0,0,0,0,0,0~
,0,0,0,0,0,0,0,0,0)';$S;IN;
    'P3_RXN6':'(0,0,0,0,0,0,0,0,0,0,0,0,0,0,0,0,0,CW30,0,0,0,0,0,0,0,0,0,0,0,0,0~
,0,0,0,0,0,0,0,0,0)';$S;IN;
    'P3_RXP7':'(0,0,0,0,0,0,0,0,0,0,0,0,0,0,0,0,0,DC29,0,0,0,0,0,0,0,0,0,0,0,0,0~
,0,0,0,0,0,0,0,0,0)';$S;IN;
    'P3_RXN7':'(0,0,0,0,0,0,0,0,0,0,0,0,0,0,0,0,0,DC30,0,0,0,0,0,0,0,0,0,0,0,0,0~
,0,0,0,0,0,0,0,0,0)';$S;IN;
    'P3_RXP8':'(0,0,0,0,0,0,0,0,0,0,0,0,0,0,0,0,0,DA29,0,0,0,0,0,0,0,0,0,0,0,0,0~
,0,0,0,0,0,0,0,0,0)';$S;IN;
    'P3_RXN8':'(0,0,0,0,0,0,0,0,0,0,0,0,0,0,0,0,0,DA30,0,0,0,0,0,0,0,0,0,0,0,0,0~
,0,0,0,0,0,0,0,0,0)';$S;IN;
    'P3_RXP9':'(0,0,0,0,0,0,0,0,0,0,0,0,0,0,0,0,0,CW26,0,0,0,0,0,0,0,0,0,0,0,0,0~
,0,0,0,0,0,0,0,0,0)';$S;IN;
    'P3_RXN9':'(0,0,0,0,0,0,0,0,0,0,0,0,0,0,0,0,0,CW27,0,0,0,0,0,0,0,0,0,0,0,0,0~
,0,0,0,0,0,0,0,0,0)';$S;IN;
    'P3_RXP10':'(0,0,0,0,0,0,0,0,0,0,0,0,0,0,0,0,0,DC26,0,0,0,0,0,0,0,0,0,0,0,0,~
0,0,0,0,0,0,0,0,0,0)';$S;IN;
    'P3_RXN10':'(0,0,0,0,0,0,0,0,0,0,0,0,0,0,0,0,0,DC27,0,0,0,0,0,0,0,0,0,0,0,0,~
0,0,0,0,0,0,0,0,0,0)';$S;IN;
    'P3_RXP11':'(0,0,0,0,0,0,0,0,0,0,0,0,0,0,0,0,0,DA26,0,0,0,0,0,0,0,0,0,0,0,0,~
0,0,0,0,0,0,0,0,0,0)';$S;IN;
    'P3_RXN11':'(0,0,0,0,0,0,0,0,0,0,0,0,0,0,0,0,0,DA27,0,0,0,0,0,0,0,0,0,0,0,0,~
0,0,0,0,0,0,0,0,0,0)';$S;IN;
    'P3_RXP12':'(0,0,0,0,0,0,0,0,0,0,0,0,0,0,0,0,0,CW23,0,0,0,0,0,0,0,0,0,0,0,0,~
0,0,0,0,0,0,0,0,0,0)';$S;IN;
    'P3_RXN12':'(0,0,0,0,0,0,0,0,0,0,0,0,0,0,0,0,0,CW24,0,0,0,0,0,0,0,0,0,0,0,0,~
0,0,0,0,0,0,0,0,0,0)';$S;IN;
    'P3_RXP13':'(0,0,0,0,0,0,0,0,0,0,0,0,0,0,0,0,0,DC23,0,0,0,0,0,0,0,0,0,0,0,0,~
0,0,0,0,0,0,0,0,0,0)';$S;IN;
    'P3_RXN13':'(0,0,0,0,0,0,0,0,0,0,0,0,0,0,0,0,0,DC24,0,0,0,0,0,0,0,0,0,0,0,0,~
0,0,0,0,0,0,0,0,0,0)';$S;IN;
    'P3_RXP14':'(0,0,0,0,0,0,0,0,0,0,0,0,0,0,0,0,0,DA23,0,0,0,0,0,0,0,0,0,0,0,0,~
0,0,0,0,0,0,0,0,0,0)';$S;IN;
    'P3_RXN14':'(0,0,0,0,0,0,0,0,0,0,0,0,0,0,0,0,0,DA24,0,0,0,0,0,0,0,0,0,0,0,0,~
0,0,0,0,0,0,0,0,0,0)';$S;IN;
    'P3_RXP15':'(0,0,0,0,0,0,0,0,0,0,0,0,0,0,0,0,0,CU23,0,0,0,0,0,0,0,0,0,0,0,0,~
0,0,0,0,0,0,0,0,0,0)';$S;IN;
    'P3_RXN15':'(0,0,0,0,0,0,0,0,0,0,0,0,0,0,0,0,0,CU24,0,0,0,0,0,0,0,0,0,0,0,0,~
0,0,0,0,0,0,0,0,0,0)';$S;IN;
    'P3_TXP0':'(0,0,0,0,0,0,0,0,0,0,0,0,0,0,0,0,0,CD36,0,0,0,0,0,0,0,0,0,0,0,0,0~
,0,0,0,0,0,0,0,0,0)';$S;OUT;
    'P3_TXN0':'(0,0,0,0,0,0,0,0,0,0,0,0,0,0,0,0,0,CD35,0,0,0,0,0,0,0,0,0,0,0,0,0~
,0,0,0,0,0,0,0,0,0)';$S;OUT;
    'P3_TXP1':'(0,0,0,0,0,0,0,0,0,0,0,0,0,0,0,0,0,CF36,0,0,0,0,0,0,0,0,0,0,0,0,0~
,0,0,0,0,0,0,0,0,0)';$S;OUT;
    'P3_TXN1':'(0,0,0,0,0,0,0,0,0,0,0,0,0,0,0,0,0,CF35,0,0,0,0,0,0,0,0,0,0,0,0,0~
,0,0,0,0,0,0,0,0,0)';$S;OUT;
    'P3_TXP2':'(0,0,0,0,0,0,0,0,0,0,0,0,0,0,0,0,0,CH36,0,0,0,0,0,0,0,0,0,0,0,0,0~
,0,0,0,0,0,0,0,0,0)';$S;OUT;
    'P3_TXN2':'(0,0,0,0,0,0,0,0,0,0,0,0,0,0,0,0,0,CH35,0,0,0,0,0,0,0,0,0,0,0,0,0~
,0,0,0,0,0,0,0,0,0)';$S;OUT;
    'P3_TXP3':'(0,0,0,0,0,0,0,0,0,0,0,0,0,0,0,0,0,CC33,0,0,0,0,0,0,0,0,0,0,0,0,0~
,0,0,0,0,0,0,0,0,0)';$S;OUT;
    'P3_TXN3':'(0,0,0,0,0,0,0,0,0,0,0,0,0,0,0,0,0,CC32,0,0,0,0,0,0,0,0,0,0,0,0,0~
,0,0,0,0,0,0,0,0,0)';$S;OUT;
    'P3_TXP4':'(0,0,0,0,0,0,0,0,0,0,0,0,0,0,0,0,0,CJ33,0,0,0,0,0,0,0,0,0,0,0,0,0~
,0,0,0,0,0,0,0,0,0)';$S;OUT;
    'P3_TXN4':'(0,0,0,0,0,0,0,0,0,0,0,0,0,0,0,0,0,CJ32,0,0,0,0,0,0,0,0,0,0,0,0,0~
,0,0,0,0,0,0,0,0,0)';$S;OUT;
    'P3_TXP5':'(0,0,0,0,0,0,0,0,0,0,0,0,0,0,0,0,0,CG33,0,0,0,0,0,0,0,0,0,0,0,0,0~
,0,0,0,0,0,0,0,0,0)';$S;OUT;
    'P3_TXN5':'(0,0,0,0,0,0,0,0,0,0,0,0,0,0,0,0,0,CG32,0,0,0,0,0,0,0,0,0,0,0,0,0~
,0,0,0,0,0,0,0,0,0)';$S;OUT;
    'P3_TXP6':'(0,0,0,0,0,0,0,0,0,0,0,0,0,0,0,0,0,CE33,0,0,0,0,0,0,0,0,0,0,0,0,0~
,0,0,0,0,0,0,0,0,0)';$S;OUT;
    'P3_TXN6':'(0,0,0,0,0,0,0,0,0,0,0,0,0,0,0,0,0,CE32,0,0,0,0,0,0,0,0,0,0,0,0,0~
,0,0,0,0,0,0,0,0,0)';$S;OUT;
    'P3_TXP7':'(0,0,0,0,0,0,0,0,0,0,0,0,0,0,0,0,0,CC30,0,0,0,0,0,0,0,0,0,0,0,0,0~
,0,0,0,0,0,0,0,0,0)';$S;OUT;
    'P3_TXN7':'(0,0,0,0,0,0,0,0,0,0,0,0,0,0,0,0,0,CC29,0,0,0,0,0,0,0,0,0,0,0,0,0~
,0,0,0,0,0,0,0,0,0)';$S;OUT;
    'P3_TXP8':'(0,0,0,0,0,0,0,0,0,0,0,0,0,0,0,0,0,CG30,0,0,0,0,0,0,0,0,0,0,0,0,0~
,0,0,0,0,0,0,0,0,0)';$S;OUT;
    'P3_TXN8':'(0,0,0,0,0,0,0,0,0,0,0,0,0,0,0,0,0,CG29,0,0,0,0,0,0,0,0,0,0,0,0,0~
,0,0,0,0,0,0,0,0,0)';$S;OUT;
    'P3_TXP9':'(0,0,0,0,0,0,0,0,0,0,0,0,0,0,0,0,0,CE30,0,0,0,0,0,0,0,0,0,0,0,0,0~
,0,0,0,0,0,0,0,0,0)';$S;OUT;
    'P3_TXN9':'(0,0,0,0,0,0,0,0,0,0,0,0,0,0,0,0,0,CE29,0,0,0,0,0,0,0,0,0,0,0,0,0~
,0,0,0,0,0,0,0,0,0)';$S;OUT;
    'P3_TXP10':'(0,0,0,0,0,0,0,0,0,0,0,0,0,0,0,0,0,CC27,0,0,0,0,0,0,0,0,0,0,0,0,~
0,0,0,0,0,0,0,0,0,0)';$S;OUT;
    'P3_TXN10':'(0,0,0,0,0,0,0,0,0,0,0,0,0,0,0,0,0,CC26,0,0,0,0,0,0,0,0,0,0,0,0,~
0,0,0,0,0,0,0,0,0,0)';$S;OUT;
    'P3_TXP11':'(0,0,0,0,0,0,0,0,0,0,0,0,0,0,0,0,0,CG27,0,0,0,0,0,0,0,0,0,0,0,0,~
0,0,0,0,0,0,0,0,0,0)';$S;OUT;
    'P3_TXN11':'(0,0,0,0,0,0,0,0,0,0,0,0,0,0,0,0,0,CG26,0,0,0,0,0,0,0,0,0,0,0,0,~
0,0,0,0,0,0,0,0,0,0)';$S;OUT;
    'P3_TXP12':'(0,0,0,0,0,0,0,0,0,0,0,0,0,0,0,0,0,CE27,0,0,0,0,0,0,0,0,0,0,0,0,~
0,0,0,0,0,0,0,0,0,0)';$S;OUT;
    'P3_TXN12':'(0,0,0,0,0,0,0,0,0,0,0,0,0,0,0,0,0,CE26,0,0,0,0,0,0,0,0,0,0,0,0,~
0,0,0,0,0,0,0,0,0,0)';$S;OUT;
    'P3_TXP13':'(0,0,0,0,0,0,0,0,0,0,0,0,0,0,0,0,0,CC24,0,0,0,0,0,0,0,0,0,0,0,0,~
0,0,0,0,0,0,0,0,0,0)';$S;OUT;
    'P3_TXN13':'(0,0,0,0,0,0,0,0,0,0,0,0,0,0,0,0,0,CC23,0,0,0,0,0,0,0,0,0,0,0,0,~
0,0,0,0,0,0,0,0,0,0)';$S;OUT;
    'P3_TXP14':'(0,0,0,0,0,0,0,0,0,0,0,0,0,0,0,0,0,CG24,0,0,0,0,0,0,0,0,0,0,0,0,~
0,0,0,0,0,0,0,0,0,0)';$S;OUT;
    'P3_TXN14':'(0,0,0,0,0,0,0,0,0,0,0,0,0,0,0,0,0,CG23,0,0,0,0,0,0,0,0,0,0,0,0,~
0,0,0,0,0,0,0,0,0,0)';$S;OUT;
    'P3_TXP15':'(0,0,0,0,0,0,0,0,0,0,0,0,0,0,0,0,0,CE24,0,0,0,0,0,0,0,0,0,0,0,0,~
0,0,0,0,0,0,0,0,0,0)';$S;OUT;
    'P3_TXN15':'(0,0,0,0,0,0,0,0,0,0,0,0,0,0,0,0,0,CE23,0,0,0,0,0,0,0,0,0,0,0,0,~
0,0,0,0,0,0,0,0,0,0)';$S;OUT;
    'P4_RXN2':'(0,0,0,0,0,0,0,0,0,0,0,0,0,0,0,0,0,0,DG47,0,0,0,0,0,0,0,0,0,0,0,0~
,0,0,0,0,0,0,0,0,0)';$S;IN;
    'P4_RXN3':'(0,0,0,0,0,0,0,0,0,0,0,0,0,0,0,0,0,0,DG44,0,0,0,0,0,0,0,0,0,0,0,0~
,0,0,0,0,0,0,0,0,0)';$S;IN;
    'P4_RXP2':'(0,0,0,0,0,0,0,0,0,0,0,0,0,0,0,0,0,0,DG48,0,0,0,0,0,0,0,0,0,0,0,0~
,0,0,0,0,0,0,0,0,0)';$S;IN;
    'P4_RXP3':'(0,0,0,0,0,0,0,0,0,0,0,0,0,0,0,0,0,0,DG45,0,0,0,0,0,0,0,0,0,0,0,0~
,0,0,0,0,0,0,0,0,0)';$S;IN;
    'P4_TXN2':'(0,0,0,0,0,0,0,0,0,0,0,0,0,0,0,0,0,0,DE46,0,0,0,0,0,0,0,0,0,0,0,0~
,0,0,0,0,0,0,0,0,0)';$S;OUT;
    'P4_TXN3':'(0,0,0,0,0,0,0,0,0,0,0,0,0,0,0,0,0,0,DE43,0,0,0,0,0,0,0,0,0,0,0,0~
,0,0,0,0,0,0,0,0,0)';$S;OUT;
    'P4_TXP2':'(0,0,0,0,0,0,0,0,0,0,0,0,0,0,0,0,0,0,DE47,0,0,0,0,0,0,0,0,0,0,0,0~
,0,0,0,0,0,0,0,0,0)';$S;OUT;
    'P4_TXP3':'(0,0,0,0,0,0,0,0,0,0,0,0,0,0,0,0,0,0,DE44,0,0,0,0,0,0,0,0,0,0,0,0~
,0,0,0,0,0,0,0,0,0)';$S;OUT;
    'P5_RXN2':'(0,0,0,0,0,0,0,0,0,0,0,0,0,0,0,0,0,0,E44,0,0,0,0,0,0,0,0,0,0,0,0,~
0,0,0,0,0,0,0,0,0)';$S;IN;
    'P5_RXN3':'(0,0,0,0,0,0,0,0,0,0,0,0,0,0,0,0,0,0,E41,0,0,0,0,0,0,0,0,0,0,0,0,~
0,0,0,0,0,0,0,0,0)';$S;IN;
    'P5_RXP2':'(0,0,0,0,0,0,0,0,0,0,0,0,0,0,0,0,0,0,E43,0,0,0,0,0,0,0,0,0,0,0,0,~
0,0,0,0,0,0,0,0,0)';$S;IN;
    'P5_RXP3':'(0,0,0,0,0,0,0,0,0,0,0,0,0,0,0,0,0,0,E40,0,0,0,0,0,0,0,0,0,0,0,0,~
0,0,0,0,0,0,0,0,0)';$S;IN;
    'P5_TXN2':'(0,0,0,0,0,0,0,0,0,0,0,0,0,0,0,0,0,0,C45,0,0,0,0,0,0,0,0,0,0,0,0,~
0,0,0,0,0,0,0,0,0)';$S;OUT;
    'P5_TXN3':'(0,0,0,0,0,0,0,0,0,0,0,0,0,0,0,0,0,0,C42,0,0,0,0,0,0,0,0,0,0,0,0,~
0,0,0,0,0,0,0,0,0)';$S;OUT;
    'P5_TXP2':'(0,0,0,0,0,0,0,0,0,0,0,0,0,0,0,0,0,0,C44,0,0,0,0,0,0,0,0,0,0,0,0,~
0,0,0,0,0,0,0,0,0)';$S;OUT;
    'P5_TXP3':'(0,0,0,0,0,0,0,0,0,0,0,0,0,0,0,0,0,0,C41,0,0,0,0,0,0,0,0,0,0,0,0,~
0,0,0,0,0,0,0,0,0)';$S;OUT;
    'P4_TXP0':'(0,0,0,0,0,0,0,0,0,0,0,0,0,0,0,0,0,0,DE53,0,0,0,0,0,0,0,0,0,0,0,0~
,0,0,0,0,0,0,0,0,0)';$S;OUT;
    'P4_TXP1':'(0,0,0,0,0,0,0,0,0,0,0,0,0,0,0,0,0,0,DE50,0,0,0,0,0,0,0,0,0,0,0,0~
,0,0,0,0,0,0,0,0,0)';$S;OUT;
    'P4_TXN0':'(0,0,0,0,0,0,0,0,0,0,0,0,0,0,0,0,0,0,DE52,0,0,0,0,0,0,0,0,0,0,0,0~
,0,0,0,0,0,0,0,0,0)';$S;OUT;
    'P4_RXP0':'(0,0,0,0,0,0,0,0,0,0,0,0,0,0,0,0,0,0,DG54,0,0,0,0,0,0,0,0,0,0,0,0~
,0,0,0,0,0,0,0,0,0)';$S;IN;
    'P4_TXN1':'(0,0,0,0,0,0,0,0,0,0,0,0,0,0,0,0,0,0,DE49,0,0,0,0,0,0,0,0,0,0,0,0~
,0,0,0,0,0,0,0,0,0)';$S;OUT;
    'P4_RXP1':'(0,0,0,0,0,0,0,0,0,0,0,0,0,0,0,0,0,0,DG51,0,0,0,0,0,0,0,0,0,0,0,0~
,0,0,0,0,0,0,0,0,0)';$S;IN;
    'P4_RXN0':'(0,0,0,0,0,0,0,0,0,0,0,0,0,0,0,0,0,0,DG53,0,0,0,0,0,0,0,0,0,0,0,0~
,0,0,0,0,0,0,0,0,0)';$S;IN;
    'P4_RXN1':'(0,0,0,0,0,0,0,0,0,0,0,0,0,0,0,0,0,0,DG50,0,0,0,0,0,0,0,0,0,0,0,0~
,0,0,0,0,0,0,0,0,0)';$S;IN;
    'WAFL_RXN0||P5_RXN0':'(0,0,0,0,0,0,0,0,0,0,0,0,0,0,0,0,0,0,E50,0,0,0,0,0,0,0~
,0,0,0,0,0,0,0,0,0,0,0,0,0,0)';$S;IN;
    'WAFL_RXP0||P5_RXP0':'(0,0,0,0,0,0,0,0,0,0,0,0,0,0,0,0,0,0,E49,0,0,0,0,0,0,0~
,0,0,0,0,0,0,0,0,0,0,0,0,0,0)';$S;IN;
    'WAFL_RXN1||P5_RXN1':'(0,0,0,0,0,0,0,0,0,0,0,0,0,0,0,0,0,0,E47,0,0,0,0,0,0,0~
,0,0,0,0,0,0,0,0,0,0,0,0,0,0)';$S;IN;
    'WAFL_RXP1||P5_RXP1':'(0,0,0,0,0,0,0,0,0,0,0,0,0,0,0,0,0,0,E46,0,0,0,0,0,0,0~
,0,0,0,0,0,0,0,0,0,0,0,0,0,0)';$S;IN;
    'WAFL_TXN0||P5_TXN0':'(0,0,0,0,0,0,0,0,0,0,0,0,0,0,0,0,0,0,C51,0,0,0,0,0,0,0~
,0,0,0,0,0,0,0,0,0,0,0,0,0,0)';$S;OUT;
    'WAFL_TXP0||P5_TXP0':'(0,0,0,0,0,0,0,0,0,0,0,0,0,0,0,0,0,0,C50,0,0,0,0,0,0,0~
,0,0,0,0,0,0,0,0,0,0,0,0,0,0)';$S;OUT;
    'WAFL_TXN1||P5_TXN1':'(0,0,0,0,0,0,0,0,0,0,0,0,0,0,0,0,0,0,C48,0,0,0,0,0,0,0~
,0,0,0,0,0,0,0,0,0,0,0,0,0,0)';$S;OUT;
    'WAFL_TXP1||P5_TXP1':'(0,0,0,0,0,0,0,0,0,0,0,0,0,0,0,0,0,0,C47,0,0,0,0,0,0,0~
,0,0,0,0,0,0,0,0,0,0,0,0,0,0)';$S;OUT;
    'ALERT_L':'(0,0,0,0,0,0,0,0,0,0,0,0,0,0,0,0,0,0,0,A68,0,0,0,0,0,0,0,0,0,0,0,~
0,0,0,0,0,0,0,0,0)';$S;OUT;
    'CPU_PRESENT_L':'(0,0,0,0,0,0,0,0,0,0,0,0,0,0,0,0,0,0,0,B66,0,0,0,0,0,0,0,0,~
0,0,0,0,0,0,0,0,0,0,0,0)';$S;OUT;
    'DBREQ_L':'(0,0,0,0,0,0,0,0,0,0,0,0,0,0,0,0,0,0,0,C16,0,0,0,0,0,0,0,0,0,0,0,~
0,0,0,0,0,0,0,0,0)';$S;IN;
    'PROCHOT_L':'(0,0,0,0,0,0,0,0,0,0,0,0,0,0,0,0,0,0,0,A69,0,0,0,0,0,0,0,0,0,0,~
0,0,0,0,0,0,0,0,0,0)';$S;IN;
    'SA0':'(0,0,0,0,0,0,0,0,0,0,0,0,0,0,0,0,0,0,0,DJ55,0,0,0,0,0,0,0,0,0,0,0,0,0~
,0,0,0,0,0,0,0)';$S;IN;
    'SIC':'(0,0,0,0,0,0,0,0,0,0,0,0,0,0,0,0,0,0,0,DJ71,0,0,0,0,0,0,0,0,0,0,0,0,0~
,0,0,0,0,0,0,0)';$S;OUT;
    'SID':'(0,0,0,0,0,0,0,0,0,0,0,0,0,0,0,0,0,0,0,DH71,0,0,0,0,0,0,0,0,0,0,0,0,0~
,0,0,0,0,0,0,0)';$S;BIDI;
    'TDI':'(0,0,0,0,0,0,0,0,0,0,0,0,0,0,0,0,0,0,0,C17,0,0,0,0,0,0,0,0,0,0,0,0,0,~
0,0,0,0,0,0,0)';$S;IN;
    'TDO':'(0,0,0,0,0,0,0,0,0,0,0,0,0,0,0,0,0,0,0,C18,0,0,0,0,0,0,0,0,0,0,0,0,0,~
0,0,0,0,0,0,0)';$S;OUT;
    'THERMTRIP_L':'(0,0,0,0,0,0,0,0,0,0,0,0,0,0,0,0,0,0,0,DJ9,0,0,0,0,0,0,0,0,0,~
0,0,0,0,0,0,0,0,0,0,0)';$S;OUT;
    'TMS':'(0,0,0,0,0,0,0,0,0,0,0,0,0,0,0,0,0,0,0,A16,0,0,0,0,0,0,0,0,0,0,0,0,0,~
0,0,0,0,0,0,0)';$S;IN;
    'TRST_L':'(0,0,0,0,0,0,0,0,0,0,0,0,0,0,0,0,0,0,0,A17,0,0,0,0,0,0,0,0,0,0,0,0~
,0,0,0,0,0,0,0,0)';$S;IN;
    'XTRIG_L4':'(0,0,0,0,0,0,0,0,0,0,0,0,0,0,0,0,0,0,0,C66,0,0,0,0,0,0,0,0,0,0,0~
,0,0,0,0,0,0,0,0,0)';$S;OUT;
    'XTRIG_L5':'(0,0,0,0,0,0,0,0,0,0,0,0,0,0,0,0,0,0,0,C65,0,0,0,0,0,0,0,0,0,0,0~
,0,0,0,0,0,0,0,0,0)';$S;OUT;
    'XTRIG_L6':'(0,0,0,0,0,0,0,0,0,0,0,0,0,0,0,0,0,0,0,A66,0,0,0,0,0,0,0,0,0,0,0~
,0,0,0,0,0,0,0,0,0)';$S;OUT;
    'XTRIG_L7':'(0,0,0,0,0,0,0,0,0,0,0,0,0,0,0,0,0,0,0,A65,0,0,0,0,0,0,0,0,0,0,0~
,0,0,0,0,0,0,0,0,0)';$S;OUT;
    'SA1':'(0,0,0,0,0,0,0,0,0,0,0,0,0,0,0,0,0,0,0,DJ56,0,0,0,0,0,0,0,0,0,0,0,0,0~
,0,0,0,0,0,0,0)';$S;IN;
    'CORETYPE0':'(0,0,0,0,0,0,0,0,0,0,0,0,0,0,0,0,0,0,0,C70,0,0,0,0,0,0,0,0,0,0,~
0,0,0,0,0,0,0,0,0,0)';$S;OUT;
    'CORETYPE1':'(0,0,0,0,0,0,0,0,0,0,0,0,0,0,0,0,0,0,0,B69,0,0,0,0,0,0,0,0,0,0,~
0,0,0,0,0,0,0,0,0,0)';$S;OUT;
    'SP5R2':'(0,0,0,0,0,0,0,0,0,0,0,0,0,0,0,0,0,0,0,C68,0,0,0,0,0,0,0,0,0,0,0,0,~
0,0,0,0,0,0,0,0)';$S;OUT;
    'SP5R3':'(0,0,0,0,0,0,0,0,0,0,0,0,0,0,0,0,0,0,0,DH73,0,0,0,0,0,0,0,0,0,0,0,0~
,0,0,0,0,0,0,0,0)';$S;OUT;
    'SP5R4':'(0,0,0,0,0,0,0,0,0,0,0,0,0,0,0,0,0,0,0,DH10,0,0,0,0,0,0,0,0,0,0,0,0~
,0,0,0,0,0,0,0,0)';$S;OUT;
    'PCC0_L':'(0,0,0,0,0,0,0,0,0,0,0,0,0,0,0,0,0,0,0,C22,0,0,0,0,0,0,0,0,0,0,0,0~
,0,0,0,0,0,0,0,0)';$S;IN;
    'PCC1_L':'(0,0,0,0,0,0,0,0,0,0,0,0,0,0,0,0,0,0,0,DG72,0,0,0,0,0,0,0,0,0,0,0,~
0,0,0,0,0,0,0,0,0)';$S;IN;
    'AZ_BITCLK':'(0,0,0,0,0,0,0,0,0,0,0,0,0,0,0,0,0,0,0,C32,0,0,0,0,0,0,0,0,0,0,~
0,0,0,0,0,0,0,0,0,0)';$S;OUT;
    'AZ_SYNC':'(0,0,0,0,0,0,0,0,0,0,0,0,0,0,0,0,0,0,0,D32,0,0,0,0,0,0,0,0,0,0,0,~
0,0,0,0,0,0,0,0,0)';$S;OUT;
    'SVD0':'(0,0,0,0,0,0,0,0,0,0,0,0,0,0,0,0,0,0,0,A22,0,0,0,0,0,0,0,0,0,0,0,0,0~
,0,0,0,0,0,0,0)';$S;BIDI;
    'SVT0':'(0,0,0,0,0,0,0,0,0,0,0,0,0,0,0,0,0,0,0,B21,0,0,0,0,0,0,0,0,0,0,0,0,0~
,0,0,0,0,0,0,0)';$S;IN;
    'SVD1':'(0,0,0,0,0,0,0,0,0,0,0,0,0,0,0,0,0,0,0,DH72,0,0,0,0,0,0,0,0,0,0,0,0,~
0,0,0,0,0,0,0,0)';$S;BIDI;
    'SVC0':'(0,0,0,0,0,0,0,0,0,0,0,0,0,0,0,0,0,0,0,A23,0,0,0,0,0,0,0,0,0,0,0,0,0~
,0,0,0,0,0,0,0)';$S;OUT;
    'SVT1':'(0,0,0,0,0,0,0,0,0,0,0,0,0,0,0,0,0,0,0,DG73,0,0,0,0,0,0,0,0,0,0,0,0,~
0,0,0,0,0,0,0,0)';$S;IN;
    'SVC1':'(0,0,0,0,0,0,0,0,0,0,0,0,0,0,0,0,0,0,0,DJ72,0,0,0,0,0,0,0,0,0,0,0,0,~
0,0,0,0,0,0,0,0)';$S;OUT;
    'UART0_RXD||AGPIO136':'(0,0,0,0,0,0,0,0,0,0,0,0,0,0,0,0,0,0,0,DG35,0,0,0,0,0~
,0,0,0,0,0,0,0,0,0,0,0,0,0,0,0)';$S;BIDI;
    'UART0_RTS_L||UART2_RXD||AGPIO137':'(0,0,0,0,0,0,0,0,0,0,0,0,0,0,0,0,0,0,0,D~
F34,0,0,0,0,0,0,0,0,0,0,0,0,0,0,0,0,0,0,0,0)';$S;BIDI;
    'UART0_INTR||AGPIO139':'(0,0,0,0,0,0,0,0,0,0,0,0,0,0,0,0,0,0,0,DG34,0,0,0,0,~
0,0,0,0,0,0,0,0,0,0,0,0,0,0,0,0)';$S;BIDI;
    'UART0_TXD||AGPIO138':'(0,0,0,0,0,0,0,0,0,0,0,0,0,0,0,0,0,0,0,DJ34,0,0,0,0,0~
,0,0,0,0,0,0,0,0,0,0,0,0,0,0,0)';$S;BIDI;
    'UART0_CTS_L||UART2_TXD||AGPIO135':'(0,0,0,0,0,0,0,0,0,0,0,0,0,0,0,0,0,0,0,D~
J33,0,0,0,0,0,0,0,0,0,0,0,0,0,0,0,0,0,0,0,0)';$S;BIDI;
    'AZ_SDIN2||SW_MDATA0':'(0,0,0,0,0,0,0,0,0,0,0,0,0,0,0,0,0,0,0,A33,0,0,0,0,0,~
0,0,0,0,0,0,0,0,0,0,0,0,0,0,0)';$S;OUT;
    'AZ_SDOUT||SW_MDATA2':'(0,0,0,0,0,0,0,0,0,0,0,0,0,0,0,0,0,0,0,A32,0,0,0,0,0,~
0,0,0,0,0,0,0,0,0,0,0,0,0,0,0)';$S;OUT;
    'AZ_RST_L||SW_MDATA1':'(0,0,0,0,0,0,0,0,0,0,0,0,0,0,0,0,0,0,0,A34,0,0,0,0,0,~
0,0,0,0,0,0,0,0,0,0,0,0,0,0,0)';$S;OUT;
    'AZ_SDIN0||SW_MDATA3':'(0,0,0,0,0,0,0,0,0,0,0,0,0,0,0,0,0,0,0,C33,0,0,0,0,0,~
0,0,0,0,0,0,0,0,0,0,0,0,0,0,0)';$S;OUT;
    'AZ_SDIN1||SW_MCLK':'(0,0,0,0,0,0,0,0,0,0,0,0,0,0,0,0,0,0,0,D33,0,0,0,0,0,0,~
0,0,0,0,0,0,0,0,0,0,0,0,0,0)';$S;OUT;
    'SP5R1':'(0,0,0,0,0,0,0,0,0,0,0,0,0,0,0,0,0,0,0,C19,0,0,0,0,0,0,0,0,0,0,0,0,~
0,0,0,0,0,0,0,0)';$S;OUT;
    'TCK':'(0,0,0,0,0,0,0,0,0,0,0,0,0,0,0,0,0,0,0,B17,0,0,0,0,0,0,0,0,0,0,0,0,0,~
0,0,0,0,0,0,0)';$S;IN;
    'RTC_LDO_SELECT':'(0,0,0,0,0,0,0,0,0,0,0,0,0,0,0,0,0,0,0,DH8,0,0,0,0,0,0,0,0~
,0,0,0,0,0,0,0,0,0,0,0,0)';$S;IN;
    'UART1_RXD||AGPIO141':'(0,0,0,0,0,0,0,0,0,0,0,0,0,0,0,0,0,0,0,DH33,0,0,0,0,0~
,0,0,0,0,0,0,0,0,0,0,0,0,0,0,0)';$S;BIDI;
    'UART1_TXD||AGPIO142':'(0,0,0,0,0,0,0,0,0,0,0,0,0,0,0,0,0,0,0,DJ32,0,0,0,0,0~
,0,0,0,0,0,0,0,0,0,0,0,0,0,0,0)';$S;BIDI;
    'VSS_SENSE_A':'(0,0,0,0,0,0,0,0,0,0,0,0,0,0,0,0,0,0,0,C3,0,0,0,0,0,0,0,0,0,0~
,0,0,0,0,0,0,0,0,0,0)';$S;
    'VSS_SENSE_B':'(0,0,0,0,0,0,0,0,0,0,0,0,0,0,0,0,0,0,0,BR54,0,0,0,0,0,0,0,0,0~
,0,0,0,0,0,0,0,0,0,0,0)';$S;
    'VSS_SENSE_C':'(0,0,0,0,0,0,0,0,0,0,0,0,0,0,0,0,0,0,0,DJ3,0,0,0,0,0,0,0,0,0,~
0,0,0,0,0,0,0,0,0,0,0)';$S;
    'VSS_SENSE_D':'(0,0,0,0,0,0,0,0,0,0,0,0,0,0,0,0,0,0,0,B73,0,0,0,0,0,0,0,0,0,~
0,0,0,0,0,0,0,0,0,0,0)';$S;
    'VDDIO_SENSE':'(0,0,0,0,0,0,0,0,0,0,0,0,0,0,0,0,0,0,0,BR53,0,0,0,0,0,0,0,0,0~
,0,0,0,0,0,0,0,0,0,0,0)';$S;
    'VDD_11_S3_SENSE':'(0,0,0,0,0,0,0,0,0,0,0,0,0,0,0,0,0,0,0,DH3,0,0,0,0,0,0,0,~
0,0,0,0,0,0,0,0,0,0,0,0,0)';$S;
    'VDD_18_S5_SENSE':'(0,0,0,0,0,0,0,0,0,0,0,0,0,0,0,0,0,0,0,C74,0,0,0,0,0,0,0,~
0,0,0,0,0,0,0,0,0,0,0,0,0)';$S;
    'VDD_33_S5_SENSE':'(0,0,0,0,0,0,0,0,0,0,0,0,0,0,0,0,0,0,0,BP53,0,0,0,0,0,0,0~
,0,0,0,0,0,0,0,0,0,0,0,0,0)';$S;
    'VDDCR_SOC_SENSE':'(0,0,0,0,0,0,0,0,0,0,0,0,0,0,0,0,0,0,0,B3,0,0,0,0,0,0,0,0~
,0,0,0,0,0,0,0,0,0,0,0,0)';$S;
    'VDDCR_CPU1_SENSE':'(0,0,0,0,0,0,0,0,0,0,0,0,0,0,0,0,0,0,0,DG3,0,0,0,0,0,0,0~
,0,0,0,0,0,0,0,0,0,0,0,0,0)';$S;
    'VDDCR_CPU0_SENSE':'(0,0,0,0,0,0,0,0,0,0,0,0,0,0,0,0,0,0,0,C2,0,0,0,0,0,0,0,~
0,0,0,0,0,0,0,0,0,0,0,0,0)';$S;
    'TEST6_X3D4':'(0,0,0,0,0,0,0,0,0,0,0,0,0,0,0,0,0,0,0,AA23,0,0,0,0,0,0,0,0,0,~
0,0,0,0,0,0,0,0,0,0,0)';$S;OUT;
    'TEST6_CCD1':'(0,0,0,0,0,0,0,0,0,0,0,0,0,0,0,0,0,0,0,CJ30,0,0,0,0,0,0,0,0,0,~
0,0,0,0,0,0,0,0,0,0,0)';$S;OUT;
    'TEST5_CCD0':'(0,0,0,0,0,0,0,0,0,0,0,0,0,0,0,0,0,0,0,AA51,0,0,0,0,0,0,0,0,0,~
0,0,0,0,0,0,0,0,0,0,0)';$S;OUT;
    'TEST6_X3D5':'(0,0,0,0,0,0,0,0,0,0,0,0,0,0,0,0,0,0,0,CJ53,0,0,0,0,0,0,0,0,0,~
0,0,0,0,0,0,0,0,0,0,0)';$S;OUT;
    'TEST6_CCD2':'(0,0,0,0,0,0,0,0,0,0,0,0,0,0,0,0,0,0,0,CJ46,0,0,0,0,0,0,0,0,0,~
0,0,0,0,0,0,0,0,0,0,0)';$S;OUT;
    'TEST5_CCD1':'(0,0,0,0,0,0,0,0,0,0,0,0,0,0,0,0,0,0,0,CJ27,0,0,0,0,0,0,0,0,0,~
0,0,0,0,0,0,0,0,0,0,0)';$S;OUT;
    'TEST4_CCD0':'(0,0,0,0,0,0,0,0,0,0,0,0,0,0,0,0,0,0,0,AA50,0,0,0,0,0,0,0,0,0,~
0,0,0,0,0,0,0,0,0,0,0)';$S;OUT;
    'TEST6_CCD3':'(0,0,0,0,0,0,0,0,0,0,0,0,0,0,0,0,0,0,0,Y46,0,0,0,0,0,0,0,0,0,0~
,0,0,0,0,0,0,0,0,0,0)';$S;OUT;
    'TEST5_CCD2':'(0,0,0,0,0,0,0,0,0,0,0,0,0,0,0,0,0,0,0,CJ49,0,0,0,0,0,0,0,0,0,~
0,0,0,0,0,0,0,0,0,0,0)';$S;OUT;
    'TEST4_CCD1':'(0,0,0,0,0,0,0,0,0,0,0,0,0,0,0,0,0,0,0,CJ28,0,0,0,0,0,0,0,0,0,~
0,0,0,0,0,0,0,0,0,0,0)';$S;OUT;
    'TEST5_CCD3':'(0,0,0,0,0,0,0,0,0,0,0,0,0,0,0,0,0,0,0,Y30,0,0,0,0,0,0,0,0,0,0~
,0,0,0,0,0,0,0,0,0,0)';$S;OUT;
    'TEST4_IOD':'(0,0,0,0,0,0,0,0,0,0,0,0,0,0,0,0,0,0,0,AA25,0,0,0,0,0,0,0,0,0,0~
,0,0,0,0,0,0,0,0,0,0)';$S;OUT;
    'TEST4_CCD2':'(0,0,0,0,0,0,0,0,0,0,0,0,0,0,0,0,0,0,0,CJ48,0,0,0,0,0,0,0,0,0,~
0,0,0,0,0,0,0,0,0,0,0)';$S;OUT;
    'TEST5_IOD':'(0,0,0,0,0,0,0,0,0,0,0,0,0,0,0,0,0,0,0,AA24,0,0,0,0,0,0,0,0,0,0~
,0,0,0,0,0,0,0,0,0,0)';$S;OUT;
    'TEST5_CCD4':'(0,0,0,0,0,0,0,0,0,0,0,0,0,0,0,0,0,0,0,AA53,0,0,0,0,0,0,0,0,0,~
0,0,0,0,0,0,0,0,0,0,0)';$S;OUT;
    'TEST4_CCD3':'(0,0,0,0,0,0,0,0,0,0,0,0,0,0,0,0,0,0,0,AA30,0,0,0,0,0,0,0,0,0,~
0,0,0,0,0,0,0,0,0,0,0)';$S;OUT;
    'TEST6_IOD':'(0,0,0,0,0,0,0,0,0,0,0,0,0,0,0,0,0,0,0,AA49,0,0,0,0,0,0,0,0,0,0~
,0,0,0,0,0,0,0,0,0,0)';$S;OUT;
    'TEST5_CCD5':'(0,0,0,0,0,0,0,0,0,0,0,0,0,0,0,0,0,0,0,CJ25,0,0,0,0,0,0,0,0,0,~
0,0,0,0,0,0,0,0,0,0,0)';$S;OUT;
    'TEST4_CCD4':'(0,0,0,0,0,0,0,0,0,0,0,0,0,0,0,0,0,0,0,AA52,0,0,0,0,0,0,0,0,0,~
0,0,0,0,0,0,0,0,0,0,0)';$S;OUT;
    'TEST5_CCD6':'(0,0,0,0,0,0,0,0,0,0,0,0,0,0,0,0,0,0,0,CJ51,0,0,0,0,0,0,0,0,0,~
0,0,0,0,0,0,0,0,0,0,0)';$S;OUT;
    'TEST4_CCD5':'(0,0,0,0,0,0,0,0,0,0,0,0,0,0,0,0,0,0,0,CJ26,0,0,0,0,0,0,0,0,0,~
0,0,0,0,0,0,0,0,0,0,0)';$S;OUT;
    'TEST5_CCD7':'(0,0,0,0,0,0,0,0,0,0,0,0,0,0,0,0,0,0,0,AA26,0,0,0,0,0,0,0,0,0,~
0,0,0,0,0,0,0,0,0,0,0)';$S;OUT;
    'TEST4_CCD6':'(0,0,0,0,0,0,0,0,0,0,0,0,0,0,0,0,0,0,0,CJ50,0,0,0,0,0,0,0,0,0,~
0,0,0,0,0,0,0,0,0,0,0)';$S;OUT;
    'TEST47_CCD0':'(0,0,0,0,0,0,0,0,0,0,0,0,0,0,0,0,0,0,0,B60,0,0,0,0,0,0,0,0,0,~
0,0,0,0,0,0,0,0,0,0,0)';$S;OUT;
    'TEST5_CCD8':'(0,0,0,0,0,0,0,0,0,0,0,0,0,0,0,0,0,0,0,Y47,0,0,0,0,0,0,0,0,0,0~
,0,0,0,0,0,0,0,0,0,0)';$S;OUT;
    'TEST50_IOD':'(0,0,0,0,0,0,0,0,0,0,0,0,0,0,0,0,0,0,0,B61,0,0,0,0,0,0,0,0,0,0~
,0,0,0,0,0,0,0,0,0,0)';$S;OUT;
    'TEST4_CCD7':'(0,0,0,0,0,0,0,0,0,0,0,0,0,0,0,0,0,0,0,AA27,0,0,0,0,0,0,0,0,0,~
0,0,0,0,0,0,0,0,0,0,0)';$S;OUT;
    'TEST47_CCD1':'(0,0,0,0,0,0,0,0,0,0,0,0,0,0,0,0,0,0,0,CJ24,0,0,0,0,0,0,0,0,0~
,0,0,0,0,0,0,0,0,0,0,0)';$S;OUT;
    'TEST5_CCD9':'(0,0,0,0,0,0,0,0,0,0,0,0,0,0,0,0,0,0,0,CK29,0,0,0,0,0,0,0,0,0,~
0,0,0,0,0,0,0,0,0,0,0)';$S;OUT;
    'TEST4_CCD8':'(0,0,0,0,0,0,0,0,0,0,0,0,0,0,0,0,0,0,0,AA48,0,0,0,0,0,0,0,0,0,~
0,0,0,0,0,0,0,0,0,0,0)';$S;OUT;
    'TEST47_CCD2':'(0,0,0,0,0,0,0,0,0,0,0,0,0,0,0,0,0,0,0,CK46,0,0,0,0,0,0,0,0,0~
,0,0,0,0,0,0,0,0,0,0,0)';$S;OUT;
    'TEST4_CCD10':'(0,0,0,0,0,0,0,0,0,0,0,0,0,0,0,0,0,0,0,CJ47,0,0,0,0,0,0,0,0,0~
,0,0,0,0,0,0,0,0,0,0,0)';$S;OUT;
    'TEST4_CCD9':'(0,0,0,0,0,0,0,0,0,0,0,0,0,0,0,0,0,0,0,CK30,0,0,0,0,0,0,0,0,0,~
0,0,0,0,0,0,0,0,0,0,0)';$S;OUT;
    'TEST5_CCD10':'(0,0,0,0,0,0,0,0,0,0,0,0,0,0,0,0,0,0,0,CK47,0,0,0,0,0,0,0,0,0~
,0,0,0,0,0,0,0,0,0,0,0)';$S;OUT;
    'TEST4_CCD11':'(0,0,0,0,0,0,0,0,0,0,0,0,0,0,0,0,0,0,0,AA28,0,0,0,0,0,0,0,0,0~
,0,0,0,0,0,0,0,0,0,0,0)';$S;OUT;
    'TEST5_CCD11':'(0,0,0,0,0,0,0,0,0,0,0,0,0,0,0,0,0,0,0,Y29,0,0,0,0,0,0,0,0,0,~
0,0,0,0,0,0,0,0,0,0,0)';$S;OUT;
    'TEST6_X3D0':'(0,0,0,0,0,0,0,0,0,0,0,0,0,0,0,0,0,0,0,AA47,0,0,0,0,0,0,0,0,0,~
0,0,0,0,0,0,0,0,0,0,0)';$S;OUT;
    'TEST47_IOD0':'(0,0,0,0,0,0,0,0,0,0,0,0,0,0,0,0,0,0,0,B58,0,0,0,0,0,0,0,0,0,~
0,0,0,0,0,0,0,0,0,0,0)';$S;OUT;
    'TEST6_X3D1':'(0,0,0,0,0,0,0,0,0,0,0,0,0,0,0,0,0,0,0,CJ29,0,0,0,0,0,0,0,0,0,~
0,0,0,0,0,0,0,0,0,0,0)';$S;OUT;
    'TEST47_IOD1':'(0,0,0,0,0,0,0,0,0,0,0,0,0,0,0,0,0,0,0,D7,0,0,0,0,0,0,0,0,0,0~
,0,0,0,0,0,0,0,0,0,0)';$S;OUT;
    'TEST6_X3D2':'(0,0,0,0,0,0,0,0,0,0,0,0,0,0,0,0,0,0,0,AA29,0,0,0,0,0,0,0,0,0,~
0,0,0,0,0,0,0,0,0,0,0)';$S;OUT;
    'TEST6_X3D3':'(0,0,0,0,0,0,0,0,0,0,0,0,0,0,0,0,0,0,0,CJ52,0,0,0,0,0,0,0,0,0,~
0,0,0,0,0,0,0,0,0,0,0)';$S;OUT;
    'TEST6_CCD0':'(0,0,0,0,0,0,0,0,0,0,0,0,0,0,0,0,0,0,0,AA46,0,0,0,0,0,0,0,0,0,~
0,0,0,0,0,0,0,0,0,0,0)';$S;OUT;
    'TEST47_CCD3':'(0,0,0,0,0,0,0,0,0,0,0,0,0,0,0,0,0,0,0,E32,0,0,0,0,0,0,0,0,0,~
0,0,0,0,0,0,0,0,0,0,0)';$S;OUT;
    'TEST41_IOD':'(0,0,0,0,0,0,0,0,0,0,0,0,0,0,0,0,0,0,0,W31,0,0,0,0,0,0,0,0,0,0~
,0,0,0,0,0,0,0,0,0,0)';$S;OUT;
    'BP0':'(0,0,0,0,0,0,0,0,0,0,0,0,0,0,0,0,0,0,0,C63,0,0,0,0,0,0,0,0,0,0,0,0,0,~
0,0,0,0,0,0,0)';$S;OUT;
    'BP1':'(0,0,0,0,0,0,0,0,0,0,0,0,0,0,0,0,0,0,0,C62,0,0,0,0,0,0,0,0,0,0,0,0,0,~
0,0,0,0,0,0,0)';$S;OUT;
    'BP2':'(0,0,0,0,0,0,0,0,0,0,0,0,0,0,0,0,0,0,0,A63,0,0,0,0,0,0,0,0,0,0,0,0,0,~
0,0,0,0,0,0,0)';$S;OUT;
    'BP3':'(0,0,0,0,0,0,0,0,0,0,0,0,0,0,0,0,0,0,0,A62,0,0,0,0,0,0,0,0,0,0,0,0,0,~
0,0,0,0,0,0,0)';$S;OUT;
    'CORETYPE2':'(0,0,0,0,0,0,0,0,0,0,0,0,0,0,0,0,0,0,0,D68,0,0,0,0,0,0,0,0,0,0,~
0,0,0,0,0,0,0,0,0,0)';$S;OUT;
    'PWR_GOOD':'(0,0,0,0,0,0,0,0,0,0,0,0,0,0,0,0,0,0,0,0,DJ8,0,0,0,0,0,0,0,0,0,0~
,0,0,0,0,0,0,0,0,0)';$S;IN;
    'RSMRST_L':'(0,0,0,0,0,0,0,0,0,0,0,0,0,0,0,0,0,0,0,0,DG10,0,0,0,0,0,0,0,0,0,~
0,0,0,0,0,0,0,0,0,0)';$S;IN;
    'SLP_S3_L':'(0,0,0,0,0,0,0,0,0,0,0,0,0,0,0,0,0,0,0,0,DJ5,0,0,0,0,0,0,0,0,0,0~
,0,0,0,0,0,0,0,0,0)';$S;OUT;
    'SLP_S5_L':'(0,0,0,0,0,0,0,0,0,0,0,0,0,0,0,0,0,0,0,0,DG4,0,0,0,0,0,0,0,0,0,0~
,0,0,0,0,0,0,0,0,0)';$S;OUT;
    'SYS_RESET_L||AGPIO1':'(0,0,0,0,0,0,0,0,0,0,0,0,0,0,0,0,0,0,0,0,DH6,0,0,0,0,~
0,0,0,0,0,0,0,0,0,0,0,0,0,0,0)';$S;BIDI;
    'WAKE_L||AGPIO2':'(0,0,0,0,0,0,0,0,0,0,0,0,0,0,0,0,0,0,0,0,DJ10,0,0,0,0,0,0,~
0,0,0,0,0,0,0,0,0,0,0,0,0)';$S;BIDI;
    'X32K_X1':'(0,0,0,0,0,0,0,0,0,0,0,0,0,0,0,0,0,0,0,0,DJ14,0,0,0,0,0,0,0,0,0,0~
,0,0,0,0,0,0,0,0,0)';$S;IN;
    'X32K_X2':'(0,0,0,0,0,0,0,0,0,0,0,0,0,0,0,0,0,0,0,0,DJ13,0,0,0,0,0,0,0,0,0,0~
,0,0,0,0,0,0,0,0,0)';$S;IN;
    'X48M_X1':'(0,0,0,0,0,0,0,0,0,0,0,0,0,0,0,0,0,0,0,0,DJ17,0,0,0,0,0,0,0,0,0,0~
,0,0,0,0,0,0,0,0,0)';$S;IN;
    'X48M_X2':'(0,0,0,0,0,0,0,0,0,0,0,0,0,0,0,0,0,0,0,0,DJ16,0,0,0,0,0,0,0,0,0,0~
,0,0,0,0,0,0,0,0,0)';$S;IN;
    'PWR_BTN_L||AGPIO0':'(0,0,0,0,0,0,0,0,0,0,0,0,0,0,0,0,0,0,0,0,DH7,0,0,0,0,0,~
0,0,0,0,0,0,0,0,0,0,0,0,0,0)';$S;BIDI;
    'NV_SAVE_L':'(0,0,0,0,0,0,0,0,0,0,0,0,0,0,0,0,0,0,0,0,B64,0,0,0,0,0,0,0,0,0,~
0,0,0,0,0,0,0,0,0,0)';$S;OUT;
    'FORCE_SELFREFRESH':'(0,0,0,0,0,0,0,0,0,0,0,0,0,0,0,0,0,0,0,0,B63,0,0,0,0,0,~
0,0,0,0,0,0,0,0,0,0,0,0,0,0)';$S;IN;
    'RTCCLK':'(0,0,0,0,0,0,0,0,0,0,0,0,0,0,0,0,0,0,0,0,DH9,0,0,0,0,0,0,0,0,0,0,0~
,0,0,0,0,0,0,0,0)';$S;BIDI;
    'GPP_CLK05N':'(0,0,0,0,0,0,0,0,0,0,0,0,0,0,0,0,0,0,0,0,C9,0,0,0,0,0,0,0,0,0,~
0,0,0,0,0,0,0,0,0,0)';$S;OUT;
    'GPP_CLK15N':'(0,0,0,0,0,0,0,0,0,0,0,0,0,0,0,0,0,0,0,0,DJ50,0,0,0,0,0,0,0,0,~
0,0,0,0,0,0,0,0,0,0,0)';$S;OUT;
    'GPP_CLK04N':'(0,0,0,0,0,0,0,0,0,0,0,0,0,0,0,0,0,0,0,0,C12,0,0,0,0,0,0,0,0,0~
,0,0,0,0,0,0,0,0,0,0)';$S;OUT;
    'GPP_CLK14N':'(0,0,0,0,0,0,0,0,0,0,0,0,0,0,0,0,0,0,0,0,DJ47,0,0,0,0,0,0,0,0,~
0,0,0,0,0,0,0,0,0,0,0)';$S;OUT;
    'GPP_CLK05P':'(0,0,0,0,0,0,0,0,0,0,0,0,0,0,0,0,0,0,0,0,B9,0,0,0,0,0,0,0,0,0,~
0,0,0,0,0,0,0,0,0,0)';$S;OUT;
    'GPP_CLK03N':'(0,0,0,0,0,0,0,0,0,0,0,0,0,0,0,0,0,0,0,0,A11,0,0,0,0,0,0,0,0,0~
,0,0,0,0,0,0,0,0,0,0)';$S;OUT;
    'GPP_CLK15P':'(0,0,0,0,0,0,0,0,0,0,0,0,0,0,0,0,0,0,0,0,DJ51,0,0,0,0,0,0,0,0,~
0,0,0,0,0,0,0,0,0,0,0)';$S;OUT;
    'GPP_CLK13N':'(0,0,0,0,0,0,0,0,0,0,0,0,0,0,0,0,0,0,0,0,DJ54,0,0,0,0,0,0,0,0,~
0,0,0,0,0,0,0,0,0,0,0)';$S;OUT;
    'GPP_CLK04P':'(0,0,0,0,0,0,0,0,0,0,0,0,0,0,0,0,0,0,0,0,B12,0,0,0,0,0,0,0,0,0~
,0,0,0,0,0,0,0,0,0,0)';$S;OUT;
    'GPP_CLK02N':'(0,0,0,0,0,0,0,0,0,0,0,0,0,0,0,0,0,0,0,0,C6,0,0,0,0,0,0,0,0,0,~
0,0,0,0,0,0,0,0,0,0)';$S;OUT;
    'GPP_CLK14P':'(0,0,0,0,0,0,0,0,0,0,0,0,0,0,0,0,0,0,0,0,DJ48,0,0,0,0,0,0,0,0,~
0,0,0,0,0,0,0,0,0,0,0)';$S;OUT;
    'GPP_CLK12N':'(0,0,0,0,0,0,0,0,0,0,0,0,0,0,0,0,0,0,0,0,DJ44,0,0,0,0,0,0,0,0,~
0,0,0,0,0,0,0,0,0,0,0)';$S;OUT;
    'GPP_CLK03P':'(0,0,0,0,0,0,0,0,0,0,0,0,0,0,0,0,0,0,0,0,A10,0,0,0,0,0,0,0,0,0~
,0,0,0,0,0,0,0,0,0,0)';$S;OUT;
    'GPP_CLK01N':'(0,0,0,0,0,0,0,0,0,0,0,0,0,0,0,0,0,0,0,0,A7,0,0,0,0,0,0,0,0,0,~
0,0,0,0,0,0,0,0,0,0)';$S;OUT;
    'GPP_CLK13P':'(0,0,0,0,0,0,0,0,0,0,0,0,0,0,0,0,0,0,0,0,DJ53,0,0,0,0,0,0,0,0,~
0,0,0,0,0,0,0,0,0,0,0)';$S;OUT;
    'GPP_CLK11N':'(0,0,0,0,0,0,0,0,0,0,0,0,0,0,0,0,0,0,0,0,DJ42,0,0,0,0,0,0,0,0,~
0,0,0,0,0,0,0,0,0,0,0)';$S;OUT;
    'GPP_CLK02P':'(0,0,0,0,0,0,0,0,0,0,0,0,0,0,0,0,0,0,0,0,B6,0,0,0,0,0,0,0,0,0,~
0,0,0,0,0,0,0,0,0,0)';$S;OUT;
    'GPP_CLK12P':'(0,0,0,0,0,0,0,0,0,0,0,0,0,0,0,0,0,0,0,0,DJ45,0,0,0,0,0,0,0,0,~
0,0,0,0,0,0,0,0,0,0,0)';$S;OUT;
    'GPP_CLK01P':'(0,0,0,0,0,0,0,0,0,0,0,0,0,0,0,0,0,0,0,0,A8,0,0,0,0,0,0,0,0,0,~
0,0,0,0,0,0,0,0,0,0)';$S;OUT;
    'GPP_CLK11P':'(0,0,0,0,0,0,0,0,0,0,0,0,0,0,0,0,0,0,0,0,DJ41,0,0,0,0,0,0,0,0,~
0,0,0,0,0,0,0,0,0,0,0)';$S;OUT;
    'AGPIO4||SATA_ACT_L':'(0,0,0,0,0,0,0,0,0,0,0,0,0,0,0,0,0,0,0,0,DF36,0,0,0,0,~
0,0,0,0,0,0,0,0,0,0,0,0,0,0,0)';$S;BIDI;
    'AGPIO3||SPD_HOST_CTRL_L':'(0,0,0,0,0,0,0,0,0,0,0,0,0,0,0,0,0,0,0,0,DE36,0,0~
,0,0,0,0,0,0,0,0,0,0,0,0,0,0,0,0,0)';$S;BIDI;
    'PCIE_RST1_L||AGPIO26':'(0,0,0,0,0,0,0,0,0,0,0,0,0,0,0,0,0,0,0,0,DG36,0,0,0,~
0,0,0,0,0,0,0,0,0,0,0,0,0,0,0,0)';$S;BIDI;
    'SGPIO_LOAD||AGPIO261':'(0,0,0,0,0,0,0,0,0,0,0,0,0,0,0,0,0,0,0,0,B15,0,0,0,0~
,0,0,0,0,0,0,0,0,0,0,0,0,0,0,0)';$S;BIDI;
    'I3C2_SDA||I2C2_SDA||SPD2_SDA||AGPIO150':'(0,0,0,0,0,0,0,0,0,0,0,0,0,0,0,0,0~
,0,0,0,B72,0,0,0,0,0,0,0,0,0,0,0,0,0,0,0,0,0,0,0)';$S;BIDI;
    'SGPIO_DATAOUT||AGPIO260':'(0,0,0,0,0,0,0,0,0,0,0,0,0,0,0,0,0,0,0,0,D15,0,0,~
0,0,0,0,0,0,0,0,0,0,0,0,0,0,0,0,0)';$S;BIDI;
    'I3C3_SDA||I2C3_SDA||SPD3_SDA||AGPIO152':'(0,0,0,0,0,0,0,0,0,0,0,0,0,0,0,0,0~
,0,0,0,B4,0,0,0,0,0,0,0,0,0,0,0,0,0,0,0,0,0,0,0)';$S;BIDI;
    'AGPIO258||SGPIO2_CLK||CLK_REQ02_L':'(0,0,0,0,0,0,0,0,0,0,0,0,0,0,0,0,0,0,0,~
0,A13,0,0,0,0,0,0,0,0,0,0,0,0,0,0,0,0,0,0,0)';$S;BIDI;
    'AGPIO256||SGPIO0_CLK':'(0,0,0,0,0,0,0,0,0,0,0,0,0,0,0,0,0,0,0,0,A14,0,0,0,0~
,0,0,0,0,0,0,0,0,0,0,0,0,0,0,0)';$S;BIDI;
    'PCIE_RST0_L||AGPIO266':'(0,0,0,0,0,0,0,0,0,0,0,0,0,0,0,0,0,0,0,0,D18,0,0,0,~
0,0,0,0,0,0,0,0,0,0,0,0,0,0,0,0)';$S;BIDI;
    'AGPIO115||CLK_REQ11_L':'(0,0,0,0,0,0,0,0,0,0,0,0,0,0,0,0,0,0,0,0,DH16,0,0,0~
,0,0,0,0,0,0,0,0,0,0,0,0,0,0,0,0)';$S;BIDI;
    'I3C0_SDA||I2C0_SDA||SPD0_SDA||SMBUS0_SDA||AGPIO146':'(0,0,0,0,0,0,0,0,0,0,0~
,0,0,0,0,0,0,0,0,0,B71,0,0,0,0,0,0,0,0,0,0,0,0,0,0,0,0,0,0,0)';$S;BIDI;
    'I3C1_SCL||I2C1_SCL||SPD1_SCL||AGPIO147':'(0,0,0,0,0,0,0,0,0,0,0,0,0,0,0,0,0~
,0,0,0,C7,0,0,0,0,0,0,0,0,0,0,0,0,0,0,0,0,0,0,0)';$S;BIDI;
    'I3C2_SCL||I2C2_SCL||SPD2_SCL||AGPIO149':'(0,0,0,0,0,0,0,0,0,0,0,0,0,0,0,0,0~
,0,0,0,C72,0,0,0,0,0,0,0,0,0,0,0,0,0,0,0,0,0,0,0)';$S;BIDI;
    'I3C0_SCL||I2C0_SCL||SPD0_SCL||SMBUS0_SCL||AGPIO145':'(0,0,0,0,0,0,0,0,0,0,0~
,0,0,0,0,0,0,0,0,0,A71,0,0,0,0,0,0,0,0,0,0,0,0,0,0,0,0,0,0,0)';$S;BIDI;
    'AGPIO259||SGPIO3_CLK':'(0,0,0,0,0,0,0,0,0,0,0,0,0,0,0,0,0,0,0,0,B16,0,0,0,0~
,0,0,0,0,0,0,0,0,0,0,0,0,0,0,0)';$S;BIDI;
    'PWRGD_OUT||AGPIO12':'(0,0,0,0,0,0,0,0,0,0,0,0,0,0,0,0,0,0,0,0,DH36,0,0,0,0,~
0,0,0,0,0,0,0,0,0,0,0,0,0,0,0)';$S;BIDI;
    'AGPIO116||CLK_REQ12_L':'(0,0,0,0,0,0,0,0,0,0,0,0,0,0,0,0,0,0,0,0,DH15,0,0,0~
,0,0,0,0,0,0,0,0,0,0,0,0,0,0,0,0)';$S;BIDI;
    'I3C1_SDA||I2C1_SDA||SPD1_SDA||AGPIO148':'(0,0,0,0,0,0,0,0,0,0,0,0,0,0,0,0,0~
,0,0,0,A5,0,0,0,0,0,0,0,0,0,0,0,0,0,0,0,0,0,0,0)';$S;BIDI;
    'I3C3_SCL||I2C3_SCL||SPD3_SCL||AGPIO151':'(0,0,0,0,0,0,0,0,0,0,0,0,0,0,0,0,0~
,0,0,0,A4,0,0,0,0,0,0,0,0,0,0,0,0,0,0,0,0,0,0,0)';$S;BIDI;
    'I2C4_SCL||HP_SCL||UBM_SCL||AGPIO13':'(0,0,0,0,0,0,0,0,0,0,0,0,0,0,0,0,0,0,0~
,0,DG12,0,0,0,0,0,0,0,0,0,0,0,0,0,0,0,0,0,0,0)';$S;BIDI;
    'I2C4_SDA||HP_SDA||UBM_SDA||AGPIO14':'(0,0,0,0,0,0,0,0,0,0,0,0,0,0,0,0,0,0,0~
,0,DH12,0,0,0,0,0,0,0,0,0,0,0,0,0,0,0,0,0,0,0)';$S;BIDI;
    'I2C5_SCL||BMC_SCL||SMBUS1_SCL||AGPIO19':'(0,0,0,0,0,0,0,0,0,0,0,0,0,0,0,0,0~
,0,0,0,DJ21,0,0,0,0,0,0,0,0,0,0,0,0,0,0,0,0,0,0,0)';$S;BIDI;
    'I2C5_SDA||BMC_SDA||SMBUS1_SDA||AGPIO20':'(0,0,0,0,0,0,0,0,0,0,0,0,0,0,0,0,0~
,0,0,0,DJ20,0,0,0,0,0,0,0,0,0,0,0,0,0,0,0,0,0,0,0)';$S;BIDI;
    'SMERR_L||AGPIO24':'(0,0,0,0,0,0,0,0,0,0,0,0,0,0,0,0,0,0,0,0,DJ11,0,0,0,0,0,~
0,0,0,0,0,0,0,0,0,0,0,0,0,0)';$S;BIDI;
    'REFCLK100SSC_P||GPP_CLK10P':'(0,0,0,0,0,0,0,0,0,0,0,0,0,0,0,0,0,0,0,0,A19,0~
,0,0,0,0,0,0,0,0,0,0,0,0,0,0,0,0,0,0)';$S;BIDI;
    'REFCLK100SSC_N||GPP_CLK10N':'(0,0,0,0,0,0,0,0,0,0,0,0,0,0,0,0,0,0,0,0,A20,0~
,0,0,0,0,0,0,0,0,0,0,0,0,0,0,0,0,0,0)';$S;BIDI;
    'RESET_L':'(0,0,0,0,0,0,0,0,0,0,0,0,0,0,0,0,0,0,0,0,B67,0,0,0,0,0,0,0,0,0,0,~
0,0,0,0,0,0,0,0,0)';$S;BIDI;
    'AGPIO104':'(0,0,0,0,0,0,0,0,0,0,0,0,0,0,0,0,0,0,0,0,DH30,0,0,0,0,0,0,0,0,0,~
0,0,0,0,0,0,0,0,0,0)';$S;BIDI;
    'AGPIO105':'(0,0,0,0,0,0,0,0,0,0,0,0,0,0,0,0,0,0,0,0,DE30,0,0,0,0,0,0,0,0,0,~
0,0,0,0,0,0,0,0,0,0)';$S;BIDI;
    'AGPIO106':'(0,0,0,0,0,0,0,0,0,0,0,0,0,0,0,0,0,0,0,0,DF31,0,0,0,0,0,0,0,0,0,~
0,0,0,0,0,0,0,0,0,0)';$S;BIDI;
    'AGPIO107':'(0,0,0,0,0,0,0,0,0,0,0,0,0,0,0,0,0,0,0,0,DG31,0,0,0,0,0,0,0,0,0,~
0,0,0,0,0,0,0,0,0,0)';$S;BIDI;
    'AGPIO109':'(0,0,0,0,0,0,0,0,0,0,0,0,0,0,0,0,0,0,0,0,DG32,0,0,0,0,0,0,0,0,0,~
0,0,0,0,0,0,0,0,0,0)';$S;BIDI;
    'AGPIO87':'(0,0,0,0,0,0,0,0,0,0,0,0,0,0,0,0,0,0,0,0,DG11,0,0,0,0,0,0,0,0,0,0~
,0,0,0,0,0,0,0,0,0)';$S;BIDI;
    'AGPIO21':'(0,0,0,0,0,0,0,0,0,0,0,0,0,0,0,0,0,0,0,0,DF33,0,0,0,0,0,0,0,0,0,0~
,0,0,0,0,0,0,0,0,0)';$S;BIDI;
    'AGPIO88':'(0,0,0,0,0,0,0,0,0,0,0,0,0,0,0,0,0,0,0,0,DJ29,0,0,0,0,0,0,0,0,0,0~
,0,0,0,0,0,0,0,0,0)';$S;BIDI;
    'AGPIO22':'(0,0,0,0,0,0,0,0,0,0,0,0,0,0,0,0,0,0,0,0,DE32,0,0,0,0,0,0,0,0,0,0~
,0,0,0,0,0,0,0,0,0)';$S;BIDI;
    'GENINT_L||PM_INTR_L||UBM_CPRSNT_CHANGE_DET_L||AGPIO89':'(0,0,0,0,0,0,0,0,0,~
0,0,0,0,0,0,0,0,0,0,0,DJ35,0,0,0,0,0,0,0,0,0,0,0,0,0,0,0,0,0,0,0)';$S;BIDI;
    'AGPIO5||DEVSLP0||SATA_ZP0_L':'(0,0,0,0,0,0,0,0,0,0,0,0,0,0,0,0,0,0,0,0,DF40~
,0,0,0,0,0,0,0,0,0,0,0,0,0,0,0,0,0,0,0)';$S;BIDI;
    'AGPIO6||DEVSLP1||SATA_ZP1_L':'(0,0,0,0,0,0,0,0,0,0,0,0,0,0,0,0,0,0,0,0,DE40~
,0,0,0,0,0,0,0,0,0,0,0,0,0,0,0,0,0,0,0)';$S;BIDI;
    'PWROK||SVI_RST_L':'(0,0,0,0,0,0,0,0,0,0,0,0,0,0,0,0,0,0,0,0,D69,0,0,0,0,0,0~
,0,0,0,0,0,0,0,0,0,0,0,0,0)';$S;OUT;
    'AGPIO257||SGPIO1_CLK||CLK_REQ01_L':'(0,0,0,0,0,0,0,0,0,0,0,0,0,0,0,0,0,0,0,~
0,C14,0,0,0,0,0,0,0,0,0,0,0,0,0,0,0,0,0,0,0)';$S;BIDI;
    'SEC_SDA||AGPIO263':'(0,0,0,0,0,0,0,0,0,0,0,0,0,0,0,0,0,0,0,0,D14,0,0,0,0,0,~
0,0,0,0,0,0,0,0,0,0,0,0,0,0)';$S;BIDI;
    'SEC_SCL||AGPIO262':'(0,0,0,0,0,0,0,0,0,0,0,0,0,0,0,0,0,0,0,0,B14,0,0,0,0,0,~
0,0,0,0,0,0,0,0,0,0,0,0,0,0)';$S;BIDI;
    'NMI_SYNC_FLOOD_L':'(0,0,0,0,0,0,0,0,0,0,0,0,0,0,0,0,0,0,0,0,DJ31,0,0,0,0,0,~
0,0,0,0,0,0,0,0,0,0,0,0,0,0)';$S;IN;
    'AGPIO7':'(0,0,0,0,0,0,0,0,0,0,0,0,0,0,0,0,0,0,0,0,DH4,0,0,0,0,0,0,0,0,0,0,0~
,0,0,0,0,0,0,0,0)';$S;BIDI;
    'USB00_DN':'(0,0,0,0,0,0,0,0,0,0,0,0,0,0,0,0,0,0,0,0,0,A25,0,0,0,0,0,0,0,0,0~
,0,0,0,0,0,0,0,0,0)';$S;BIDI;
    'USB00_DP':'(0,0,0,0,0,0,0,0,0,0,0,0,0,0,0,0,0,0,0,0,0,A26,0,0,0,0,0,0,0,0,0~
,0,0,0,0,0,0,0,0,0)';$S;BIDI;
    'USB00_RXN':'(0,0,0,0,0,0,0,0,0,0,0,0,0,0,0,0,0,0,0,0,0,E26,0,0,0,0,0,0,0,0,~
0,0,0,0,0,0,0,0,0,0)';$S;IN;
    'USB00_RXP':'(0,0,0,0,0,0,0,0,0,0,0,0,0,0,0,0,0,0,0,0,0,E27,0,0,0,0,0,0,0,0,~
0,0,0,0,0,0,0,0,0,0)';$S;IN;
    'USB00_TXN':'(0,0,0,0,0,0,0,0,0,0,0,0,0,0,0,0,0,0,0,0,0,C26,0,0,0,0,0,0,0,0,~
0,0,0,0,0,0,0,0,0,0)';$S;OUT;
    'USB00_TXP':'(0,0,0,0,0,0,0,0,0,0,0,0,0,0,0,0,0,0,0,0,0,C25,0,0,0,0,0,0,0,0,~
0,0,0,0,0,0,0,0,0,0)';$S;OUT;
    'USB01_DN':'(0,0,0,0,0,0,0,0,0,0,0,0,0,0,0,0,0,0,0,0,0,A29,0,0,0,0,0,0,0,0,0~
,0,0,0,0,0,0,0,0,0)';$S;BIDI;
    'USB01_DP':'(0,0,0,0,0,0,0,0,0,0,0,0,0,0,0,0,0,0,0,0,0,A28,0,0,0,0,0,0,0,0,0~
,0,0,0,0,0,0,0,0,0)';$S;BIDI;
    'USB01_RXN':'(0,0,0,0,0,0,0,0,0,0,0,0,0,0,0,0,0,0,0,0,0,C28,0,0,0,0,0,0,0,0,~
0,0,0,0,0,0,0,0,0,0)';$S;IN;
    'USB01_RXP':'(0,0,0,0,0,0,0,0,0,0,0,0,0,0,0,0,0,0,0,0,0,C29,0,0,0,0,0,0,0,0,~
0,0,0,0,0,0,0,0,0,0)';$S;IN;
    'USB01_TXN':'(0,0,0,0,0,0,0,0,0,0,0,0,0,0,0,0,0,0,0,0,0,E29,0,0,0,0,0,0,0,0,~
0,0,0,0,0,0,0,0,0,0)';$S;OUT;
    'USB01_TXP':'(0,0,0,0,0,0,0,0,0,0,0,0,0,0,0,0,0,0,0,0,0,E30,0,0,0,0,0,0,0,0,~
0,0,0,0,0,0,0,0,0,0)';$S;OUT;
    'USB10_DN':'(0,0,0,0,0,0,0,0,0,0,0,0,0,0,0,0,0,0,0,0,0,DH67,0,0,0,0,0,0,0,0,~
0,0,0,0,0,0,0,0,0,0)';$S;BIDI;
    'USB10_DP':'(0,0,0,0,0,0,0,0,0,0,0,0,0,0,0,0,0,0,0,0,0,DJ67,0,0,0,0,0,0,0,0,~
0,0,0,0,0,0,0,0,0,0)';$S;BIDI;
    'USB10_RXN':'(0,0,0,0,0,0,0,0,0,0,0,0,0,0,0,0,0,0,0,0,0,DH65,0,0,0,0,0,0,0,0~
,0,0,0,0,0,0,0,0,0,0)';$S;IN;
    'USB10_RXP':'(0,0,0,0,0,0,0,0,0,0,0,0,0,0,0,0,0,0,0,0,0,DJ65,0,0,0,0,0,0,0,0~
,0,0,0,0,0,0,0,0,0,0)';$S;IN;
    'USB10_TXN':'(0,0,0,0,0,0,0,0,0,0,0,0,0,0,0,0,0,0,0,0,0,DJ69,0,0,0,0,0,0,0,0~
,0,0,0,0,0,0,0,0,0,0)';$S;OUT;
    'USB10_TXP':'(0,0,0,0,0,0,0,0,0,0,0,0,0,0,0,0,0,0,0,0,0,DH69,0,0,0,0,0,0,0,0~
,0,0,0,0,0,0,0,0,0,0)';$S;OUT;
    'USB11_DN':'(0,0,0,0,0,0,0,0,0,0,0,0,0,0,0,0,0,0,0,0,0,DJ60,0,0,0,0,0,0,0,0,~
0,0,0,0,0,0,0,0,0,0)';$S;BIDI;
    'USB11_DP':'(0,0,0,0,0,0,0,0,0,0,0,0,0,0,0,0,0,0,0,0,0,DH60,0,0,0,0,0,0,0,0,~
0,0,0,0,0,0,0,0,0,0)';$S;BIDI;
    'USB11_RXN':'(0,0,0,0,0,0,0,0,0,0,0,0,0,0,0,0,0,0,0,0,0,DH62,0,0,0,0,0,0,0,0~
,0,0,0,0,0,0,0,0,0,0)';$S;IN;
    'USB11_RXP':'(0,0,0,0,0,0,0,0,0,0,0,0,0,0,0,0,0,0,0,0,0,DJ62,0,0,0,0,0,0,0,0~
,0,0,0,0,0,0,0,0,0,0)';$S;IN;
    'USB11_TXN':'(0,0,0,0,0,0,0,0,0,0,0,0,0,0,0,0,0,0,0,0,0,DH58,0,0,0,0,0,0,0,0~
,0,0,0,0,0,0,0,0,0,0)';$S;OUT;
    'USB11_TXP':'(0,0,0,0,0,0,0,0,0,0,0,0,0,0,0,0,0,0,0,0,0,DG58,0,0,0,0,0,0,0,0~
,0,0,0,0,0,0,0,0,0,0)';$S;OUT;
    'USB10_OC_L||AGPIO16':'(0,0,0,0,0,0,0,0,0,0,0,0,0,0,0,0,0,0,0,0,0,DG40,0,0,0~
,0,0,0,0,0,0,0,0,0,0,0,0,0,0,0)';$S;BIDI;
    'USB11_OC_L||AGPIO17':'(0,0,0,0,0,0,0,0,0,0,0,0,0,0,0,0,0,0,0,0,0,DH40,0,0,0~
,0,0,0,0,0,0,0,0,0,0,0,0,0,0,0)';$S;BIDI;
    'ESPI_CS0_L||AGPIO124':'(0,0,0,0,0,0,0,0,0,0,0,0,0,0,0,0,0,0,0,0,0,DG28,0,0,~
0,0,0,0,0,0,0,0,0,0,0,0,0,0,0,0)';$S;BIDI;
    'USB00_OC_L||AGPIO264':'(0,0,0,0,0,0,0,0,0,0,0,0,0,0,0,0,0,0,0,0,0,E23,0,0,0~
,0,0,0,0,0,0,0,0,0,0,0,0,0,0,0)';$S;BIDI;
    'SPI_CS0_L||AGPIO118':'(0,0,0,0,0,0,0,0,0,0,0,0,0,0,0,0,0,0,0,0,0,DF30,0,0,0~
,0,0,0,0,0,0,0,0,0,0,0,0,0,0,0)';$S;BIDI;
    'ESPI1_DAT1||SPI1_DAT1||AGPIO132':'(0,0,0,0,0,0,0,0,0,0,0,0,0,0,0,0,0,0,0,0,~
0,DE24,0,0,0,0,0,0,0,0,0,0,0,0,0,0,0,0,0,0)';$S;BIDI;
    'ESPI1_DAT0||SPI1_DAT0||AGPIO131':'(0,0,0,0,0,0,0,0,0,0,0,0,0,0,0,0,0,0,0,0,~
0,DH24,0,0,0,0,0,0,0,0,0,0,0,0,0,0,0,0,0,0)';$S;BIDI;
    'ESPI_CS1_L||AGPIO125':'(0,0,0,0,0,0,0,0,0,0,0,0,0,0,0,0,0,0,0,0,0,DJ23,0,0,~
0,0,0,0,0,0,0,0,0,0,0,0,0,0,0,0)';$S;BIDI;
    'ESPI1_DAT3||SPI1_DAT3||AGPIO134':'(0,0,0,0,0,0,0,0,0,0,0,0,0,0,0,0,0,0,0,0,~
0,DG25,0,0,0,0,0,0,0,0,0,0,0,0,0,0,0,0,0,0)';$S;BIDI;
    'ESPI1_DAT2||SPI1_DAT2||AGPIO133':'(0,0,0,0,0,0,0,0,0,0,0,0,0,0,0,0,0,0,0,0,~
0,DF25,0,0,0,0,0,0,0,0,0,0,0,0,0,0,0,0,0,0)';$S;BIDI;
    'ESPI0_DAT3||SPI0_DAT3||AGPIO123':'(0,0,0,0,0,0,0,0,0,0,0,0,0,0,0,0,0,0,0,0,~
0,DG29,0,0,0,0,0,0,0,0,0,0,0,0,0,0,0,0,0,0)';$S;BIDI;
    'ESPI0_DAT2||SPI0_DAT2||AGPIO122':'(0,0,0,0,0,0,0,0,0,0,0,0,0,0,0,0,0,0,0,0,~
0,DJ28,0,0,0,0,0,0,0,0,0,0,0,0,0,0,0,0,0,0)';$S;BIDI;
    'ESPI0_DAT1||SPI0_DAT1||AGPIO121':'(0,0,0,0,0,0,0,0,0,0,0,0,0,0,0,0,0,0,0,0,~
0,DG22,0,0,0,0,0,0,0,0,0,0,0,0,0,0,0,0,0,0)';$S;BIDI;
    'ESPI0_DAT0||SPI0_DAT0||AGPIO120':'(0,0,0,0,0,0,0,0,0,0,0,0,0,0,0,0,0,0,0,0,~
0,DF28,0,0,0,0,0,0,0,0,0,0,0,0,0,0,0,0,0,0)';$S;BIDI;
    'SPI_CS2_L||AGPIO126':'(0,0,0,0,0,0,0,0,0,0,0,0,0,0,0,0,0,0,0,0,0,DH27,0,0,0~
,0,0,0,0,0,0,0,0,0,0,0,0,0,0,0)';$S;BIDI;
    'SPI_CS1_L||AGPIO119':'(0,0,0,0,0,0,0,0,0,0,0,0,0,0,0,0,0,0,0,0,0,DG26,0,0,0~
,0,0,0,0,0,0,0,0,0,0,0,0,0,0,0)';$S;BIDI;
    'USB01_OC_L||AGPIO265':'(0,0,0,0,0,0,0,0,0,0,0,0,0,0,0,0,0,0,0,0,0,E24,0,0,0~
,0,0,0,0,0,0,0,0,0,0,0,0,0,0,0)';$S;BIDI;
    'ESPI_RSTIN_L||KBRST_L||AGPIO129':'(0,0,0,0,0,0,0,0,0,0,0,0,0,0,0,0,0,0,0,0,~
0,DJ26,0,0,0,0,0,0,0,0,0,0,0,0,0,0,0,0,0,0)';$S;BIDI;
    'ESPI1_ALERT_L||AGPIO110':'(0,0,0,0,0,0,0,0,0,0,0,0,0,0,0,0,0,0,0,0,0,DF24,0~
,0,0,0,0,0,0,0,0,0,0,0,0,0,0,0,0,0)';$S;BIDI;
    'ESPI_CLK0||SPI_CLK0||AGPIO117':'(0,0,0,0,0,0,0,0,0,0,0,0,0,0,0,0,0,0,0,0,0,~
DJ27,0,0,0,0,0,0,0,0,0,0,0,0,0,0,0,0,0,0)';$S;BIDI;
    'AGPIO76||SPI_TPM_CS_L':'(0,0,0,0,0,0,0,0,0,0,0,0,0,0,0,0,0,0,0,0,0,DJ25,0,0~
,0,0,0,0,0,0,0,0,0,0,0,0,0,0,0,0)';$S;BIDI;
    'ESPI0_ALERT_L||AGPIO108':'(0,0,0,0,0,0,0,0,0,0,0,0,0,0,0,0,0,0,0,0,0,DJ22,0~
,0,0,0,0,0,0,0,0,0,0,0,0,0,0,0,0,0)';$S;BIDI;
    'ESPI_CLK2||AGPIO74':'(0,0,0,0,0,0,0,0,0,0,0,0,0,0,0,0,0,0,0,0,0,DF27,0,0,0,~
0,0,0,0,0,0,0,0,0,0,0,0,0,0,0)';$S;BIDI;
    'ESPI_CLK1||SPI_CLK1||AGPIO75':'(0,0,0,0,0,0,0,0,0,0,0,0,0,0,0,0,0,0,0,0,0,D~
G23,0,0,0,0,0,0,0,0,0,0,0,0,0,0,0,0,0,0)';$S;BIDI;
    'ESPI_RSTOUT_L||AGPIO23':'(0,0,0,0,0,0,0,0,0,0,0,0,0,0,0,0,0,0,0,0,0,DE27,0,~
0,0,0,0,0,0,0,0,0,0,0,0,0,0,0,0,0)';$S;BIDI;
    'RSVD_BD62':'(0,0,0,0,0,0,0,0,0,0,0,0,0,0,0,0,0,0,0,0,0,0,BD62,0,0,0,0,0,0,0~
,0,0,0,0,0,0,0,0,0,0)';$S;OUT;
    'RSVD_D72':'(0,0,0,0,0,0,0,0,0,0,0,0,0,0,0,0,0,0,0,0,0,0,D72,0,0,0,0,0,0,0,0~
,0,0,0,0,0,0,0,0,0)';$S;OUT;
    'RSVD_C54':'(0,0,0,0,0,0,0,0,0,0,0,0,0,0,0,0,0,0,0,0,0,0,C54,0,0,0,0,0,0,0,0~
,0,0,0,0,0,0,0,0,0)';$S;OUT;
    'RSVD_BD65':'(0,0,0,0,0,0,0,0,0,0,0,0,0,0,0,0,0,0,0,0,0,0,BD65,0,0,0,0,0,0,0~
,0,0,0,0,0,0,0,0,0,0)';$S;OUT;
    'RSVD_E33':'(0,0,0,0,0,0,0,0,0,0,0,0,0,0,0,0,0,0,0,0,0,0,E33,0,0,0,0,0,0,0,0~
,0,0,0,0,0,0,0,0,0)';$S;OUT;
    'RSVD_D4':'(0,0,0,0,0,0,0,0,0,0,0,0,0,0,0,0,0,0,0,0,0,0,D4,0,0,0,0,0,0,0,0,0~
,0,0,0,0,0,0,0,0)';$S;OUT;
    'RSVD_A55':'(0,0,0,0,0,0,0,0,0,0,0,0,0,0,0,0,0,0,0,0,0,0,A55,0,0,0,0,0,0,0,0~
,0,0,0,0,0,0,0,0,0)';$S;OUT;
    'RSVD_BD69':'(0,0,0,0,0,0,0,0,0,0,0,0,0,0,0,0,0,0,0,0,0,0,BD69,0,0,0,0,0,0,0~
,0,0,0,0,0,0,0,0,0,0)';$S;OUT;
    'RSVD_E36':'(0,0,0,0,0,0,0,0,0,0,0,0,0,0,0,0,0,0,0,0,0,0,E36,0,0,0,0,0,0,0,0~
,0,0,0,0,0,0,0,0,0)';$S;OUT;
    'RSVD_D8':'(0,0,0,0,0,0,0,0,0,0,0,0,0,0,0,0,0,0,0,0,0,0,D8,0,0,0,0,0,0,0,0,0~
,0,0,0,0,0,0,0,0)';$S;OUT;
    'RSVD_A56':'(0,0,0,0,0,0,0,0,0,0,0,0,0,0,0,0,0,0,0,0,0,0,A56,0,0,0,0,0,0,0,0~
,0,0,0,0,0,0,0,0,0)';$S;OUT;
    'RSVD_BD72':'(0,0,0,0,0,0,0,0,0,0,0,0,0,0,0,0,0,0,0,0,0,0,BD72,0,0,0,0,0,0,0~
,0,0,0,0,0,0,0,0,0,0)';$S;OUT;
    'RSVD_BD4':'(0,0,0,0,0,0,0,0,0,0,0,0,0,0,0,0,0,0,0,0,0,0,BD4,0,0,0,0,0,0,0,0~
,0,0,0,0,0,0,0,0,0)';$S;OUT;
    'RSVD_D11':'(0,0,0,0,0,0,0,0,0,0,0,0,0,0,0,0,0,0,0,0,0,0,D11,0,0,0,0,0,0,0,0~
,0,0,0,0,0,0,0,0,0)';$S;OUT;
    'RSVD_A57':'(0,0,0,0,0,0,0,0,0,0,0,0,0,0,0,0,0,0,0,0,0,0,A57,0,0,0,0,0,0,0,0~
,0,0,0,0,0,0,0,0,0)';$S;OUT;
    'RSVD_DG17':'(0,0,0,0,0,0,0,0,0,0,0,0,0,0,0,0,0,0,0,0,0,0,DG17,0,0,0,0,0,0,0~
,0,0,0,0,0,0,0,0,0,0)';$S;OUT;
    'RSVD_D22':'(0,0,0,0,0,0,0,0,0,0,0,0,0,0,0,0,0,0,0,0,0,0,D22,0,0,0,0,0,0,0,0~
,0,0,0,0,0,0,0,0,0)';$S;OUT;
    'RSVD_A59':'(0,0,0,0,0,0,0,0,0,0,0,0,0,0,0,0,0,0,0,0,0,0,A59,0,0,0,0,0,0,0,0~
,0,0,0,0,0,0,0,0,0)';$S;OUT;
    'RSVD_DH17':'(0,0,0,0,0,0,0,0,0,0,0,0,0,0,0,0,0,0,0,0,0,0,DH17,0,0,0,0,0,0,0~
,0,0,0,0,0,0,0,0,0,0)';$S;OUT;
    'RSVD_BD11':'(0,0,0,0,0,0,0,0,0,0,0,0,0,0,0,0,0,0,0,0,0,0,BD11,0,0,0,0,0,0,0~
,0,0,0,0,0,0,0,0,0,0)';$S;OUT;
    'RSVD_D34':'(0,0,0,0,0,0,0,0,0,0,0,0,0,0,0,0,0,0,0,0,0,0,D34,0,0,0,0,0,0,0,0~
,0,0,0,0,0,0,0,0,0)';$S;OUT;
    'RSVD_A31':'(0,0,0,0,0,0,0,0,0,0,0,0,0,0,0,0,0,0,0,0,0,0,A31,0,0,0,0,0,0,0,0~
,0,0,0,0,0,0,0,0,0)';$S;OUT;
    'RSVD_DH21':'(0,0,0,0,0,0,0,0,0,0,0,0,0,0,0,0,0,0,0,0,0,0,DH21,0,0,0,0,0,0,0~
,0,0,0,0,0,0,0,0,0,0)';$S;OUT;
    'RSVD_BD14':'(0,0,0,0,0,0,0,0,0,0,0,0,0,0,0,0,0,0,0,0,0,0,BD14,0,0,0,0,0,0,0~
,0,0,0,0,0,0,0,0,0,0)';$S;OUT;
    'RSVD_B40':'(0,0,0,0,0,0,0,0,0,0,0,0,0,0,0,0,0,0,0,0,0,0,B40,0,0,0,0,0,0,0,0~
,0,0,0,0,0,0,0,0,0)';$S;OUT;
    'RSVD_A35':'(0,0,0,0,0,0,0,0,0,0,0,0,0,0,0,0,0,0,0,0,0,0,A35,0,0,0,0,0,0,0,0~
,0,0,0,0,0,0,0,0,0)';$S;OUT;
    'RSVD_DJ4':'(0,0,0,0,0,0,0,0,0,0,0,0,0,0,0,0,0,0,0,0,0,0,DJ4,0,0,0,0,0,0,0,0~
,0,0,0,0,0,0,0,0,0)';$S;OUT;
    'RSVD_BD18':'(0,0,0,0,0,0,0,0,0,0,0,0,0,0,0,0,0,0,0,0,0,0,BD18,0,0,0,0,0,0,0~
,0,0,0,0,0,0,0,0,0,0)';$S;OUT;
    'RSVD_D58':'(0,0,0,0,0,0,0,0,0,0,0,0,0,0,0,0,0,0,0,0,0,0,D58,0,0,0,0,0,0,0,0~
,0,0,0,0,0,0,0,0,0)';$S;OUT;
    'RSVD_C31':'(0,0,0,0,0,0,0,0,0,0,0,0,0,0,0,0,0,0,0,0,0,0,C31,0,0,0,0,0,0,0,0~
,0,0,0,0,0,0,0,0,0)';$S;OUT;
    'RSVD_A41':'(0,0,0,0,0,0,0,0,0,0,0,0,0,0,0,0,0,0,0,0,0,0,A41,0,0,0,0,0,0,0,0~
,0,0,0,0,0,0,0,0,0)';$S;OUT;
    'RSVD_BD21':'(0,0,0,0,0,0,0,0,0,0,0,0,0,0,0,0,0,0,0,0,0,0,BD21,0,0,0,0,0,0,0~
,0,0,0,0,0,0,0,0,0,0)';$S;OUT;
    'RSVD_D62':'(0,0,0,0,0,0,0,0,0,0,0,0,0,0,0,0,0,0,0,0,0,0,D62,0,0,0,0,0,0,0,0~
,0,0,0,0,0,0,0,0,0)';$S;OUT;
    'RSVD_C34':'(0,0,0,0,0,0,0,0,0,0,0,0,0,0,0,0,0,0,0,0,0,0,C34,0,0,0,0,0,0,0,0~
,0,0,0,0,0,0,0,0,0)';$S;OUT;
    'RSVD_A42':'(0,0,0,0,0,0,0,0,0,0,0,0,0,0,0,0,0,0,0,0,0,0,A42,0,0,0,0,0,0,0,0~
,0,0,0,0,0,0,0,0,0)';$S;OUT;
    'RSVD_D65':'(0,0,0,0,0,0,0,0,0,0,0,0,0,0,0,0,0,0,0,0,0,0,D65,0,0,0,0,0,0,0,0~
,0,0,0,0,0,0,0,0,0)';$S;OUT;
    'RSVD_C35':'(0,0,0,0,0,0,0,0,0,0,0,0,0,0,0,0,0,0,0,0,0,0,C35,0,0,0,0,0,0,0,0~
,0,0,0,0,0,0,0,0,0)';$S;OUT;
    'RSVD_A45':'(0,0,0,0,0,0,0,0,0,0,0,0,0,0,0,0,0,0,0,0,0,0,A45,0,0,0,0,0,0,0,0~
,0,0,0,0,0,0,0,0,0)';$S;OUT;
    'RSVD_C53':'(0,0,0,0,0,0,0,0,0,0,0,0,0,0,0,0,0,0,0,0,0,0,C53,0,0,0,0,0,0,0,0~
,0,0,0,0,0,0,0,0,0)';$S;OUT;
    'RSVD_A48':'(0,0,0,0,0,0,0,0,0,0,0,0,0,0,0,0,0,0,0,0,0,0,A48,0,0,0,0,0,0,0,0~
,0,0,0,0,0,0,0,0,0)';$S;OUT;
    'RSVD_A50':'(0,0,0,0,0,0,0,0,0,0,0,0,0,0,0,0,0,0,0,0,0,0,A50,0,0,0,0,0,0,0,0~
,0,0,0,0,0,0,0,0,0)';$S;OUT;
    'RSVD_A51':'(0,0,0,0,0,0,0,0,0,0,0,0,0,0,0,0,0,0,0,0,0,0,A51,0,0,0,0,0,0,0,0~
,0,0,0,0,0,0,0,0,0)';$S;OUT;
    'RSVD_A54':'(0,0,0,0,0,0,0,0,0,0,0,0,0,0,0,0,0,0,0,0,0,0,A54,0,0,0,0,0,0,0,0~
,0,0,0,0,0,0,0,0,0)';$S;OUT;
    'RSVD_BD55':'(0,0,0,0,0,0,0,0,0,0,0,0,0,0,0,0,0,0,0,0,0,0,BD55,0,0,0,0,0,0,0~
,0,0,0,0,0,0,0,0,0,0)';$S;OUT;
    'RSVD_BD58':'(0,0,0,0,0,0,0,0,0,0,0,0,0,0,0,0,0,0,0,0,0,0,BD58,0,0,0,0,0,0,0~
,0,0,0,0,0,0,0,0,0,0)';$S;OUT;
    'RSVD_D36':'(0,0,0,0,0,0,0,0,0,0,0,0,0,0,0,0,0,0,0,0,0,0,D36,0,0,0,0,0,0,0,0~
,0,0,0,0,0,0,0,0,0)';$S;OUT;
    'RSVD_BD7':'(0,0,0,0,0,0,0,0,0,0,0,0,0,0,0,0,0,0,0,0,0,0,BD7,0,0,0,0,0,0,0,0~
,0,0,0,0,0,0,0,0,0)';$S;OUT;
    'RSVD_A60':'(0,0,0,0,0,0,0,0,0,0,0,0,0,0,0,0,0,0,0,0,0,0,A60,0,0,0,0,0,0,0,0~
,0,0,0,0,0,0,0,0,0)';$S;OUT;
    'TEST6_X3D7':'(0,0,0,0,0,0,0,0,0,0,0,0,0,0,0,0,0,0,0,0,0,0,DJ57,0,0,0,0,0,0,~
0,0,0,0,0,0,0,0,0,0,0)';$S;OUT;
    'TEST5_CCD13':'(0,0,0,0,0,0,0,0,0,0,0,0,0,0,0,0,0,0,0,0,0,0,DH14,0,0,0,0,0,0~
,0,0,0,0,0,0,0,0,0,0,0)';$S;OUT;
    'TEST4_CCD13':'(0,0,0,0,0,0,0,0,0,0,0,0,0,0,0,0,0,0,0,0,0,0,DH13,0,0,0,0,0,0~
,0,0,0,0,0,0,0,0,0,0,0)';$S;OUT;
    'TEST5_CCD14':'(0,0,0,0,0,0,0,0,0,0,0,0,0,0,0,0,0,0,0,0,0,0,DG42,0,0,0,0,0,0~
,0,0,0,0,0,0,0,0,0,0,0)';$S;OUT;
    'TEST4_CCD14':'(0,0,0,0,0,0,0,0,0,0,0,0,0,0,0,0,0,0,0,0,0,0,DF41,0,0,0,0,0,0~
,0,0,0,0,0,0,0,0,0,0,0)';$S;OUT;
    'TEST5_CCD15':'(0,0,0,0,0,0,0,0,0,0,0,0,0,0,0,0,0,0,0,0,0,0,D23,0,0,0,0,0,0,~
0,0,0,0,0,0,0,0,0,0,0)';$S;OUT;
    'TEST5_CCD12':'(0,0,0,0,0,0,0,0,0,0,0,0,0,0,0,0,0,0,0,0,0,0,C59,0,0,0,0,0,0,~
0,0,0,0,0,0,0,0,0,0,0)';$S;OUT;
    'TEST4_CCD12':'(0,0,0,0,0,0,0,0,0,0,0,0,0,0,0,0,0,0,0,0,0,0,C58,0,0,0,0,0,0,~
0,0,0,0,0,0,0,0,0,0,0)';$S;OUT;
    'TEST4_CCD15':'(0,0,0,0,0,0,0,0,0,0,0,0,0,0,0,0,0,0,0,0,0,0,C23,0,0,0,0,0,0,~
0,0,0,0,0,0,0,0,0,0,0)';$S;OUT;
    'TEST6_X3D6':'(0,0,0,0,0,0,0,0,0,0,0,0,0,0,0,0,0,0,0,0,0,0,B36,0,0,0,0,0,0,0~
,0,0,0,0,0,0,0,0,0,0)';$S;OUT;
    'VDDCR_CPU0_W47':'(0,0,0,0,0,0,0,0,0,0,0,0,0,0,0,0,0,0,0,0,0,0,0,W47,0,0,0,0~
,0,0,0,0,0,0,0,0,0,0,0,0)';$S;
    'VDDCR_CPU0_W46':'(0,0,0,0,0,0,0,0,0,0,0,0,0,0,0,0,0,0,0,0,0,0,0,W46,0,0,0,0~
,0,0,0,0,0,0,0,0,0,0,0,0)';$S;
    'VDDCR_CPU0_W44':'(0,0,0,0,0,0,0,0,0,0,0,0,0,0,0,0,0,0,0,0,0,0,0,W44,0,0,0,0~
,0,0,0,0,0,0,0,0,0,0,0,0)';$S;
    'VDDCR_CPU0_W43':'(0,0,0,0,0,0,0,0,0,0,0,0,0,0,0,0,0,0,0,0,0,0,0,W43,0,0,0,0~
,0,0,0,0,0,0,0,0,0,0,0,0)';$S;
    'VDDCR_CPU0_W33':'(0,0,0,0,0,0,0,0,0,0,0,0,0,0,0,0,0,0,0,0,0,0,0,W33,0,0,0,0~
,0,0,0,0,0,0,0,0,0,0,0,0)';$S;
    'VDDCR_CPU0_W32':'(0,0,0,0,0,0,0,0,0,0,0,0,0,0,0,0,0,0,0,0,0,0,0,W32,0,0,0,0~
,0,0,0,0,0,0,0,0,0,0,0,0)';$S;
    'VDDCR_CPU0_W30':'(0,0,0,0,0,0,0,0,0,0,0,0,0,0,0,0,0,0,0,0,0,0,0,W30,0,0,0,0~
,0,0,0,0,0,0,0,0,0,0,0,0)';$S;
    'VDDCR_CPU0_W29':'(0,0,0,0,0,0,0,0,0,0,0,0,0,0,0,0,0,0,0,0,0,0,0,W29,0,0,0,0~
,0,0,0,0,0,0,0,0,0,0,0,0)';$S;
    'VDDCR_CPU0_U41':'(0,0,0,0,0,0,0,0,0,0,0,0,0,0,0,0,0,0,0,0,0,0,0,U41,0,0,0,0~
,0,0,0,0,0,0,0,0,0,0,0,0)';$S;
    'VDDCR_CPU0_U40':'(0,0,0,0,0,0,0,0,0,0,0,0,0,0,0,0,0,0,0,0,0,0,0,U40,0,0,0,0~
,0,0,0,0,0,0,0,0,0,0,0,0)';$S;
    'VDDCR_CPU0_U36':'(0,0,0,0,0,0,0,0,0,0,0,0,0,0,0,0,0,0,0,0,0,0,0,U36,0,0,0,0~
,0,0,0,0,0,0,0,0,0,0,0,0)';$S;
    'VDDCR_CPU0_U35':'(0,0,0,0,0,0,0,0,0,0,0,0,0,0,0,0,0,0,0,0,0,0,0,U35,0,0,0,0~
,0,0,0,0,0,0,0,0,0,0,0,0)';$S;
    'VDDCR_CPU0_T53':'(0,0,0,0,0,0,0,0,0,0,0,0,0,0,0,0,0,0,0,0,0,0,0,T53,0,0,0,0~
,0,0,0,0,0,0,0,0,0,0,0,0)';$S;
    'VDDCR_CPU0_T52':'(0,0,0,0,0,0,0,0,0,0,0,0,0,0,0,0,0,0,0,0,0,0,0,T52,0,0,0,0~
,0,0,0,0,0,0,0,0,0,0,0,0)';$S;
    'VDDCR_CPU0_T50':'(0,0,0,0,0,0,0,0,0,0,0,0,0,0,0,0,0,0,0,0,0,0,0,T50,0,0,0,0~
,0,0,0,0,0,0,0,0,0,0,0,0)';$S;
    'VDDCR_CPU0_T49':'(0,0,0,0,0,0,0,0,0,0,0,0,0,0,0,0,0,0,0,0,0,0,0,T49,0,0,0,0~
,0,0,0,0,0,0,0,0,0,0,0,0)';$S;
    'VDDCR_CPU0_T47':'(0,0,0,0,0,0,0,0,0,0,0,0,0,0,0,0,0,0,0,0,0,0,0,T47,0,0,0,0~
,0,0,0,0,0,0,0,0,0,0,0,0)';$S;
    'VDDCR_CPU0_T46':'(0,0,0,0,0,0,0,0,0,0,0,0,0,0,0,0,0,0,0,0,0,0,0,T46,0,0,0,0~
,0,0,0,0,0,0,0,0,0,0,0,0)';$S;
    'VDDCR_CPU0_T44':'(0,0,0,0,0,0,0,0,0,0,0,0,0,0,0,0,0,0,0,0,0,0,0,T44,0,0,0,0~
,0,0,0,0,0,0,0,0,0,0,0,0)';$S;
    'VDDCR_CPU0_T43':'(0,0,0,0,0,0,0,0,0,0,0,0,0,0,0,0,0,0,0,0,0,0,0,T43,0,0,0,0~
,0,0,0,0,0,0,0,0,0,0,0,0)';$S;
    'VDDCR_CPU0_T33':'(0,0,0,0,0,0,0,0,0,0,0,0,0,0,0,0,0,0,0,0,0,0,0,T33,0,0,0,0~
,0,0,0,0,0,0,0,0,0,0,0,0)';$S;
    'VDDCR_CPU0_T32':'(0,0,0,0,0,0,0,0,0,0,0,0,0,0,0,0,0,0,0,0,0,0,0,T32,0,0,0,0~
,0,0,0,0,0,0,0,0,0,0,0,0)';$S;
    'VDDCR_CPU0_T30':'(0,0,0,0,0,0,0,0,0,0,0,0,0,0,0,0,0,0,0,0,0,0,0,T30,0,0,0,0~
,0,0,0,0,0,0,0,0,0,0,0,0)';$S;
    'VDDCR_CPU0_T29':'(0,0,0,0,0,0,0,0,0,0,0,0,0,0,0,0,0,0,0,0,0,0,0,T29,0,0,0,0~
,0,0,0,0,0,0,0,0,0,0,0,0)';$S;
    'VDDCR_CPU0_T27':'(0,0,0,0,0,0,0,0,0,0,0,0,0,0,0,0,0,0,0,0,0,0,0,T27,0,0,0,0~
,0,0,0,0,0,0,0,0,0,0,0,0)';$S;
    'VDDCR_CPU0_T26':'(0,0,0,0,0,0,0,0,0,0,0,0,0,0,0,0,0,0,0,0,0,0,0,T26,0,0,0,0~
,0,0,0,0,0,0,0,0,0,0,0,0)';$S;
    'VDDCR_CPU0_T24':'(0,0,0,0,0,0,0,0,0,0,0,0,0,0,0,0,0,0,0,0,0,0,0,T24,0,0,0,0~
,0,0,0,0,0,0,0,0,0,0,0,0)';$S;
    'VDDCR_CPU0_T23':'(0,0,0,0,0,0,0,0,0,0,0,0,0,0,0,0,0,0,0,0,0,0,0,T23,0,0,0,0~
,0,0,0,0,0,0,0,0,0,0,0,0)';$S;
    'VDDCR_CPU0_N41':'(0,0,0,0,0,0,0,0,0,0,0,0,0,0,0,0,0,0,0,0,0,0,0,N41,0,0,0,0~
,0,0,0,0,0,0,0,0,0,0,0,0)';$S;
    'VDDCR_CPU0_N40':'(0,0,0,0,0,0,0,0,0,0,0,0,0,0,0,0,0,0,0,0,0,0,0,N40,0,0,0,0~
,0,0,0,0,0,0,0,0,0,0,0,0)';$S;
    'VDDCR_CPU0_N36':'(0,0,0,0,0,0,0,0,0,0,0,0,0,0,0,0,0,0,0,0,0,0,0,N36,0,0,0,0~
,0,0,0,0,0,0,0,0,0,0,0,0)';$S;
    'VDDCR_CPU0_N35':'(0,0,0,0,0,0,0,0,0,0,0,0,0,0,0,0,0,0,0,0,0,0,0,N35,0,0,0,0~
,0,0,0,0,0,0,0,0,0,0,0,0)';$S;
    'VDDCR_CPU0_M53':'(0,0,0,0,0,0,0,0,0,0,0,0,0,0,0,0,0,0,0,0,0,0,0,M53,0,0,0,0~
,0,0,0,0,0,0,0,0,0,0,0,0)';$S;
    'VDDCR_CPU0_M52':'(0,0,0,0,0,0,0,0,0,0,0,0,0,0,0,0,0,0,0,0,0,0,0,M52,0,0,0,0~
,0,0,0,0,0,0,0,0,0,0,0,0)';$S;
    'VDDCR_CPU0_M50':'(0,0,0,0,0,0,0,0,0,0,0,0,0,0,0,0,0,0,0,0,0,0,0,M50,0,0,0,0~
,0,0,0,0,0,0,0,0,0,0,0,0)';$S;
    'VDDCR_CPU0_M49':'(0,0,0,0,0,0,0,0,0,0,0,0,0,0,0,0,0,0,0,0,0,0,0,M49,0,0,0,0~
,0,0,0,0,0,0,0,0,0,0,0,0)';$S;
    'VDDCR_CPU0_M47':'(0,0,0,0,0,0,0,0,0,0,0,0,0,0,0,0,0,0,0,0,0,0,0,M47,0,0,0,0~
,0,0,0,0,0,0,0,0,0,0,0,0)';$S;
    'VDDCR_CPU0_M46':'(0,0,0,0,0,0,0,0,0,0,0,0,0,0,0,0,0,0,0,0,0,0,0,M46,0,0,0,0~
,0,0,0,0,0,0,0,0,0,0,0,0)';$S;
    'VDDCR_CPU0_M44':'(0,0,0,0,0,0,0,0,0,0,0,0,0,0,0,0,0,0,0,0,0,0,0,M44,0,0,0,0~
,0,0,0,0,0,0,0,0,0,0,0,0)';$S;
    'VDDCR_CPU0_M43':'(0,0,0,0,0,0,0,0,0,0,0,0,0,0,0,0,0,0,0,0,0,0,0,M43,0,0,0,0~
,0,0,0,0,0,0,0,0,0,0,0,0)';$S;
    'VDDCR_CPU0_M33':'(0,0,0,0,0,0,0,0,0,0,0,0,0,0,0,0,0,0,0,0,0,0,0,M33,0,0,0,0~
,0,0,0,0,0,0,0,0,0,0,0,0)';$S;
    'VDDCR_CPU0_M32':'(0,0,0,0,0,0,0,0,0,0,0,0,0,0,0,0,0,0,0,0,0,0,0,M32,0,0,0,0~
,0,0,0,0,0,0,0,0,0,0,0,0)';$S;
    'VDDCR_CPU0_M30':'(0,0,0,0,0,0,0,0,0,0,0,0,0,0,0,0,0,0,0,0,0,0,0,M30,0,0,0,0~
,0,0,0,0,0,0,0,0,0,0,0,0)';$S;
    'VDDCR_CPU0_M29':'(0,0,0,0,0,0,0,0,0,0,0,0,0,0,0,0,0,0,0,0,0,0,0,M29,0,0,0,0~
,0,0,0,0,0,0,0,0,0,0,0,0)';$S;
    'VDDCR_CPU0_M27':'(0,0,0,0,0,0,0,0,0,0,0,0,0,0,0,0,0,0,0,0,0,0,0,M27,0,0,0,0~
,0,0,0,0,0,0,0,0,0,0,0,0)';$S;
    'VDDCR_CPU0_M26':'(0,0,0,0,0,0,0,0,0,0,0,0,0,0,0,0,0,0,0,0,0,0,0,M26,0,0,0,0~
,0,0,0,0,0,0,0,0,0,0,0,0)';$S;
    'VDDCR_CPU0_M24':'(0,0,0,0,0,0,0,0,0,0,0,0,0,0,0,0,0,0,0,0,0,0,0,M24,0,0,0,0~
,0,0,0,0,0,0,0,0,0,0,0,0)';$S;
    'VDDCR_CPU0_M23':'(0,0,0,0,0,0,0,0,0,0,0,0,0,0,0,0,0,0,0,0,0,0,0,M23,0,0,0,0~
,0,0,0,0,0,0,0,0,0,0,0,0)';$S;
    'VDDCR_CPU0_J41':'(0,0,0,0,0,0,0,0,0,0,0,0,0,0,0,0,0,0,0,0,0,0,0,J41,0,0,0,0~
,0,0,0,0,0,0,0,0,0,0,0,0)';$S;
    'VDDCR_CPU0_J40':'(0,0,0,0,0,0,0,0,0,0,0,0,0,0,0,0,0,0,0,0,0,0,0,J40,0,0,0,0~
,0,0,0,0,0,0,0,0,0,0,0,0)';$S;
    'VDDCR_CPU0_J36':'(0,0,0,0,0,0,0,0,0,0,0,0,0,0,0,0,0,0,0,0,0,0,0,J36,0,0,0,0~
,0,0,0,0,0,0,0,0,0,0,0,0)';$S;
    'VDDCR_CPU0_J35':'(0,0,0,0,0,0,0,0,0,0,0,0,0,0,0,0,0,0,0,0,0,0,0,J35,0,0,0,0~
,0,0,0,0,0,0,0,0,0,0,0,0)';$S;
    'VDDCR_CPU0_H53':'(0,0,0,0,0,0,0,0,0,0,0,0,0,0,0,0,0,0,0,0,0,0,0,H53,0,0,0,0~
,0,0,0,0,0,0,0,0,0,0,0,0)';$S;
    'VDDCR_CPU0_H52':'(0,0,0,0,0,0,0,0,0,0,0,0,0,0,0,0,0,0,0,0,0,0,0,H52,0,0,0,0~
,0,0,0,0,0,0,0,0,0,0,0,0)';$S;
    'VDDCR_CPU0_H50':'(0,0,0,0,0,0,0,0,0,0,0,0,0,0,0,0,0,0,0,0,0,0,0,H50,0,0,0,0~
,0,0,0,0,0,0,0,0,0,0,0,0)';$S;
    'VDDCR_CPU0_H49':'(0,0,0,0,0,0,0,0,0,0,0,0,0,0,0,0,0,0,0,0,0,0,0,H49,0,0,0,0~
,0,0,0,0,0,0,0,0,0,0,0,0)';$S;
    'VDDCR_CPU0_H47':'(0,0,0,0,0,0,0,0,0,0,0,0,0,0,0,0,0,0,0,0,0,0,0,H47,0,0,0,0~
,0,0,0,0,0,0,0,0,0,0,0,0)';$S;
    'VDDCR_CPU0_H46':'(0,0,0,0,0,0,0,0,0,0,0,0,0,0,0,0,0,0,0,0,0,0,0,H46,0,0,0,0~
,0,0,0,0,0,0,0,0,0,0,0,0)';$S;
    'VDDCR_CPU0_H44':'(0,0,0,0,0,0,0,0,0,0,0,0,0,0,0,0,0,0,0,0,0,0,0,H44,0,0,0,0~
,0,0,0,0,0,0,0,0,0,0,0,0)';$S;
    'VDDCR_CPU0_H43':'(0,0,0,0,0,0,0,0,0,0,0,0,0,0,0,0,0,0,0,0,0,0,0,H43,0,0,0,0~
,0,0,0,0,0,0,0,0,0,0,0,0)';$S;
    'VDDCR_CPU0_H33':'(0,0,0,0,0,0,0,0,0,0,0,0,0,0,0,0,0,0,0,0,0,0,0,H33,0,0,0,0~
,0,0,0,0,0,0,0,0,0,0,0,0)';$S;
    'VDDCR_CPU0_H32':'(0,0,0,0,0,0,0,0,0,0,0,0,0,0,0,0,0,0,0,0,0,0,0,H32,0,0,0,0~
,0,0,0,0,0,0,0,0,0,0,0,0)';$S;
    'VDDCR_CPU0_H30':'(0,0,0,0,0,0,0,0,0,0,0,0,0,0,0,0,0,0,0,0,0,0,0,H30,0,0,0,0~
,0,0,0,0,0,0,0,0,0,0,0,0)';$S;
    'VDDCR_CPU0_H29':'(0,0,0,0,0,0,0,0,0,0,0,0,0,0,0,0,0,0,0,0,0,0,0,H29,0,0,0,0~
,0,0,0,0,0,0,0,0,0,0,0,0)';$S;
    'VDDCR_CPU0_H27':'(0,0,0,0,0,0,0,0,0,0,0,0,0,0,0,0,0,0,0,0,0,0,0,H27,0,0,0,0~
,0,0,0,0,0,0,0,0,0,0,0,0)';$S;
    'VDDCR_CPU0_H26':'(0,0,0,0,0,0,0,0,0,0,0,0,0,0,0,0,0,0,0,0,0,0,0,H26,0,0,0,0~
,0,0,0,0,0,0,0,0,0,0,0,0)';$S;
    'VDDCR_CPU0_H24':'(0,0,0,0,0,0,0,0,0,0,0,0,0,0,0,0,0,0,0,0,0,0,0,H24,0,0,0,0~
,0,0,0,0,0,0,0,0,0,0,0,0)';$S;
    'VDDCR_CPU0_H23':'(0,0,0,0,0,0,0,0,0,0,0,0,0,0,0,0,0,0,0,0,0,0,0,H23,0,0,0,0~
,0,0,0,0,0,0,0,0,0,0,0,0)';$S;
    'VDDCR_CPU0_G41':'(0,0,0,0,0,0,0,0,0,0,0,0,0,0,0,0,0,0,0,0,0,0,0,G41,0,0,0,0~
,0,0,0,0,0,0,0,0,0,0,0,0)';$S;
    'VDDCR_CPU0_G40':'(0,0,0,0,0,0,0,0,0,0,0,0,0,0,0,0,0,0,0,0,0,0,0,G40,0,0,0,0~
,0,0,0,0,0,0,0,0,0,0,0,0)';$S;
    'VDDCR_CPU0_G36':'(0,0,0,0,0,0,0,0,0,0,0,0,0,0,0,0,0,0,0,0,0,0,0,G36,0,0,0,0~
,0,0,0,0,0,0,0,0,0,0,0,0)';$S;
    'VDDCR_CPU0_G35':'(0,0,0,0,0,0,0,0,0,0,0,0,0,0,0,0,0,0,0,0,0,0,0,G35,0,0,0,0~
,0,0,0,0,0,0,0,0,0,0,0,0)';$S;
    'VDDCR_CPU0_F54':'(0,0,0,0,0,0,0,0,0,0,0,0,0,0,0,0,0,0,0,0,0,0,0,F54,0,0,0,0~
,0,0,0,0,0,0,0,0,0,0,0,0)';$S;
    'VDDCR_CPU0_F51':'(0,0,0,0,0,0,0,0,0,0,0,0,0,0,0,0,0,0,0,0,0,0,0,F51,0,0,0,0~
,0,0,0,0,0,0,0,0,0,0,0,0)';$S;
    'VDDCR_CPU0_F48':'(0,0,0,0,0,0,0,0,0,0,0,0,0,0,0,0,0,0,0,0,0,0,0,F48,0,0,0,0~
,0,0,0,0,0,0,0,0,0,0,0,0)';$S;
    'VDDCR_CPU0_F45':'(0,0,0,0,0,0,0,0,0,0,0,0,0,0,0,0,0,0,0,0,0,0,0,F45,0,0,0,0~
,0,0,0,0,0,0,0,0,0,0,0,0)';$S;
    'VDDCR_CPU0_F42':'(0,0,0,0,0,0,0,0,0,0,0,0,0,0,0,0,0,0,0,0,0,0,0,F42,0,0,0,0~
,0,0,0,0,0,0,0,0,0,0,0,0)';$S;
    'VDDCR_CPU0_F34':'(0,0,0,0,0,0,0,0,0,0,0,0,0,0,0,0,0,0,0,0,0,0,0,F34,0,0,0,0~
,0,0,0,0,0,0,0,0,0,0,0,0)';$S;
    'VDDCR_CPU0_F31':'(0,0,0,0,0,0,0,0,0,0,0,0,0,0,0,0,0,0,0,0,0,0,0,F31,0,0,0,0~
,0,0,0,0,0,0,0,0,0,0,0,0)';$S;
    'VDDCR_CPU0_F28':'(0,0,0,0,0,0,0,0,0,0,0,0,0,0,0,0,0,0,0,0,0,0,0,F28,0,0,0,0~
,0,0,0,0,0,0,0,0,0,0,0,0)';$S;
    'VDDCR_CPU0_F25':'(0,0,0,0,0,0,0,0,0,0,0,0,0,0,0,0,0,0,0,0,0,0,0,F25,0,0,0,0~
,0,0,0,0,0,0,0,0,0,0,0,0)';$S;
    'VDDCR_CPU0_F22':'(0,0,0,0,0,0,0,0,0,0,0,0,0,0,0,0,0,0,0,0,0,0,0,F22,0,0,0,0~
,0,0,0,0,0,0,0,0,0,0,0,0)';$S;
    'VDDCR_CPU0_E54':'(0,0,0,0,0,0,0,0,0,0,0,0,0,0,0,0,0,0,0,0,0,0,0,E54,0,0,0,0~
,0,0,0,0,0,0,0,0,0,0,0,0)';$S;
    'VDDCR_CPU0_E51':'(0,0,0,0,0,0,0,0,0,0,0,0,0,0,0,0,0,0,0,0,0,0,0,E51,0,0,0,0~
,0,0,0,0,0,0,0,0,0,0,0,0)';$S;
    'VDDCR_CPU0_E48':'(0,0,0,0,0,0,0,0,0,0,0,0,0,0,0,0,0,0,0,0,0,0,0,E48,0,0,0,0~
,0,0,0,0,0,0,0,0,0,0,0,0)';$S;
    'VDDCR_CPU0_E45':'(0,0,0,0,0,0,0,0,0,0,0,0,0,0,0,0,0,0,0,0,0,0,0,E45,0,0,0,0~
,0,0,0,0,0,0,0,0,0,0,0,0)';$S;
    'VDDCR_CPU0_E42':'(0,0,0,0,0,0,0,0,0,0,0,0,0,0,0,0,0,0,0,0,0,0,0,E42,0,0,0,0~
,0,0,0,0,0,0,0,0,0,0,0,0)';$S;
    'VDDCR_CPU0_E35':'(0,0,0,0,0,0,0,0,0,0,0,0,0,0,0,0,0,0,0,0,0,0,0,E35,0,0,0,0~
,0,0,0,0,0,0,0,0,0,0,0,0)';$S;
    'VDDCR_CPU0_E34':'(0,0,0,0,0,0,0,0,0,0,0,0,0,0,0,0,0,0,0,0,0,0,0,E34,0,0,0,0~
,0,0,0,0,0,0,0,0,0,0,0,0)';$S;
    'VDDCR_CPU0_E31':'(0,0,0,0,0,0,0,0,0,0,0,0,0,0,0,0,0,0,0,0,0,0,0,E31,0,0,0,0~
,0,0,0,0,0,0,0,0,0,0,0,0)';$S;
    'VDDCR_CPU0_E28':'(0,0,0,0,0,0,0,0,0,0,0,0,0,0,0,0,0,0,0,0,0,0,0,E28,0,0,0,0~
,0,0,0,0,0,0,0,0,0,0,0,0)';$S;
    'VDDCR_CPU0_E25':'(0,0,0,0,0,0,0,0,0,0,0,0,0,0,0,0,0,0,0,0,0,0,0,E25,0,0,0,0~
,0,0,0,0,0,0,0,0,0,0,0,0)';$S;
    'VDDCR_CPU0_E22':'(0,0,0,0,0,0,0,0,0,0,0,0,0,0,0,0,0,0,0,0,0,0,0,E22,0,0,0,0~
,0,0,0,0,0,0,0,0,0,0,0,0)';$S;
    'VDDCR_CPU0_D56':'(0,0,0,0,0,0,0,0,0,0,0,0,0,0,0,0,0,0,0,0,0,0,0,D56,0,0,0,0~
,0,0,0,0,0,0,0,0,0,0,0,0)';$S;
    'VDDCR_CPU0_D55':'(0,0,0,0,0,0,0,0,0,0,0,0,0,0,0,0,0,0,0,0,0,0,0,D55,0,0,0,0~
,0,0,0,0,0,0,0,0,0,0,0,0)';$S;
    'VDDCR_CPU0_C20':'(0,0,0,0,0,0,0,0,0,0,0,0,0,0,0,0,0,0,0,0,0,0,0,C20,0,0,0,0~
,0,0,0,0,0,0,0,0,0,0,0,0)';$S;
    'VDDCR_CPU0_B57':'(0,0,0,0,0,0,0,0,0,0,0,0,0,0,0,0,0,0,0,0,0,0,0,B57,0,0,0,0~
,0,0,0,0,0,0,0,0,0,0,0,0)';$S;
    'VDDCR_CPU0_B56':'(0,0,0,0,0,0,0,0,0,0,0,0,0,0,0,0,0,0,0,0,0,0,0,B56,0,0,0,0~
,0,0,0,0,0,0,0,0,0,0,0,0)';$S;
    'VDDCR_CPU0_B54':'(0,0,0,0,0,0,0,0,0,0,0,0,0,0,0,0,0,0,0,0,0,0,0,B54,0,0,0,0~
,0,0,0,0,0,0,0,0,0,0,0,0)';$S;
    'VDDCR_CPU0_B53':'(0,0,0,0,0,0,0,0,0,0,0,0,0,0,0,0,0,0,0,0,0,0,0,B53,0,0,0,0~
,0,0,0,0,0,0,0,0,0,0,0,0)';$S;
    'VDDCR_CPU0_B51':'(0,0,0,0,0,0,0,0,0,0,0,0,0,0,0,0,0,0,0,0,0,0,0,B51,0,0,0,0~
,0,0,0,0,0,0,0,0,0,0,0,0)';$S;
    'VDDCR_CPU0_B50':'(0,0,0,0,0,0,0,0,0,0,0,0,0,0,0,0,0,0,0,0,0,0,0,B50,0,0,0,0~
,0,0,0,0,0,0,0,0,0,0,0,0)';$S;
    'VDDCR_CPU0_B48':'(0,0,0,0,0,0,0,0,0,0,0,0,0,0,0,0,0,0,0,0,0,0,0,B48,0,0,0,0~
,0,0,0,0,0,0,0,0,0,0,0,0)';$S;
    'VDDCR_CPU0_B47':'(0,0,0,0,0,0,0,0,0,0,0,0,0,0,0,0,0,0,0,0,0,0,0,B47,0,0,0,0~
,0,0,0,0,0,0,0,0,0,0,0,0)';$S;
    'VDDCR_CPU0_B45':'(0,0,0,0,0,0,0,0,0,0,0,0,0,0,0,0,0,0,0,0,0,0,0,B45,0,0,0,0~
,0,0,0,0,0,0,0,0,0,0,0,0)';$S;
    'VDDCR_CPU0_B44':'(0,0,0,0,0,0,0,0,0,0,0,0,0,0,0,0,0,0,0,0,0,0,0,B44,0,0,0,0~
,0,0,0,0,0,0,0,0,0,0,0,0)';$S;
    'VDDCR_CPU0_B42':'(0,0,0,0,0,0,0,0,0,0,0,0,0,0,0,0,0,0,0,0,0,0,0,B42,0,0,0,0~
,0,0,0,0,0,0,0,0,0,0,0,0)';$S;
    'VDDCR_CPU0_B41':'(0,0,0,0,0,0,0,0,0,0,0,0,0,0,0,0,0,0,0,0,0,0,0,B41,0,0,0,0~
,0,0,0,0,0,0,0,0,0,0,0,0)';$S;
    'VDDCR_CPU0_B35':'(0,0,0,0,0,0,0,0,0,0,0,0,0,0,0,0,0,0,0,0,0,0,0,B35,0,0,0,0~
,0,0,0,0,0,0,0,0,0,0,0,0)';$S;
    'VDDCR_CPU0_B34':'(0,0,0,0,0,0,0,0,0,0,0,0,0,0,0,0,0,0,0,0,0,0,0,B34,0,0,0,0~
,0,0,0,0,0,0,0,0,0,0,0,0)';$S;
    'VDDCR_CPU0_B32':'(0,0,0,0,0,0,0,0,0,0,0,0,0,0,0,0,0,0,0,0,0,0,0,B32,0,0,0,0~
,0,0,0,0,0,0,0,0,0,0,0,0)';$S;
    'VDDCR_CPU0_B31':'(0,0,0,0,0,0,0,0,0,0,0,0,0,0,0,0,0,0,0,0,0,0,0,B31,0,0,0,0~
,0,0,0,0,0,0,0,0,0,0,0,0)';$S;
    'VDDCR_CPU0_B29':'(0,0,0,0,0,0,0,0,0,0,0,0,0,0,0,0,0,0,0,0,0,0,0,B29,0,0,0,0~
,0,0,0,0,0,0,0,0,0,0,0,0)';$S;
    'VDDCR_CPU0_B28':'(0,0,0,0,0,0,0,0,0,0,0,0,0,0,0,0,0,0,0,0,0,0,0,B28,0,0,0,0~
,0,0,0,0,0,0,0,0,0,0,0,0)';$S;
    'VDDCR_CPU0_B26':'(0,0,0,0,0,0,0,0,0,0,0,0,0,0,0,0,0,0,0,0,0,0,0,B26,0,0,0,0~
,0,0,0,0,0,0,0,0,0,0,0,0)';$S;
    'VDDCR_CPU0_B25':'(0,0,0,0,0,0,0,0,0,0,0,0,0,0,0,0,0,0,0,0,0,0,0,B25,0,0,0,0~
,0,0,0,0,0,0,0,0,0,0,0,0)';$S;
    'VDDCR_CPU0_B23':'(0,0,0,0,0,0,0,0,0,0,0,0,0,0,0,0,0,0,0,0,0,0,0,B23,0,0,0,0~
,0,0,0,0,0,0,0,0,0,0,0,0)';$S;
    'VDDCR_CPU0_B22':'(0,0,0,0,0,0,0,0,0,0,0,0,0,0,0,0,0,0,0,0,0,0,0,B22,0,0,0,0~
,0,0,0,0,0,0,0,0,0,0,0,0)';$S;
    'VDDCR_CPU0_B20':'(0,0,0,0,0,0,0,0,0,0,0,0,0,0,0,0,0,0,0,0,0,0,0,B20,0,0,0,0~
,0,0,0,0,0,0,0,0,0,0,0,0)';$S;
    'VDDCR_CPU0_B19':'(0,0,0,0,0,0,0,0,0,0,0,0,0,0,0,0,0,0,0,0,0,0,0,B19,0,0,0,0~
,0,0,0,0,0,0,0,0,0,0,0,0)';$S;
    'VDDCR_CPU0_AT47':'(0,0,0,0,0,0,0,0,0,0,0,0,0,0,0,0,0,0,0,0,0,0,0,AT47,0,0,0~
,0,0,0,0,0,0,0,0,0,0,0,0,0)';$S;
    'VDDCR_CPU0_AT45':'(0,0,0,0,0,0,0,0,0,0,0,0,0,0,0,0,0,0,0,0,0,0,0,AT45,0,0,0~
,0,0,0,0,0,0,0,0,0,0,0,0,0)';$S;
    'VDDCR_CPU0_AT43':'(0,0,0,0,0,0,0,0,0,0,0,0,0,0,0,0,0,0,0,0,0,0,0,AT43,0,0,0~
,0,0,0,0,0,0,0,0,0,0,0,0,0)';$S;
    'VDDCR_CPU0_AT41':'(0,0,0,0,0,0,0,0,0,0,0,0,0,0,0,0,0,0,0,0,0,0,0,AT41,0,0,0~
,0,0,0,0,0,0,0,0,0,0,0,0,0)';$S;
    'VDDCR_CPU0_AT39':'(0,0,0,0,0,0,0,0,0,0,0,0,0,0,0,0,0,0,0,0,0,0,0,AT39,0,0,0~
,0,0,0,0,0,0,0,0,0,0,0,0,0)';$S;
    'VDDCR_CPU0_AT36':'(0,0,0,0,0,0,0,0,0,0,0,0,0,0,0,0,0,0,0,0,0,0,0,AT36,0,0,0~
,0,0,0,0,0,0,0,0,0,0,0,0,0)';$S;
    'VDDCR_CPU0_AT34':'(0,0,0,0,0,0,0,0,0,0,0,0,0,0,0,0,0,0,0,0,0,0,0,AT34,0,0,0~
,0,0,0,0,0,0,0,0,0,0,0,0,0)';$S;
    'VDDCR_CPU0_AT32':'(0,0,0,0,0,0,0,0,0,0,0,0,0,0,0,0,0,0,0,0,0,0,0,AT32,0,0,0~
,0,0,0,0,0,0,0,0,0,0,0,0,0)';$S;
    'VDDCR_CPU0_AT30':'(0,0,0,0,0,0,0,0,0,0,0,0,0,0,0,0,0,0,0,0,0,0,0,AT30,0,0,0~
,0,0,0,0,0,0,0,0,0,0,0,0,0)';$S;
    'VDDCR_CPU0_AT28':'(0,0,0,0,0,0,0,0,0,0,0,0,0,0,0,0,0,0,0,0,0,0,0,AT28,0,0,0~
,0,0,0,0,0,0,0,0,0,0,0,0,0)';$S;
    'VDDCR_CPU0_AT26':'(0,0,0,0,0,0,0,0,0,0,0,0,0,0,0,0,0,0,0,0,0,0,0,AT26,0,0,0~
,0,0,0,0,0,0,0,0,0,0,0,0,0)';$S;
    'VDDCR_CPU0_AT24':'(0,0,0,0,0,0,0,0,0,0,0,0,0,0,0,0,0,0,0,0,0,0,0,AT24,0,0,0~
,0,0,0,0,0,0,0,0,0,0,0,0,0)';$S;
    'VDDCR_CPU0_AR50':'(0,0,0,0,0,0,0,0,0,0,0,0,0,0,0,0,0,0,0,0,0,0,0,AR50,0,0,0~
,0,0,0,0,0,0,0,0,0,0,0,0,0)';$S;
    'VDDCR_CPU0_AR48':'(0,0,0,0,0,0,0,0,0,0,0,0,0,0,0,0,0,0,0,0,0,0,0,AR48,0,0,0~
,0,0,0,0,0,0,0,0,0,0,0,0,0)';$S;
    'VDDCR_CPU0_AR46':'(0,0,0,0,0,0,0,0,0,0,0,0,0,0,0,0,0,0,0,0,0,0,0,AR46,0,0,0~
,0,0,0,0,0,0,0,0,0,0,0,0,0)';$S;
    'VDDCR_CPU0_AR44':'(0,0,0,0,0,0,0,0,0,0,0,0,0,0,0,0,0,0,0,0,0,0,0,AR44,0,0,0~
,0,0,0,0,0,0,0,0,0,0,0,0,0)';$S;
    'VDDCR_CPU0_AR42':'(0,0,0,0,0,0,0,0,0,0,0,0,0,0,0,0,0,0,0,0,0,0,0,AR42,0,0,0~
,0,0,0,0,0,0,0,0,0,0,0,0,0)';$S;
    'VDDCR_CPU0_AR40':'(0,0,0,0,0,0,0,0,0,0,0,0,0,0,0,0,0,0,0,0,0,0,0,AR40,0,0,0~
,0,0,0,0,0,0,0,0,0,0,0,0,0)';$S;
    'VDDCR_CPU0_AR35':'(0,0,0,0,0,0,0,0,0,0,0,0,0,0,0,0,0,0,0,0,0,0,0,AR35,0,0,0~
,0,0,0,0,0,0,0,0,0,0,0,0,0)';$S;
    'VDDCR_CPU0_AR33':'(0,0,0,0,0,0,0,0,0,0,0,0,0,0,0,0,0,0,0,0,0,0,0,AR33,0,0,0~
,0,0,0,0,0,0,0,0,0,0,0,0,0)';$S;
    'VDDCR_CPU0_AR31':'(0,0,0,0,0,0,0,0,0,0,0,0,0,0,0,0,0,0,0,0,0,0,0,AR31,0,0,0~
,0,0,0,0,0,0,0,0,0,0,0,0,0)';$S;
    'VDDCR_CPU0_AR29':'(0,0,0,0,0,0,0,0,0,0,0,0,0,0,0,0,0,0,0,0,0,0,0,AR29,0,0,0~
,0,0,0,0,0,0,0,0,0,0,0,0,0)';$S;
    'VDDCR_CPU0_AR27':'(0,0,0,0,0,0,0,0,0,0,0,0,0,0,0,0,0,0,0,0,0,0,0,AR27,0,0,0~
,0,0,0,0,0,0,0,0,0,0,0,0,0)';$S;
    'VDDCR_CPU0_AR25':'(0,0,0,0,0,0,0,0,0,0,0,0,0,0,0,0,0,0,0,0,0,0,0,AR25,0,0,0~
,0,0,0,0,0,0,0,0,0,0,0,0,0)';$S;
    'VDDCR_CPU0_AR23':'(0,0,0,0,0,0,0,0,0,0,0,0,0,0,0,0,0,0,0,0,0,0,0,AR23,0,0,0~
,0,0,0,0,0,0,0,0,0,0,0,0,0)';$S;
    'VDDCR_CPU0_AP53':'(0,0,0,0,0,0,0,0,0,0,0,0,0,0,0,0,0,0,0,0,0,0,0,AP53,0,0,0~
,0,0,0,0,0,0,0,0,0,0,0,0,0)';$S;
    'VDDCR_CPU0_AP52':'(0,0,0,0,0,0,0,0,0,0,0,0,0,0,0,0,0,0,0,0,0,0,0,AP52,0,0,0~
,0,0,0,0,0,0,0,0,0,0,0,0,0)';$S;
    'VDDCR_CPU0_AP50':'(0,0,0,0,0,0,0,0,0,0,0,0,0,0,0,0,0,0,0,0,0,0,0,AP50,0,0,0~
,0,0,0,0,0,0,0,0,0,0,0,0,0)';$S;
    'VDDCR_CPU0_AP49':'(0,0,0,0,0,0,0,0,0,0,0,0,0,0,0,0,0,0,0,0,0,0,0,AP49,0,0,0~
,0,0,0,0,0,0,0,0,0,0,0,0,0)';$S;
    'VDDCR_CPU0_AP47':'(0,0,0,0,0,0,0,0,0,0,0,0,0,0,0,0,0,0,0,0,0,0,0,AP47,0,0,0~
,0,0,0,0,0,0,0,0,0,0,0,0,0)';$S;
    'VDDCR_CPU0_AP46':'(0,0,0,0,0,0,0,0,0,0,0,0,0,0,0,0,0,0,0,0,0,0,0,AP46,0,0,0~
,0,0,0,0,0,0,0,0,0,0,0,0,0)';$S;
    'VDDCR_CPU0_AP44':'(0,0,0,0,0,0,0,0,0,0,0,0,0,0,0,0,0,0,0,0,0,0,0,AP44,0,0,0~
,0,0,0,0,0,0,0,0,0,0,0,0,0)';$S;
    'VDDCR_CPU0_AP43':'(0,0,0,0,0,0,0,0,0,0,0,0,0,0,0,0,0,0,0,0,0,0,0,AP43,0,0,0~
,0,0,0,0,0,0,0,0,0,0,0,0,0)';$S;
    'VDDCR_CPU0_AP33':'(0,0,0,0,0,0,0,0,0,0,0,0,0,0,0,0,0,0,0,0,0,0,0,AP33,0,0,0~
,0,0,0,0,0,0,0,0,0,0,0,0,0)';$S;
    'VDDCR_CPU0_AP32':'(0,0,0,0,0,0,0,0,0,0,0,0,0,0,0,0,0,0,0,0,0,0,0,AP32,0,0,0~
,0,0,0,0,0,0,0,0,0,0,0,0,0)';$S;
    'VDDCR_CPU0_AP30':'(0,0,0,0,0,0,0,0,0,0,0,0,0,0,0,0,0,0,0,0,0,0,0,AP30,0,0,0~
,0,0,0,0,0,0,0,0,0,0,0,0,0)';$S;
    'VDDCR_CPU0_AP29':'(0,0,0,0,0,0,0,0,0,0,0,0,0,0,0,0,0,0,0,0,0,0,0,AP29,0,0,0~
,0,0,0,0,0,0,0,0,0,0,0,0,0)';$S;
    'VDDCR_CPU0_AP27':'(0,0,0,0,0,0,0,0,0,0,0,0,0,0,0,0,0,0,0,0,0,0,0,AP27,0,0,0~
,0,0,0,0,0,0,0,0,0,0,0,0,0)';$S;
    'VDDCR_CPU0_AP26':'(0,0,0,0,0,0,0,0,0,0,0,0,0,0,0,0,0,0,0,0,0,0,0,AP26,0,0,0~
,0,0,0,0,0,0,0,0,0,0,0,0,0)';$S;
    'VDDCR_CPU0_AP24':'(0,0,0,0,0,0,0,0,0,0,0,0,0,0,0,0,0,0,0,0,0,0,0,AP24,0,0,0~
,0,0,0,0,0,0,0,0,0,0,0,0,0)';$S;
    'VDDCR_CPU0_AP23':'(0,0,0,0,0,0,0,0,0,0,0,0,0,0,0,0,0,0,0,0,0,0,0,AP23,0,0,0~
,0,0,0,0,0,0,0,0,0,0,0,0,0)';$S;
    'VDDCR_CPU0_AL41':'(0,0,0,0,0,0,0,0,0,0,0,0,0,0,0,0,0,0,0,0,0,0,0,AL41,0,0,0~
,0,0,0,0,0,0,0,0,0,0,0,0,0)';$S;
    'VDDCR_CPU0_AL40':'(0,0,0,0,0,0,0,0,0,0,0,0,0,0,0,0,0,0,0,0,0,0,0,AL40,0,0,0~
,0,0,0,0,0,0,0,0,0,0,0,0,0)';$S;
    'VDDCR_CPU0_AL36':'(0,0,0,0,0,0,0,0,0,0,0,0,0,0,0,0,0,0,0,0,0,0,0,AL36,0,0,0~
,0,0,0,0,0,0,0,0,0,0,0,0,0)';$S;
    'VDDCR_CPU0_AL35':'(0,0,0,0,0,0,0,0,0,0,0,0,0,0,0,0,0,0,0,0,0,0,0,AL35,0,0,0~
,0,0,0,0,0,0,0,0,0,0,0,0,0)';$S;
    'VDDCR_CPU0_AK53':'(0,0,0,0,0,0,0,0,0,0,0,0,0,0,0,0,0,0,0,0,0,0,0,AK53,0,0,0~
,0,0,0,0,0,0,0,0,0,0,0,0,0)';$S;
    'VDDCR_CPU0_AK52':'(0,0,0,0,0,0,0,0,0,0,0,0,0,0,0,0,0,0,0,0,0,0,0,AK52,0,0,0~
,0,0,0,0,0,0,0,0,0,0,0,0,0)';$S;
    'VDDCR_CPU0_AK50':'(0,0,0,0,0,0,0,0,0,0,0,0,0,0,0,0,0,0,0,0,0,0,0,AK50,0,0,0~
,0,0,0,0,0,0,0,0,0,0,0,0,0)';$S;
    'VDDCR_CPU0_AK49':'(0,0,0,0,0,0,0,0,0,0,0,0,0,0,0,0,0,0,0,0,0,0,0,AK49,0,0,0~
,0,0,0,0,0,0,0,0,0,0,0,0,0)';$S;
    'VDDCR_CPU0_AK47':'(0,0,0,0,0,0,0,0,0,0,0,0,0,0,0,0,0,0,0,0,0,0,0,AK47,0,0,0~
,0,0,0,0,0,0,0,0,0,0,0,0,0)';$S;
    'VDDCR_CPU0_AK46':'(0,0,0,0,0,0,0,0,0,0,0,0,0,0,0,0,0,0,0,0,0,0,0,AK46,0,0,0~
,0,0,0,0,0,0,0,0,0,0,0,0,0)';$S;
    'VDDCR_CPU0_AK44':'(0,0,0,0,0,0,0,0,0,0,0,0,0,0,0,0,0,0,0,0,0,0,0,AK44,0,0,0~
,0,0,0,0,0,0,0,0,0,0,0,0,0)';$S;
    'VDDCR_CPU0_AK43':'(0,0,0,0,0,0,0,0,0,0,0,0,0,0,0,0,0,0,0,0,0,0,0,AK43,0,0,0~
,0,0,0,0,0,0,0,0,0,0,0,0,0)';$S;
    'VDDCR_CPU0_AK33':'(0,0,0,0,0,0,0,0,0,0,0,0,0,0,0,0,0,0,0,0,0,0,0,AK33,0,0,0~
,0,0,0,0,0,0,0,0,0,0,0,0,0)';$S;
    'VDDCR_CPU0_AK32':'(0,0,0,0,0,0,0,0,0,0,0,0,0,0,0,0,0,0,0,0,0,0,0,AK32,0,0,0~
,0,0,0,0,0,0,0,0,0,0,0,0,0)';$S;
    'VDDCR_CPU0_AK30':'(0,0,0,0,0,0,0,0,0,0,0,0,0,0,0,0,0,0,0,0,0,0,0,AK30,0,0,0~
,0,0,0,0,0,0,0,0,0,0,0,0,0)';$S;
    'VDDCR_CPU0_AK29':'(0,0,0,0,0,0,0,0,0,0,0,0,0,0,0,0,0,0,0,0,0,0,0,AK29,0,0,0~
,0,0,0,0,0,0,0,0,0,0,0,0,0)';$S;
    'VDDCR_CPU0_AK27':'(0,0,0,0,0,0,0,0,0,0,0,0,0,0,0,0,0,0,0,0,0,0,0,AK27,0,0,0~
,0,0,0,0,0,0,0,0,0,0,0,0,0)';$S;
    'VDDCR_CPU0_AK26':'(0,0,0,0,0,0,0,0,0,0,0,0,0,0,0,0,0,0,0,0,0,0,0,AK26,0,0,0~
,0,0,0,0,0,0,0,0,0,0,0,0,0)';$S;
    'VDDCR_CPU0_AK24':'(0,0,0,0,0,0,0,0,0,0,0,0,0,0,0,0,0,0,0,0,0,0,0,AK24,0,0,0~
,0,0,0,0,0,0,0,0,0,0,0,0,0)';$S;
    'VDDCR_CPU0_AK23':'(0,0,0,0,0,0,0,0,0,0,0,0,0,0,0,0,0,0,0,0,0,0,0,AK23,0,0,0~
,0,0,0,0,0,0,0,0,0,0,0,0,0)';$S;
    'VDDCR_CPU0_AG41':'(0,0,0,0,0,0,0,0,0,0,0,0,0,0,0,0,0,0,0,0,0,0,0,AG41,0,0,0~
,0,0,0,0,0,0,0,0,0,0,0,0,0)';$S;
    'VDDCR_CPU0_AG40':'(0,0,0,0,0,0,0,0,0,0,0,0,0,0,0,0,0,0,0,0,0,0,0,AG40,0,0,0~
,0,0,0,0,0,0,0,0,0,0,0,0,0)';$S;
    'VDDCR_CPU0_AG36':'(0,0,0,0,0,0,0,0,0,0,0,0,0,0,0,0,0,0,0,0,0,0,0,AG36,0,0,0~
,0,0,0,0,0,0,0,0,0,0,0,0,0)';$S;
    'VDDCR_CPU0_AG35':'(0,0,0,0,0,0,0,0,0,0,0,0,0,0,0,0,0,0,0,0,0,0,0,AG35,0,0,0~
,0,0,0,0,0,0,0,0,0,0,0,0,0)';$S;
    'VDDCR_CPU0_AF53':'(0,0,0,0,0,0,0,0,0,0,0,0,0,0,0,0,0,0,0,0,0,0,0,AF53,0,0,0~
,0,0,0,0,0,0,0,0,0,0,0,0,0)';$S;
    'VDDCR_CPU0_AF52':'(0,0,0,0,0,0,0,0,0,0,0,0,0,0,0,0,0,0,0,0,0,0,0,AF52,0,0,0~
,0,0,0,0,0,0,0,0,0,0,0,0,0)';$S;
    'VDDCR_CPU0_AF50':'(0,0,0,0,0,0,0,0,0,0,0,0,0,0,0,0,0,0,0,0,0,0,0,AF50,0,0,0~
,0,0,0,0,0,0,0,0,0,0,0,0,0)';$S;
    'VDDCR_CPU0_AF49':'(0,0,0,0,0,0,0,0,0,0,0,0,0,0,0,0,0,0,0,0,0,0,0,AF49,0,0,0~
,0,0,0,0,0,0,0,0,0,0,0,0,0)';$S;
    'VDDCR_CPU0_AF47':'(0,0,0,0,0,0,0,0,0,0,0,0,0,0,0,0,0,0,0,0,0,0,0,AF47,0,0,0~
,0,0,0,0,0,0,0,0,0,0,0,0,0)';$S;
    'VDDCR_CPU0_AF46':'(0,0,0,0,0,0,0,0,0,0,0,0,0,0,0,0,0,0,0,0,0,0,0,AF46,0,0,0~
,0,0,0,0,0,0,0,0,0,0,0,0,0)';$S;
    'VDDCR_CPU0_AF44':'(0,0,0,0,0,0,0,0,0,0,0,0,0,0,0,0,0,0,0,0,0,0,0,AF44,0,0,0~
,0,0,0,0,0,0,0,0,0,0,0,0,0)';$S;
    'VDDCR_CPU0_AF43':'(0,0,0,0,0,0,0,0,0,0,0,0,0,0,0,0,0,0,0,0,0,0,0,AF43,0,0,0~
,0,0,0,0,0,0,0,0,0,0,0,0,0)';$S;
    'VDDCR_CPU0_AF33':'(0,0,0,0,0,0,0,0,0,0,0,0,0,0,0,0,0,0,0,0,0,0,0,AF33,0,0,0~
,0,0,0,0,0,0,0,0,0,0,0,0,0)';$S;
    'VDDCR_CPU0_AF32':'(0,0,0,0,0,0,0,0,0,0,0,0,0,0,0,0,0,0,0,0,0,0,0,AF32,0,0,0~
,0,0,0,0,0,0,0,0,0,0,0,0,0)';$S;
    'VDDCR_CPU0_AF30':'(0,0,0,0,0,0,0,0,0,0,0,0,0,0,0,0,0,0,0,0,0,0,0,AF30,0,0,0~
,0,0,0,0,0,0,0,0,0,0,0,0,0)';$S;
    'VDDCR_CPU0_AF29':'(0,0,0,0,0,0,0,0,0,0,0,0,0,0,0,0,0,0,0,0,0,0,0,AF29,0,0,0~
,0,0,0,0,0,0,0,0,0,0,0,0,0)';$S;
    'VDDCR_CPU0_AF27':'(0,0,0,0,0,0,0,0,0,0,0,0,0,0,0,0,0,0,0,0,0,0,0,AF27,0,0,0~
,0,0,0,0,0,0,0,0,0,0,0,0,0)';$S;
    'VDDCR_CPU0_AF26':'(0,0,0,0,0,0,0,0,0,0,0,0,0,0,0,0,0,0,0,0,0,0,0,AF26,0,0,0~
,0,0,0,0,0,0,0,0,0,0,0,0,0)';$S;
    'VDDCR_CPU0_AF24':'(0,0,0,0,0,0,0,0,0,0,0,0,0,0,0,0,0,0,0,0,0,0,0,AF24,0,0,0~
,0,0,0,0,0,0,0,0,0,0,0,0,0)';$S;
    'VDDCR_CPU0_AF23':'(0,0,0,0,0,0,0,0,0,0,0,0,0,0,0,0,0,0,0,0,0,0,0,AF23,0,0,0~
,0,0,0,0,0,0,0,0,0,0,0,0,0)';$S;
    'VDDCR_CPU0_AC41':'(0,0,0,0,0,0,0,0,0,0,0,0,0,0,0,0,0,0,0,0,0,0,0,AC41,0,0,0~
,0,0,0,0,0,0,0,0,0,0,0,0,0)';$S;
    'VDDCR_CPU0_AC40':'(0,0,0,0,0,0,0,0,0,0,0,0,0,0,0,0,0,0,0,0,0,0,0,AC40,0,0,0~
,0,0,0,0,0,0,0,0,0,0,0,0,0)';$S;
    'VDDCR_CPU0_AC36':'(0,0,0,0,0,0,0,0,0,0,0,0,0,0,0,0,0,0,0,0,0,0,0,AC36,0,0,0~
,0,0,0,0,0,0,0,0,0,0,0,0,0)';$S;
    'VDDCR_CPU0_AC35':'(0,0,0,0,0,0,0,0,0,0,0,0,0,0,0,0,0,0,0,0,0,0,0,AC35,0,0,0~
,0,0,0,0,0,0,0,0,0,0,0,0,0)';$S;
    'VDDCR_CPU0_AB53':'(0,0,0,0,0,0,0,0,0,0,0,0,0,0,0,0,0,0,0,0,0,0,0,AB53,0,0,0~
,0,0,0,0,0,0,0,0,0,0,0,0,0)';$S;
    'VDDCR_CPU0_AB52':'(0,0,0,0,0,0,0,0,0,0,0,0,0,0,0,0,0,0,0,0,0,0,0,AB52,0,0,0~
,0,0,0,0,0,0,0,0,0,0,0,0,0)';$S;
    'VDDCR_CPU0_AB50':'(0,0,0,0,0,0,0,0,0,0,0,0,0,0,0,0,0,0,0,0,0,0,0,AB50,0,0,0~
,0,0,0,0,0,0,0,0,0,0,0,0,0)';$S;
    'VDDCR_CPU0_AB49':'(0,0,0,0,0,0,0,0,0,0,0,0,0,0,0,0,0,0,0,0,0,0,0,AB49,0,0,0~
,0,0,0,0,0,0,0,0,0,0,0,0,0)';$S;
    'VDDCR_CPU0_AB47':'(0,0,0,0,0,0,0,0,0,0,0,0,0,0,0,0,0,0,0,0,0,0,0,AB47,0,0,0~
,0,0,0,0,0,0,0,0,0,0,0,0,0)';$S;
    'VDDCR_CPU0_AB46':'(0,0,0,0,0,0,0,0,0,0,0,0,0,0,0,0,0,0,0,0,0,0,0,AB46,0,0,0~
,0,0,0,0,0,0,0,0,0,0,0,0,0)';$S;
    'VDDCR_CPU0_AB44':'(0,0,0,0,0,0,0,0,0,0,0,0,0,0,0,0,0,0,0,0,0,0,0,AB44,0,0,0~
,0,0,0,0,0,0,0,0,0,0,0,0,0)';$S;
    'VDDCR_CPU0_AB43':'(0,0,0,0,0,0,0,0,0,0,0,0,0,0,0,0,0,0,0,0,0,0,0,AB43,0,0,0~
,0,0,0,0,0,0,0,0,0,0,0,0,0)';$S;
    'VDDCR_CPU0_AB33':'(0,0,0,0,0,0,0,0,0,0,0,0,0,0,0,0,0,0,0,0,0,0,0,AB33,0,0,0~
,0,0,0,0,0,0,0,0,0,0,0,0,0)';$S;
    'VDDCR_CPU0_AB32':'(0,0,0,0,0,0,0,0,0,0,0,0,0,0,0,0,0,0,0,0,0,0,0,AB32,0,0,0~
,0,0,0,0,0,0,0,0,0,0,0,0,0)';$S;
    'VDDCR_CPU0_AB30':'(0,0,0,0,0,0,0,0,0,0,0,0,0,0,0,0,0,0,0,0,0,0,0,AB30,0,0,0~
,0,0,0,0,0,0,0,0,0,0,0,0,0)';$S;
    'VDDCR_CPU0_AB29':'(0,0,0,0,0,0,0,0,0,0,0,0,0,0,0,0,0,0,0,0,0,0,0,AB29,0,0,0~
,0,0,0,0,0,0,0,0,0,0,0,0,0)';$S;
    'VDDCR_CPU0_AB27':'(0,0,0,0,0,0,0,0,0,0,0,0,0,0,0,0,0,0,0,0,0,0,0,AB27,0,0,0~
,0,0,0,0,0,0,0,0,0,0,0,0,0)';$S;
    'VDDCR_CPU0_AB26':'(0,0,0,0,0,0,0,0,0,0,0,0,0,0,0,0,0,0,0,0,0,0,0,AB26,0,0,0~
,0,0,0,0,0,0,0,0,0,0,0,0,0)';$S;
    'VDDCR_CPU0_AB24':'(0,0,0,0,0,0,0,0,0,0,0,0,0,0,0,0,0,0,0,0,0,0,0,AB24,0,0,0~
,0,0,0,0,0,0,0,0,0,0,0,0,0)';$S;
    'VDDCR_CPU0_AB23':'(0,0,0,0,0,0,0,0,0,0,0,0,0,0,0,0,0,0,0,0,0,0,0,AB23,0,0,0~
,0,0,0,0,0,0,0,0,0,0,0,0,0)';$S;
    'VDDCR_CPU0_Y41':'(0,0,0,0,0,0,0,0,0,0,0,0,0,0,0,0,0,0,0,0,0,0,0,Y41,0,0,0,0~
,0,0,0,0,0,0,0,0,0,0,0,0)';$S;
    'VDDCR_CPU0_Y40':'(0,0,0,0,0,0,0,0,0,0,0,0,0,0,0,0,0,0,0,0,0,0,0,Y40,0,0,0,0~
,0,0,0,0,0,0,0,0,0,0,0,0)';$S;
    'VDDCR_CPU0_Y36':'(0,0,0,0,0,0,0,0,0,0,0,0,0,0,0,0,0,0,0,0,0,0,0,Y36,0,0,0,0~
,0,0,0,0,0,0,0,0,0,0,0,0)';$S;
    'VDDCR_CPU0_Y35':'(0,0,0,0,0,0,0,0,0,0,0,0,0,0,0,0,0,0,0,0,0,0,0,Y35,0,0,0,0~
,0,0,0,0,0,0,0,0,0,0,0,0)';$S;
    'VDDCR_CPU0_AU42':'(0,0,0,0,0,0,0,0,0,0,0,0,0,0,0,0,0,0,0,0,0,0,0,AU42,0,0,0~
,0,0,0,0,0,0,0,0,0,0,0,0,0)';$S;
    'VDDCR_CPU0_AU46':'(0,0,0,0,0,0,0,0,0,0,0,0,0,0,0,0,0,0,0,0,0,0,0,AU46,0,0,0~
,0,0,0,0,0,0,0,0,0,0,0,0,0)';$S;
    'VDDCR_CPU0_AT49':'(0,0,0,0,0,0,0,0,0,0,0,0,0,0,0,0,0,0,0,0,0,0,0,AT49,0,0,0~
,0,0,0,0,0,0,0,0,0,0,0,0,0)';$S;
    'VDDCR_CPU0_AU29':'(0,0,0,0,0,0,0,0,0,0,0,0,0,0,0,0,0,0,0,0,0,0,0,AU29,0,0,0~
,0,0,0,0,0,0,0,0,0,0,0,0,0)';$S;
    'VDDCR_CPU0_AU44':'(0,0,0,0,0,0,0,0,0,0,0,0,0,0,0,0,0,0,0,0,0,0,0,AU44,0,0,0~
,0,0,0,0,0,0,0,0,0,0,0,0,0)';$S;
    'VDDCR_CPU0_AU48':'(0,0,0,0,0,0,0,0,0,0,0,0,0,0,0,0,0,0,0,0,0,0,0,AU48,0,0,0~
,0,0,0,0,0,0,0,0,0,0,0,0,0)';$S;
    'VDDCR_CPU0_AU25':'(0,0,0,0,0,0,0,0,0,0,0,0,0,0,0,0,0,0,0,0,0,0,0,AU25,0,0,0~
,0,0,0,0,0,0,0,0,0,0,0,0,0)';$S;
    'VDDCR_CPU0_AU33':'(0,0,0,0,0,0,0,0,0,0,0,0,0,0,0,0,0,0,0,0,0,0,0,AU33,0,0,0~
,0,0,0,0,0,0,0,0,0,0,0,0,0)';$S;
    'VDDCR_CPU1_BN31':'(0,0,0,0,0,0,0,0,0,0,0,0,0,0,0,0,0,0,0,0,0,0,0,0,BN31,0,0~
,0,0,0,0,0,0,0,0,0,0,0,0,0)';$S;
    'VDDCR_CPU1_BN42':'(0,0,0,0,0,0,0,0,0,0,0,0,0,0,0,0,0,0,0,0,0,0,0,0,BN42,0,0~
,0,0,0,0,0,0,0,0,0,0,0,0,0)';$S;
    'VDDCR_CPU1_BN50':'(0,0,0,0,0,0,0,0,0,0,0,0,0,0,0,0,0,0,0,0,0,0,0,0,BN50,0,0~
,0,0,0,0,0,0,0,0,0,0,0,0,0)';$S;
    'VDDCR_CPU1_BP26':'(0,0,0,0,0,0,0,0,0,0,0,0,0,0,0,0,0,0,0,0,0,0,0,0,BP26,0,0~
,0,0,0,0,0,0,0,0,0,0,0,0,0)';$S;
    'VDDCR_CPU1_BP30':'(0,0,0,0,0,0,0,0,0,0,0,0,0,0,0,0,0,0,0,0,0,0,0,0,BP30,0,0~
,0,0,0,0,0,0,0,0,0,0,0,0,0)';$S;
    'VDDCR_CPU1_BP34':'(0,0,0,0,0,0,0,0,0,0,0,0,0,0,0,0,0,0,0,0,0,0,0,0,BP34,0,0~
,0,0,0,0,0,0,0,0,0,0,0,0,0)';$S;
    'VDDCR_CPU1_BP36':'(0,0,0,0,0,0,0,0,0,0,0,0,0,0,0,0,0,0,0,0,0,0,0,0,BP36,0,0~
,0,0,0,0,0,0,0,0,0,0,0,0,0)';$S;
    'VDDCR_CPU1_BP39':'(0,0,0,0,0,0,0,0,0,0,0,0,0,0,0,0,0,0,0,0,0,0,0,0,BP39,0,0~
,0,0,0,0,0,0,0,0,0,0,0,0,0)';$S;
    'VDDCR_CPU1_BP41':'(0,0,0,0,0,0,0,0,0,0,0,0,0,0,0,0,0,0,0,0,0,0,0,0,BP41,0,0~
,0,0,0,0,0,0,0,0,0,0,0,0,0)';$S;
    'VDDCR_CPU1_BP43':'(0,0,0,0,0,0,0,0,0,0,0,0,0,0,0,0,0,0,0,0,0,0,0,0,BP43,0,0~
,0,0,0,0,0,0,0,0,0,0,0,0,0)';$S;
    'VDDCR_CPU1_BP45':'(0,0,0,0,0,0,0,0,0,0,0,0,0,0,0,0,0,0,0,0,0,0,0,0,BP45,0,0~
,0,0,0,0,0,0,0,0,0,0,0,0,0)';$S;
    'VDDCR_CPU1_BP47':'(0,0,0,0,0,0,0,0,0,0,0,0,0,0,0,0,0,0,0,0,0,0,0,0,BP47,0,0~
,0,0,0,0,0,0,0,0,0,0,0,0,0)';$S;
    'VDDCR_CPU1_BP49':'(0,0,0,0,0,0,0,0,0,0,0,0,0,0,0,0,0,0,0,0,0,0,0,0,BP49,0,0~
,0,0,0,0,0,0,0,0,0,0,0,0,0)';$S;
    'VDDCR_CPU1_BR23':'(0,0,0,0,0,0,0,0,0,0,0,0,0,0,0,0,0,0,0,0,0,0,0,0,BR23,0,0~
,0,0,0,0,0,0,0,0,0,0,0,0,0)';$S;
    'VDDCR_CPU1_BR25':'(0,0,0,0,0,0,0,0,0,0,0,0,0,0,0,0,0,0,0,0,0,0,0,0,BR25,0,0~
,0,0,0,0,0,0,0,0,0,0,0,0,0)';$S;
    'VDDCR_CPU1_BR27':'(0,0,0,0,0,0,0,0,0,0,0,0,0,0,0,0,0,0,0,0,0,0,0,0,BR27,0,0~
,0,0,0,0,0,0,0,0,0,0,0,0,0)';$S;
    'VDDCR_CPU1_BR29':'(0,0,0,0,0,0,0,0,0,0,0,0,0,0,0,0,0,0,0,0,0,0,0,0,BR29,0,0~
,0,0,0,0,0,0,0,0,0,0,0,0,0)';$S;
    'VDDCR_CPU1_BR31':'(0,0,0,0,0,0,0,0,0,0,0,0,0,0,0,0,0,0,0,0,0,0,0,0,BR31,0,0~
,0,0,0,0,0,0,0,0,0,0,0,0,0)';$S;
    'VDDCR_CPU1_BR33':'(0,0,0,0,0,0,0,0,0,0,0,0,0,0,0,0,0,0,0,0,0,0,0,0,BR33,0,0~
,0,0,0,0,0,0,0,0,0,0,0,0,0)';$S;
    'VDDCR_CPU1_BR35':'(0,0,0,0,0,0,0,0,0,0,0,0,0,0,0,0,0,0,0,0,0,0,0,0,BR35,0,0~
,0,0,0,0,0,0,0,0,0,0,0,0,0)';$S;
    'VDDCR_CPU1_BR40':'(0,0,0,0,0,0,0,0,0,0,0,0,0,0,0,0,0,0,0,0,0,0,0,0,BR40,0,0~
,0,0,0,0,0,0,0,0,0,0,0,0,0)';$S;
    'VDDCR_CPU1_BR42':'(0,0,0,0,0,0,0,0,0,0,0,0,0,0,0,0,0,0,0,0,0,0,0,0,BR42,0,0~
,0,0,0,0,0,0,0,0,0,0,0,0,0)';$S;
    'VDDCR_CPU1_BR44':'(0,0,0,0,0,0,0,0,0,0,0,0,0,0,0,0,0,0,0,0,0,0,0,0,BR44,0,0~
,0,0,0,0,0,0,0,0,0,0,0,0,0)';$S;
    'VDDCR_CPU1_BR46':'(0,0,0,0,0,0,0,0,0,0,0,0,0,0,0,0,0,0,0,0,0,0,0,0,BR46,0,0~
,0,0,0,0,0,0,0,0,0,0,0,0,0)';$S;
    'VDDCR_CPU1_BR48':'(0,0,0,0,0,0,0,0,0,0,0,0,0,0,0,0,0,0,0,0,0,0,0,0,BR48,0,0~
,0,0,0,0,0,0,0,0,0,0,0,0,0)';$S;
    'VDDCR_CPU1_BR50':'(0,0,0,0,0,0,0,0,0,0,0,0,0,0,0,0,0,0,0,0,0,0,0,0,BR50,0,0~
,0,0,0,0,0,0,0,0,0,0,0,0,0)';$S;
    'VDDCR_CPU1_BR52':'(0,0,0,0,0,0,0,0,0,0,0,0,0,0,0,0,0,0,0,0,0,0,0,0,BR52,0,0~
,0,0,0,0,0,0,0,0,0,0,0,0,0)';$S;
    'VDDCR_CPU1_BT23':'(0,0,0,0,0,0,0,0,0,0,0,0,0,0,0,0,0,0,0,0,0,0,0,0,BT23,0,0~
,0,0,0,0,0,0,0,0,0,0,0,0,0)';$S;
    'VDDCR_CPU1_BT24':'(0,0,0,0,0,0,0,0,0,0,0,0,0,0,0,0,0,0,0,0,0,0,0,0,BT24,0,0~
,0,0,0,0,0,0,0,0,0,0,0,0,0)';$S;
    'VDDCR_CPU1_BT26':'(0,0,0,0,0,0,0,0,0,0,0,0,0,0,0,0,0,0,0,0,0,0,0,0,BT26,0,0~
,0,0,0,0,0,0,0,0,0,0,0,0,0)';$S;
    'VDDCR_CPU1_BT27':'(0,0,0,0,0,0,0,0,0,0,0,0,0,0,0,0,0,0,0,0,0,0,0,0,BT27,0,0~
,0,0,0,0,0,0,0,0,0,0,0,0,0)';$S;
    'VDDCR_CPU1_BT29':'(0,0,0,0,0,0,0,0,0,0,0,0,0,0,0,0,0,0,0,0,0,0,0,0,BT29,0,0~
,0,0,0,0,0,0,0,0,0,0,0,0,0)';$S;
    'VDDCR_CPU1_BT30':'(0,0,0,0,0,0,0,0,0,0,0,0,0,0,0,0,0,0,0,0,0,0,0,0,BT30,0,0~
,0,0,0,0,0,0,0,0,0,0,0,0,0)';$S;
    'VDDCR_CPU1_BT32':'(0,0,0,0,0,0,0,0,0,0,0,0,0,0,0,0,0,0,0,0,0,0,0,0,BT32,0,0~
,0,0,0,0,0,0,0,0,0,0,0,0,0)';$S;
    'VDDCR_CPU1_BT33':'(0,0,0,0,0,0,0,0,0,0,0,0,0,0,0,0,0,0,0,0,0,0,0,0,BT33,0,0~
,0,0,0,0,0,0,0,0,0,0,0,0,0)';$S;
    'VDDCR_CPU1_BT43':'(0,0,0,0,0,0,0,0,0,0,0,0,0,0,0,0,0,0,0,0,0,0,0,0,BT43,0,0~
,0,0,0,0,0,0,0,0,0,0,0,0,0)';$S;
    'VDDCR_CPU1_BT44':'(0,0,0,0,0,0,0,0,0,0,0,0,0,0,0,0,0,0,0,0,0,0,0,0,BT44,0,0~
,0,0,0,0,0,0,0,0,0,0,0,0,0)';$S;
    'VDDCR_CPU1_BT46':'(0,0,0,0,0,0,0,0,0,0,0,0,0,0,0,0,0,0,0,0,0,0,0,0,BT46,0,0~
,0,0,0,0,0,0,0,0,0,0,0,0,0)';$S;
    'VDDCR_CPU1_BT47':'(0,0,0,0,0,0,0,0,0,0,0,0,0,0,0,0,0,0,0,0,0,0,0,0,BT47,0,0~
,0,0,0,0,0,0,0,0,0,0,0,0,0)';$S;
    'VDDCR_CPU1_BT49':'(0,0,0,0,0,0,0,0,0,0,0,0,0,0,0,0,0,0,0,0,0,0,0,0,BT49,0,0~
,0,0,0,0,0,0,0,0,0,0,0,0,0)';$S;
    'VDDCR_CPU1_BT50':'(0,0,0,0,0,0,0,0,0,0,0,0,0,0,0,0,0,0,0,0,0,0,0,0,BT50,0,0~
,0,0,0,0,0,0,0,0,0,0,0,0,0)';$S;
    'VDDCR_CPU1_BT52':'(0,0,0,0,0,0,0,0,0,0,0,0,0,0,0,0,0,0,0,0,0,0,0,0,BT52,0,0~
,0,0,0,0,0,0,0,0,0,0,0,0,0)';$S;
    'VDDCR_CPU1_BT53':'(0,0,0,0,0,0,0,0,0,0,0,0,0,0,0,0,0,0,0,0,0,0,0,0,BT53,0,0~
,0,0,0,0,0,0,0,0,0,0,0,0,0)';$S;
    'VDDCR_CPU1_BW35':'(0,0,0,0,0,0,0,0,0,0,0,0,0,0,0,0,0,0,0,0,0,0,0,0,BW35,0,0~
,0,0,0,0,0,0,0,0,0,0,0,0,0)';$S;
    'VDDCR_CPU1_BW36':'(0,0,0,0,0,0,0,0,0,0,0,0,0,0,0,0,0,0,0,0,0,0,0,0,BW36,0,0~
,0,0,0,0,0,0,0,0,0,0,0,0,0)';$S;
    'VDDCR_CPU1_BW40':'(0,0,0,0,0,0,0,0,0,0,0,0,0,0,0,0,0,0,0,0,0,0,0,0,BW40,0,0~
,0,0,0,0,0,0,0,0,0,0,0,0,0)';$S;
    'VDDCR_CPU1_BW41':'(0,0,0,0,0,0,0,0,0,0,0,0,0,0,0,0,0,0,0,0,0,0,0,0,BW41,0,0~
,0,0,0,0,0,0,0,0,0,0,0,0,0)';$S;
    'VDDCR_CPU1_BY23':'(0,0,0,0,0,0,0,0,0,0,0,0,0,0,0,0,0,0,0,0,0,0,0,0,BY23,0,0~
,0,0,0,0,0,0,0,0,0,0,0,0,0)';$S;
    'VDDCR_CPU1_BY24':'(0,0,0,0,0,0,0,0,0,0,0,0,0,0,0,0,0,0,0,0,0,0,0,0,BY24,0,0~
,0,0,0,0,0,0,0,0,0,0,0,0,0)';$S;
    'VDDCR_CPU1_BY26':'(0,0,0,0,0,0,0,0,0,0,0,0,0,0,0,0,0,0,0,0,0,0,0,0,BY26,0,0~
,0,0,0,0,0,0,0,0,0,0,0,0,0)';$S;
    'VDDCR_CPU1_BY27':'(0,0,0,0,0,0,0,0,0,0,0,0,0,0,0,0,0,0,0,0,0,0,0,0,BY27,0,0~
,0,0,0,0,0,0,0,0,0,0,0,0,0)';$S;
    'VDDCR_CPU1_BY29':'(0,0,0,0,0,0,0,0,0,0,0,0,0,0,0,0,0,0,0,0,0,0,0,0,BY29,0,0~
,0,0,0,0,0,0,0,0,0,0,0,0,0)';$S;
    'VDDCR_CPU1_BY30':'(0,0,0,0,0,0,0,0,0,0,0,0,0,0,0,0,0,0,0,0,0,0,0,0,BY30,0,0~
,0,0,0,0,0,0,0,0,0,0,0,0,0)';$S;
    'VDDCR_CPU1_BY32':'(0,0,0,0,0,0,0,0,0,0,0,0,0,0,0,0,0,0,0,0,0,0,0,0,BY32,0,0~
,0,0,0,0,0,0,0,0,0,0,0,0,0)';$S;
    'VDDCR_CPU1_BY33':'(0,0,0,0,0,0,0,0,0,0,0,0,0,0,0,0,0,0,0,0,0,0,0,0,BY33,0,0~
,0,0,0,0,0,0,0,0,0,0,0,0,0)';$S;
    'VDDCR_CPU1_BY43':'(0,0,0,0,0,0,0,0,0,0,0,0,0,0,0,0,0,0,0,0,0,0,0,0,BY43,0,0~
,0,0,0,0,0,0,0,0,0,0,0,0,0)';$S;
    'VDDCR_CPU1_BY44':'(0,0,0,0,0,0,0,0,0,0,0,0,0,0,0,0,0,0,0,0,0,0,0,0,BY44,0,0~
,0,0,0,0,0,0,0,0,0,0,0,0,0)';$S;
    'VDDCR_CPU1_BY46':'(0,0,0,0,0,0,0,0,0,0,0,0,0,0,0,0,0,0,0,0,0,0,0,0,BY46,0,0~
,0,0,0,0,0,0,0,0,0,0,0,0,0)';$S;
    'VDDCR_CPU1_BY47':'(0,0,0,0,0,0,0,0,0,0,0,0,0,0,0,0,0,0,0,0,0,0,0,0,BY47,0,0~
,0,0,0,0,0,0,0,0,0,0,0,0,0)';$S;
    'VDDCR_CPU1_BY49':'(0,0,0,0,0,0,0,0,0,0,0,0,0,0,0,0,0,0,0,0,0,0,0,0,BY49,0,0~
,0,0,0,0,0,0,0,0,0,0,0,0,0)';$S;
    'VDDCR_CPU1_BY50':'(0,0,0,0,0,0,0,0,0,0,0,0,0,0,0,0,0,0,0,0,0,0,0,0,BY50,0,0~
,0,0,0,0,0,0,0,0,0,0,0,0,0)';$S;
    'VDDCR_CPU1_BY52':'(0,0,0,0,0,0,0,0,0,0,0,0,0,0,0,0,0,0,0,0,0,0,0,0,BY52,0,0~
,0,0,0,0,0,0,0,0,0,0,0,0,0)';$S;
    'VDDCR_CPU1_BY53':'(0,0,0,0,0,0,0,0,0,0,0,0,0,0,0,0,0,0,0,0,0,0,0,0,BY53,0,0~
,0,0,0,0,0,0,0,0,0,0,0,0,0)';$S;
    'VDDCR_CPU1_CC35':'(0,0,0,0,0,0,0,0,0,0,0,0,0,0,0,0,0,0,0,0,0,0,0,0,CC35,0,0~
,0,0,0,0,0,0,0,0,0,0,0,0,0)';$S;
    'VDDCR_CPU1_CC36':'(0,0,0,0,0,0,0,0,0,0,0,0,0,0,0,0,0,0,0,0,0,0,0,0,CC36,0,0~
,0,0,0,0,0,0,0,0,0,0,0,0,0)';$S;
    'VDDCR_CPU1_CC40':'(0,0,0,0,0,0,0,0,0,0,0,0,0,0,0,0,0,0,0,0,0,0,0,0,CC40,0,0~
,0,0,0,0,0,0,0,0,0,0,0,0,0)';$S;
    'VDDCR_CPU1_CC41':'(0,0,0,0,0,0,0,0,0,0,0,0,0,0,0,0,0,0,0,0,0,0,0,0,CC41,0,0~
,0,0,0,0,0,0,0,0,0,0,0,0,0)';$S;
    'VDDCR_CPU1_CD23':'(0,0,0,0,0,0,0,0,0,0,0,0,0,0,0,0,0,0,0,0,0,0,0,0,CD23,0,0~
,0,0,0,0,0,0,0,0,0,0,0,0,0)';$S;
    'VDDCR_CPU1_CD24':'(0,0,0,0,0,0,0,0,0,0,0,0,0,0,0,0,0,0,0,0,0,0,0,0,CD24,0,0~
,0,0,0,0,0,0,0,0,0,0,0,0,0)';$S;
    'VDDCR_CPU1_CD26':'(0,0,0,0,0,0,0,0,0,0,0,0,0,0,0,0,0,0,0,0,0,0,0,0,CD26,0,0~
,0,0,0,0,0,0,0,0,0,0,0,0,0)';$S;
    'VDDCR_CPU1_CD27':'(0,0,0,0,0,0,0,0,0,0,0,0,0,0,0,0,0,0,0,0,0,0,0,0,CD27,0,0~
,0,0,0,0,0,0,0,0,0,0,0,0,0)';$S;
    'VDDCR_CPU1_CD29':'(0,0,0,0,0,0,0,0,0,0,0,0,0,0,0,0,0,0,0,0,0,0,0,0,CD29,0,0~
,0,0,0,0,0,0,0,0,0,0,0,0,0)';$S;
    'VDDCR_CPU1_CD30':'(0,0,0,0,0,0,0,0,0,0,0,0,0,0,0,0,0,0,0,0,0,0,0,0,CD30,0,0~
,0,0,0,0,0,0,0,0,0,0,0,0,0)';$S;
    'VDDCR_CPU1_CD32':'(0,0,0,0,0,0,0,0,0,0,0,0,0,0,0,0,0,0,0,0,0,0,0,0,CD32,0,0~
,0,0,0,0,0,0,0,0,0,0,0,0,0)';$S;
    'VDDCR_CPU1_CD33':'(0,0,0,0,0,0,0,0,0,0,0,0,0,0,0,0,0,0,0,0,0,0,0,0,CD33,0,0~
,0,0,0,0,0,0,0,0,0,0,0,0,0)';$S;
    'VDDCR_CPU1_CD43':'(0,0,0,0,0,0,0,0,0,0,0,0,0,0,0,0,0,0,0,0,0,0,0,0,CD43,0,0~
,0,0,0,0,0,0,0,0,0,0,0,0,0)';$S;
    'VDDCR_CPU1_CD44':'(0,0,0,0,0,0,0,0,0,0,0,0,0,0,0,0,0,0,0,0,0,0,0,0,CD44,0,0~
,0,0,0,0,0,0,0,0,0,0,0,0,0)';$S;
    'VDDCR_CPU1_CD46':'(0,0,0,0,0,0,0,0,0,0,0,0,0,0,0,0,0,0,0,0,0,0,0,0,CD46,0,0~
,0,0,0,0,0,0,0,0,0,0,0,0,0)';$S;
    'VDDCR_CPU1_CD47':'(0,0,0,0,0,0,0,0,0,0,0,0,0,0,0,0,0,0,0,0,0,0,0,0,CD47,0,0~
,0,0,0,0,0,0,0,0,0,0,0,0,0)';$S;
    'VDDCR_CPU1_CD49':'(0,0,0,0,0,0,0,0,0,0,0,0,0,0,0,0,0,0,0,0,0,0,0,0,CD49,0,0~
,0,0,0,0,0,0,0,0,0,0,0,0,0)';$S;
    'VDDCR_CPU1_CD50':'(0,0,0,0,0,0,0,0,0,0,0,0,0,0,0,0,0,0,0,0,0,0,0,0,CD50,0,0~
,0,0,0,0,0,0,0,0,0,0,0,0,0)';$S;
    'VDDCR_CPU1_CD52':'(0,0,0,0,0,0,0,0,0,0,0,0,0,0,0,0,0,0,0,0,0,0,0,0,CD52,0,0~
,0,0,0,0,0,0,0,0,0,0,0,0,0)';$S;
    'VDDCR_CPU1_CD53':'(0,0,0,0,0,0,0,0,0,0,0,0,0,0,0,0,0,0,0,0,0,0,0,0,CD53,0,0~
,0,0,0,0,0,0,0,0,0,0,0,0,0)';$S;
    'VDDCR_CPU1_CG35':'(0,0,0,0,0,0,0,0,0,0,0,0,0,0,0,0,0,0,0,0,0,0,0,0,CG35,0,0~
,0,0,0,0,0,0,0,0,0,0,0,0,0)';$S;
    'VDDCR_CPU1_CG36':'(0,0,0,0,0,0,0,0,0,0,0,0,0,0,0,0,0,0,0,0,0,0,0,0,CG36,0,0~
,0,0,0,0,0,0,0,0,0,0,0,0,0)';$S;
    'VDDCR_CPU1_CG40':'(0,0,0,0,0,0,0,0,0,0,0,0,0,0,0,0,0,0,0,0,0,0,0,0,CG40,0,0~
,0,0,0,0,0,0,0,0,0,0,0,0,0)';$S;
    'VDDCR_CPU1_CG41':'(0,0,0,0,0,0,0,0,0,0,0,0,0,0,0,0,0,0,0,0,0,0,0,0,CG41,0,0~
,0,0,0,0,0,0,0,0,0,0,0,0,0)';$S;
    'VDDCR_CPU1_CH23':'(0,0,0,0,0,0,0,0,0,0,0,0,0,0,0,0,0,0,0,0,0,0,0,0,CH23,0,0~
,0,0,0,0,0,0,0,0,0,0,0,0,0)';$S;
    'VDDCR_CPU1_CH24':'(0,0,0,0,0,0,0,0,0,0,0,0,0,0,0,0,0,0,0,0,0,0,0,0,CH24,0,0~
,0,0,0,0,0,0,0,0,0,0,0,0,0)';$S;
    'VDDCR_CPU1_CH26':'(0,0,0,0,0,0,0,0,0,0,0,0,0,0,0,0,0,0,0,0,0,0,0,0,CH26,0,0~
,0,0,0,0,0,0,0,0,0,0,0,0,0)';$S;
    'VDDCR_CPU1_CH27':'(0,0,0,0,0,0,0,0,0,0,0,0,0,0,0,0,0,0,0,0,0,0,0,0,CH27,0,0~
,0,0,0,0,0,0,0,0,0,0,0,0,0)';$S;
    'VDDCR_CPU1_CH29':'(0,0,0,0,0,0,0,0,0,0,0,0,0,0,0,0,0,0,0,0,0,0,0,0,CH29,0,0~
,0,0,0,0,0,0,0,0,0,0,0,0,0)';$S;
    'VDDCR_CPU1_CH30':'(0,0,0,0,0,0,0,0,0,0,0,0,0,0,0,0,0,0,0,0,0,0,0,0,CH30,0,0~
,0,0,0,0,0,0,0,0,0,0,0,0,0)';$S;
    'VDDCR_CPU1_CH32':'(0,0,0,0,0,0,0,0,0,0,0,0,0,0,0,0,0,0,0,0,0,0,0,0,CH32,0,0~
,0,0,0,0,0,0,0,0,0,0,0,0,0)';$S;
    'VDDCR_CPU1_CH33':'(0,0,0,0,0,0,0,0,0,0,0,0,0,0,0,0,0,0,0,0,0,0,0,0,CH33,0,0~
,0,0,0,0,0,0,0,0,0,0,0,0,0)';$S;
    'VDDCR_CPU1_CH43':'(0,0,0,0,0,0,0,0,0,0,0,0,0,0,0,0,0,0,0,0,0,0,0,0,CH43,0,0~
,0,0,0,0,0,0,0,0,0,0,0,0,0)';$S;
    'VDDCR_CPU1_CH44':'(0,0,0,0,0,0,0,0,0,0,0,0,0,0,0,0,0,0,0,0,0,0,0,0,CH44,0,0~
,0,0,0,0,0,0,0,0,0,0,0,0,0)';$S;
    'VDDCR_CPU1_CH46':'(0,0,0,0,0,0,0,0,0,0,0,0,0,0,0,0,0,0,0,0,0,0,0,0,CH46,0,0~
,0,0,0,0,0,0,0,0,0,0,0,0,0)';$S;
    'VDDCR_CPU1_CH47':'(0,0,0,0,0,0,0,0,0,0,0,0,0,0,0,0,0,0,0,0,0,0,0,0,CH47,0,0~
,0,0,0,0,0,0,0,0,0,0,0,0,0)';$S;
    'VDDCR_CPU1_CH49':'(0,0,0,0,0,0,0,0,0,0,0,0,0,0,0,0,0,0,0,0,0,0,0,0,CH49,0,0~
,0,0,0,0,0,0,0,0,0,0,0,0,0)';$S;
    'VDDCR_CPU1_CH50':'(0,0,0,0,0,0,0,0,0,0,0,0,0,0,0,0,0,0,0,0,0,0,0,0,CH50,0,0~
,0,0,0,0,0,0,0,0,0,0,0,0,0)';$S;
    'VDDCR_CPU1_CH52':'(0,0,0,0,0,0,0,0,0,0,0,0,0,0,0,0,0,0,0,0,0,0,0,0,CH52,0,0~
,0,0,0,0,0,0,0,0,0,0,0,0,0)';$S;
    'VDDCR_CPU1_CH53':'(0,0,0,0,0,0,0,0,0,0,0,0,0,0,0,0,0,0,0,0,0,0,0,0,CH53,0,0~
,0,0,0,0,0,0,0,0,0,0,0,0,0)';$S;
    'VDDCR_CPU1_CK35':'(0,0,0,0,0,0,0,0,0,0,0,0,0,0,0,0,0,0,0,0,0,0,0,0,CK35,0,0~
,0,0,0,0,0,0,0,0,0,0,0,0,0)';$S;
    'VDDCR_CPU1_CK36':'(0,0,0,0,0,0,0,0,0,0,0,0,0,0,0,0,0,0,0,0,0,0,0,0,CK36,0,0~
,0,0,0,0,0,0,0,0,0,0,0,0,0)';$S;
    'VDDCR_CPU1_CK40':'(0,0,0,0,0,0,0,0,0,0,0,0,0,0,0,0,0,0,0,0,0,0,0,0,CK40,0,0~
,0,0,0,0,0,0,0,0,0,0,0,0,0)';$S;
    'VDDCR_CPU1_CK41':'(0,0,0,0,0,0,0,0,0,0,0,0,0,0,0,0,0,0,0,0,0,0,0,0,CK41,0,0~
,0,0,0,0,0,0,0,0,0,0,0,0,0)';$S;
    'VDDCR_CPU1_CL29':'(0,0,0,0,0,0,0,0,0,0,0,0,0,0,0,0,0,0,0,0,0,0,0,0,CL29,0,0~
,0,0,0,0,0,0,0,0,0,0,0,0,0)';$S;
    'VDDCR_CPU1_CL30':'(0,0,0,0,0,0,0,0,0,0,0,0,0,0,0,0,0,0,0,0,0,0,0,0,CL30,0,0~
,0,0,0,0,0,0,0,0,0,0,0,0,0)';$S;
    'VDDCR_CPU1_CL32':'(0,0,0,0,0,0,0,0,0,0,0,0,0,0,0,0,0,0,0,0,0,0,0,0,CL32,0,0~
,0,0,0,0,0,0,0,0,0,0,0,0,0)';$S;
    'VDDCR_CPU1_CL33':'(0,0,0,0,0,0,0,0,0,0,0,0,0,0,0,0,0,0,0,0,0,0,0,0,CL33,0,0~
,0,0,0,0,0,0,0,0,0,0,0,0,0)';$S;
    'VDDCR_CPU1_CL43':'(0,0,0,0,0,0,0,0,0,0,0,0,0,0,0,0,0,0,0,0,0,0,0,0,CL43,0,0~
,0,0,0,0,0,0,0,0,0,0,0,0,0)';$S;
    'VDDCR_CPU1_CL44':'(0,0,0,0,0,0,0,0,0,0,0,0,0,0,0,0,0,0,0,0,0,0,0,0,CL44,0,0~
,0,0,0,0,0,0,0,0,0,0,0,0,0)';$S;
    'VDDCR_CPU1_CL46':'(0,0,0,0,0,0,0,0,0,0,0,0,0,0,0,0,0,0,0,0,0,0,0,0,CL46,0,0~
,0,0,0,0,0,0,0,0,0,0,0,0,0)';$S;
    'VDDCR_CPU1_CL47':'(0,0,0,0,0,0,0,0,0,0,0,0,0,0,0,0,0,0,0,0,0,0,0,0,CL47,0,0~
,0,0,0,0,0,0,0,0,0,0,0,0,0)';$S;
    'VDDCR_CPU1_CN35':'(0,0,0,0,0,0,0,0,0,0,0,0,0,0,0,0,0,0,0,0,0,0,0,0,CN35,0,0~
,0,0,0,0,0,0,0,0,0,0,0,0,0)';$S;
    'VDDCR_CPU1_CN36':'(0,0,0,0,0,0,0,0,0,0,0,0,0,0,0,0,0,0,0,0,0,0,0,0,CN36,0,0~
,0,0,0,0,0,0,0,0,0,0,0,0,0)';$S;
    'VDDCR_CPU1_CN40':'(0,0,0,0,0,0,0,0,0,0,0,0,0,0,0,0,0,0,0,0,0,0,0,0,CN40,0,0~
,0,0,0,0,0,0,0,0,0,0,0,0,0)';$S;
    'VDDCR_CPU1_CN41':'(0,0,0,0,0,0,0,0,0,0,0,0,0,0,0,0,0,0,0,0,0,0,0,0,CN41,0,0~
,0,0,0,0,0,0,0,0,0,0,0,0,0)';$S;
    'VDDCR_CPU1_CP23':'(0,0,0,0,0,0,0,0,0,0,0,0,0,0,0,0,0,0,0,0,0,0,0,0,CP23,0,0~
,0,0,0,0,0,0,0,0,0,0,0,0,0)';$S;
    'VDDCR_CPU1_CP24':'(0,0,0,0,0,0,0,0,0,0,0,0,0,0,0,0,0,0,0,0,0,0,0,0,CP24,0,0~
,0,0,0,0,0,0,0,0,0,0,0,0,0)';$S;
    'VDDCR_CPU1_CP26':'(0,0,0,0,0,0,0,0,0,0,0,0,0,0,0,0,0,0,0,0,0,0,0,0,CP26,0,0~
,0,0,0,0,0,0,0,0,0,0,0,0,0)';$S;
    'VDDCR_CPU1_CP27':'(0,0,0,0,0,0,0,0,0,0,0,0,0,0,0,0,0,0,0,0,0,0,0,0,CP27,0,0~
,0,0,0,0,0,0,0,0,0,0,0,0,0)';$S;
    'VDDCR_CPU1_CP29':'(0,0,0,0,0,0,0,0,0,0,0,0,0,0,0,0,0,0,0,0,0,0,0,0,CP29,0,0~
,0,0,0,0,0,0,0,0,0,0,0,0,0)';$S;
    'VDDCR_CPU1_CP30':'(0,0,0,0,0,0,0,0,0,0,0,0,0,0,0,0,0,0,0,0,0,0,0,0,CP30,0,0~
,0,0,0,0,0,0,0,0,0,0,0,0,0)';$S;
    'VDDCR_CPU1_CP32':'(0,0,0,0,0,0,0,0,0,0,0,0,0,0,0,0,0,0,0,0,0,0,0,0,CP32,0,0~
,0,0,0,0,0,0,0,0,0,0,0,0,0)';$S;
    'VDDCR_CPU1_CP33':'(0,0,0,0,0,0,0,0,0,0,0,0,0,0,0,0,0,0,0,0,0,0,0,0,CP33,0,0~
,0,0,0,0,0,0,0,0,0,0,0,0,0)';$S;
    'VDDCR_CPU1_CP43':'(0,0,0,0,0,0,0,0,0,0,0,0,0,0,0,0,0,0,0,0,0,0,0,0,CP43,0,0~
,0,0,0,0,0,0,0,0,0,0,0,0,0)';$S;
    'VDDCR_CPU1_CP44':'(0,0,0,0,0,0,0,0,0,0,0,0,0,0,0,0,0,0,0,0,0,0,0,0,CP44,0,0~
,0,0,0,0,0,0,0,0,0,0,0,0,0)';$S;
    'VDDCR_CPU1_CP46':'(0,0,0,0,0,0,0,0,0,0,0,0,0,0,0,0,0,0,0,0,0,0,0,0,CP46,0,0~
,0,0,0,0,0,0,0,0,0,0,0,0,0)';$S;
    'VDDCR_CPU1_CP47':'(0,0,0,0,0,0,0,0,0,0,0,0,0,0,0,0,0,0,0,0,0,0,0,0,CP47,0,0~
,0,0,0,0,0,0,0,0,0,0,0,0,0)';$S;
    'VDDCR_CPU1_CP49':'(0,0,0,0,0,0,0,0,0,0,0,0,0,0,0,0,0,0,0,0,0,0,0,0,CP49,0,0~
,0,0,0,0,0,0,0,0,0,0,0,0,0)';$S;
    'VDDCR_CPU1_CP50':'(0,0,0,0,0,0,0,0,0,0,0,0,0,0,0,0,0,0,0,0,0,0,0,0,CP50,0,0~
,0,0,0,0,0,0,0,0,0,0,0,0,0)';$S;
    'VDDCR_CPU1_CP52':'(0,0,0,0,0,0,0,0,0,0,0,0,0,0,0,0,0,0,0,0,0,0,0,0,CP52,0,0~
,0,0,0,0,0,0,0,0,0,0,0,0,0)';$S;
    'VDDCR_CPU1_CP53':'(0,0,0,0,0,0,0,0,0,0,0,0,0,0,0,0,0,0,0,0,0,0,0,0,CP53,0,0~
,0,0,0,0,0,0,0,0,0,0,0,0,0)';$S;
    'VDDCR_CPU1_CU35':'(0,0,0,0,0,0,0,0,0,0,0,0,0,0,0,0,0,0,0,0,0,0,0,0,CU35,0,0~
,0,0,0,0,0,0,0,0,0,0,0,0,0)';$S;
    'VDDCR_CPU1_CU36':'(0,0,0,0,0,0,0,0,0,0,0,0,0,0,0,0,0,0,0,0,0,0,0,0,CU36,0,0~
,0,0,0,0,0,0,0,0,0,0,0,0,0)';$S;
    'VDDCR_CPU1_CU40':'(0,0,0,0,0,0,0,0,0,0,0,0,0,0,0,0,0,0,0,0,0,0,0,0,CU40,0,0~
,0,0,0,0,0,0,0,0,0,0,0,0,0)';$S;
    'VDDCR_CPU1_CU41':'(0,0,0,0,0,0,0,0,0,0,0,0,0,0,0,0,0,0,0,0,0,0,0,0,CU41,0,0~
,0,0,0,0,0,0,0,0,0,0,0,0,0)';$S;
    'VDDCR_CPU1_CV23':'(0,0,0,0,0,0,0,0,0,0,0,0,0,0,0,0,0,0,0,0,0,0,0,0,CV23,0,0~
,0,0,0,0,0,0,0,0,0,0,0,0,0)';$S;
    'VDDCR_CPU1_CV24':'(0,0,0,0,0,0,0,0,0,0,0,0,0,0,0,0,0,0,0,0,0,0,0,0,CV24,0,0~
,0,0,0,0,0,0,0,0,0,0,0,0,0)';$S;
    'VDDCR_CPU1_CV26':'(0,0,0,0,0,0,0,0,0,0,0,0,0,0,0,0,0,0,0,0,0,0,0,0,CV26,0,0~
,0,0,0,0,0,0,0,0,0,0,0,0,0)';$S;
    'VDDCR_CPU1_CV27':'(0,0,0,0,0,0,0,0,0,0,0,0,0,0,0,0,0,0,0,0,0,0,0,0,CV27,0,0~
,0,0,0,0,0,0,0,0,0,0,0,0,0)';$S;
    'VDDCR_CPU1_CV29':'(0,0,0,0,0,0,0,0,0,0,0,0,0,0,0,0,0,0,0,0,0,0,0,0,CV29,0,0~
,0,0,0,0,0,0,0,0,0,0,0,0,0)';$S;
    'VDDCR_CPU1_CV30':'(0,0,0,0,0,0,0,0,0,0,0,0,0,0,0,0,0,0,0,0,0,0,0,0,CV30,0,0~
,0,0,0,0,0,0,0,0,0,0,0,0,0)';$S;
    'VDDCR_CPU1_CV32':'(0,0,0,0,0,0,0,0,0,0,0,0,0,0,0,0,0,0,0,0,0,0,0,0,CV32,0,0~
,0,0,0,0,0,0,0,0,0,0,0,0,0)';$S;
    'VDDCR_CPU1_CV33':'(0,0,0,0,0,0,0,0,0,0,0,0,0,0,0,0,0,0,0,0,0,0,0,0,CV33,0,0~
,0,0,0,0,0,0,0,0,0,0,0,0,0)';$S;
    'VDDCR_CPU1_CV43':'(0,0,0,0,0,0,0,0,0,0,0,0,0,0,0,0,0,0,0,0,0,0,0,0,CV43,0,0~
,0,0,0,0,0,0,0,0,0,0,0,0,0)';$S;
    'VDDCR_CPU1_CV44':'(0,0,0,0,0,0,0,0,0,0,0,0,0,0,0,0,0,0,0,0,0,0,0,0,CV44,0,0~
,0,0,0,0,0,0,0,0,0,0,0,0,0)';$S;
    'VDDCR_CPU1_CV46':'(0,0,0,0,0,0,0,0,0,0,0,0,0,0,0,0,0,0,0,0,0,0,0,0,CV46,0,0~
,0,0,0,0,0,0,0,0,0,0,0,0,0)';$S;
    'VDDCR_CPU1_CV47':'(0,0,0,0,0,0,0,0,0,0,0,0,0,0,0,0,0,0,0,0,0,0,0,0,CV47,0,0~
,0,0,0,0,0,0,0,0,0,0,0,0,0)';$S;
    'VDDCR_CPU1_CV49':'(0,0,0,0,0,0,0,0,0,0,0,0,0,0,0,0,0,0,0,0,0,0,0,0,CV49,0,0~
,0,0,0,0,0,0,0,0,0,0,0,0,0)';$S;
    'VDDCR_CPU1_CV50':'(0,0,0,0,0,0,0,0,0,0,0,0,0,0,0,0,0,0,0,0,0,0,0,0,CV50,0,0~
,0,0,0,0,0,0,0,0,0,0,0,0,0)';$S;
    'VDDCR_CPU1_CV52':'(0,0,0,0,0,0,0,0,0,0,0,0,0,0,0,0,0,0,0,0,0,0,0,0,CV52,0,0~
,0,0,0,0,0,0,0,0,0,0,0,0,0)';$S;
    'VDDCR_CPU1_CV53':'(0,0,0,0,0,0,0,0,0,0,0,0,0,0,0,0,0,0,0,0,0,0,0,0,CV53,0,0~
,0,0,0,0,0,0,0,0,0,0,0,0,0)';$S;
    'VDDCR_CPU1_DA35':'(0,0,0,0,0,0,0,0,0,0,0,0,0,0,0,0,0,0,0,0,0,0,0,0,DA35,0,0~
,0,0,0,0,0,0,0,0,0,0,0,0,0)';$S;
    'VDDCR_CPU1_DA36':'(0,0,0,0,0,0,0,0,0,0,0,0,0,0,0,0,0,0,0,0,0,0,0,0,DA36,0,0~
,0,0,0,0,0,0,0,0,0,0,0,0,0)';$S;
    'VDDCR_CPU1_DA40':'(0,0,0,0,0,0,0,0,0,0,0,0,0,0,0,0,0,0,0,0,0,0,0,0,DA40,0,0~
,0,0,0,0,0,0,0,0,0,0,0,0,0)';$S;
    'VDDCR_CPU1_DA41':'(0,0,0,0,0,0,0,0,0,0,0,0,0,0,0,0,0,0,0,0,0,0,0,0,DA41,0,0~
,0,0,0,0,0,0,0,0,0,0,0,0,0)';$S;
    'VDDCR_CPU1_DB23':'(0,0,0,0,0,0,0,0,0,0,0,0,0,0,0,0,0,0,0,0,0,0,0,0,DB23,0,0~
,0,0,0,0,0,0,0,0,0,0,0,0,0)';$S;
    'VDDCR_CPU1_DB24':'(0,0,0,0,0,0,0,0,0,0,0,0,0,0,0,0,0,0,0,0,0,0,0,0,DB24,0,0~
,0,0,0,0,0,0,0,0,0,0,0,0,0)';$S;
    'VDDCR_CPU1_DB26':'(0,0,0,0,0,0,0,0,0,0,0,0,0,0,0,0,0,0,0,0,0,0,0,0,DB26,0,0~
,0,0,0,0,0,0,0,0,0,0,0,0,0)';$S;
    'VDDCR_CPU1_DB27':'(0,0,0,0,0,0,0,0,0,0,0,0,0,0,0,0,0,0,0,0,0,0,0,0,DB27,0,0~
,0,0,0,0,0,0,0,0,0,0,0,0,0)';$S;
    'VDDCR_CPU1_DB29':'(0,0,0,0,0,0,0,0,0,0,0,0,0,0,0,0,0,0,0,0,0,0,0,0,DB29,0,0~
,0,0,0,0,0,0,0,0,0,0,0,0,0)';$S;
    'VDDCR_CPU1_DB30':'(0,0,0,0,0,0,0,0,0,0,0,0,0,0,0,0,0,0,0,0,0,0,0,0,DB30,0,0~
,0,0,0,0,0,0,0,0,0,0,0,0,0)';$S;
    'VDDCR_CPU1_DB32':'(0,0,0,0,0,0,0,0,0,0,0,0,0,0,0,0,0,0,0,0,0,0,0,0,DB32,0,0~
,0,0,0,0,0,0,0,0,0,0,0,0,0)';$S;
    'VDDCR_CPU1_DB33':'(0,0,0,0,0,0,0,0,0,0,0,0,0,0,0,0,0,0,0,0,0,0,0,0,DB33,0,0~
,0,0,0,0,0,0,0,0,0,0,0,0,0)';$S;
    'VDDCR_CPU1_DB43':'(0,0,0,0,0,0,0,0,0,0,0,0,0,0,0,0,0,0,0,0,0,0,0,0,DB43,0,0~
,0,0,0,0,0,0,0,0,0,0,0,0,0)';$S;
    'VDDCR_CPU1_DB44':'(0,0,0,0,0,0,0,0,0,0,0,0,0,0,0,0,0,0,0,0,0,0,0,0,DB44,0,0~
,0,0,0,0,0,0,0,0,0,0,0,0,0)';$S;
    'VDDCR_CPU1_DB46':'(0,0,0,0,0,0,0,0,0,0,0,0,0,0,0,0,0,0,0,0,0,0,0,0,DB46,0,0~
,0,0,0,0,0,0,0,0,0,0,0,0,0)';$S;
    'VDDCR_CPU1_DB47':'(0,0,0,0,0,0,0,0,0,0,0,0,0,0,0,0,0,0,0,0,0,0,0,0,DB47,0,0~
,0,0,0,0,0,0,0,0,0,0,0,0,0)';$S;
    'VDDCR_CPU1_DB49':'(0,0,0,0,0,0,0,0,0,0,0,0,0,0,0,0,0,0,0,0,0,0,0,0,DB49,0,0~
,0,0,0,0,0,0,0,0,0,0,0,0,0)';$S;
    'VDDCR_CPU1_DB50':'(0,0,0,0,0,0,0,0,0,0,0,0,0,0,0,0,0,0,0,0,0,0,0,0,DB50,0,0~
,0,0,0,0,0,0,0,0,0,0,0,0,0)';$S;
    'VDDCR_CPU1_DB52':'(0,0,0,0,0,0,0,0,0,0,0,0,0,0,0,0,0,0,0,0,0,0,0,0,DB52,0,0~
,0,0,0,0,0,0,0,0,0,0,0,0,0)';$S;
    'VDDCR_CPU1_DB53':'(0,0,0,0,0,0,0,0,0,0,0,0,0,0,0,0,0,0,0,0,0,0,0,0,DB53,0,0~
,0,0,0,0,0,0,0,0,0,0,0,0,0)';$S;
    'VDDCR_CPU1_DC35':'(0,0,0,0,0,0,0,0,0,0,0,0,0,0,0,0,0,0,0,0,0,0,0,0,DC35,0,0~
,0,0,0,0,0,0,0,0,0,0,0,0,0)';$S;
    'VDDCR_CPU1_DC36':'(0,0,0,0,0,0,0,0,0,0,0,0,0,0,0,0,0,0,0,0,0,0,0,0,DC36,0,0~
,0,0,0,0,0,0,0,0,0,0,0,0,0)';$S;
    'VDDCR_CPU1_DC40':'(0,0,0,0,0,0,0,0,0,0,0,0,0,0,0,0,0,0,0,0,0,0,0,0,DC40,0,0~
,0,0,0,0,0,0,0,0,0,0,0,0,0)';$S;
    'VDDCR_CPU1_DC41':'(0,0,0,0,0,0,0,0,0,0,0,0,0,0,0,0,0,0,0,0,0,0,0,0,DC41,0,0~
,0,0,0,0,0,0,0,0,0,0,0,0,0)';$S;
    'VDDCR_CPU1_DD22':'(0,0,0,0,0,0,0,0,0,0,0,0,0,0,0,0,0,0,0,0,0,0,0,0,DD22,0,0~
,0,0,0,0,0,0,0,0,0,0,0,0,0)';$S;
    'VDDCR_CPU1_DD25':'(0,0,0,0,0,0,0,0,0,0,0,0,0,0,0,0,0,0,0,0,0,0,0,0,DD25,0,0~
,0,0,0,0,0,0,0,0,0,0,0,0,0)';$S;
    'VDDCR_CPU1_DD28':'(0,0,0,0,0,0,0,0,0,0,0,0,0,0,0,0,0,0,0,0,0,0,0,0,DD28,0,0~
,0,0,0,0,0,0,0,0,0,0,0,0,0)';$S;
    'VDDCR_CPU1_DD31':'(0,0,0,0,0,0,0,0,0,0,0,0,0,0,0,0,0,0,0,0,0,0,0,0,DD31,0,0~
,0,0,0,0,0,0,0,0,0,0,0,0,0)';$S;
    'VDDCR_CPU1_DD34':'(0,0,0,0,0,0,0,0,0,0,0,0,0,0,0,0,0,0,0,0,0,0,0,0,DD34,0,0~
,0,0,0,0,0,0,0,0,0,0,0,0,0)';$S;
    'VDDCR_CPU1_DD42':'(0,0,0,0,0,0,0,0,0,0,0,0,0,0,0,0,0,0,0,0,0,0,0,0,DD42,0,0~
,0,0,0,0,0,0,0,0,0,0,0,0,0)';$S;
    'VDDCR_CPU1_DD45':'(0,0,0,0,0,0,0,0,0,0,0,0,0,0,0,0,0,0,0,0,0,0,0,0,DD45,0,0~
,0,0,0,0,0,0,0,0,0,0,0,0,0)';$S;
    'VDDCR_CPU1_DD48':'(0,0,0,0,0,0,0,0,0,0,0,0,0,0,0,0,0,0,0,0,0,0,0,0,DD48,0,0~
,0,0,0,0,0,0,0,0,0,0,0,0,0)';$S;
    'VDDCR_CPU1_DD51':'(0,0,0,0,0,0,0,0,0,0,0,0,0,0,0,0,0,0,0,0,0,0,0,0,DD51,0,0~
,0,0,0,0,0,0,0,0,0,0,0,0,0)';$S;
    'VDDCR_CPU1_DD54':'(0,0,0,0,0,0,0,0,0,0,0,0,0,0,0,0,0,0,0,0,0,0,0,0,DD54,0,0~
,0,0,0,0,0,0,0,0,0,0,0,0,0)';$S;
    'VDDCR_CPU1_DE22':'(0,0,0,0,0,0,0,0,0,0,0,0,0,0,0,0,0,0,0,0,0,0,0,0,DE22,0,0~
,0,0,0,0,0,0,0,0,0,0,0,0,0)';$S;
    'VDDCR_CPU1_DE25':'(0,0,0,0,0,0,0,0,0,0,0,0,0,0,0,0,0,0,0,0,0,0,0,0,DE25,0,0~
,0,0,0,0,0,0,0,0,0,0,0,0,0)';$S;
    'VDDCR_CPU1_DE28':'(0,0,0,0,0,0,0,0,0,0,0,0,0,0,0,0,0,0,0,0,0,0,0,0,DE28,0,0~
,0,0,0,0,0,0,0,0,0,0,0,0,0)';$S;
    'VDDCR_CPU1_DE31':'(0,0,0,0,0,0,0,0,0,0,0,0,0,0,0,0,0,0,0,0,0,0,0,0,DE31,0,0~
,0,0,0,0,0,0,0,0,0,0,0,0,0)';$S;
    'VDDCR_CPU1_DE34':'(0,0,0,0,0,0,0,0,0,0,0,0,0,0,0,0,0,0,0,0,0,0,0,0,DE34,0,0~
,0,0,0,0,0,0,0,0,0,0,0,0,0)';$S;
    'VDDCR_CPU1_DE35':'(0,0,0,0,0,0,0,0,0,0,0,0,0,0,0,0,0,0,0,0,0,0,0,0,DE35,0,0~
,0,0,0,0,0,0,0,0,0,0,0,0,0)';$S;
    'VDDCR_CPU1_DE41':'(0,0,0,0,0,0,0,0,0,0,0,0,0,0,0,0,0,0,0,0,0,0,0,0,DE41,0,0~
,0,0,0,0,0,0,0,0,0,0,0,0,0)';$S;
    'VDDCR_CPU1_DE42':'(0,0,0,0,0,0,0,0,0,0,0,0,0,0,0,0,0,0,0,0,0,0,0,0,DE42,0,0~
,0,0,0,0,0,0,0,0,0,0,0,0,0)';$S;
    'VDDCR_CPU1_DE45':'(0,0,0,0,0,0,0,0,0,0,0,0,0,0,0,0,0,0,0,0,0,0,0,0,DE45,0,0~
,0,0,0,0,0,0,0,0,0,0,0,0,0)';$S;
    'VDDCR_CPU1_DE48':'(0,0,0,0,0,0,0,0,0,0,0,0,0,0,0,0,0,0,0,0,0,0,0,0,DE48,0,0~
,0,0,0,0,0,0,0,0,0,0,0,0,0)';$S;
    'VDDCR_CPU1_DE51':'(0,0,0,0,0,0,0,0,0,0,0,0,0,0,0,0,0,0,0,0,0,0,0,0,DE51,0,0~
,0,0,0,0,0,0,0,0,0,0,0,0,0)';$S;
    'VDDCR_CPU1_DE54':'(0,0,0,0,0,0,0,0,0,0,0,0,0,0,0,0,0,0,0,0,0,0,0,0,DE54,0,0~
,0,0,0,0,0,0,0,0,0,0,0,0,0)';$S;
    'VDDCR_CPU1_DG19':'(0,0,0,0,0,0,0,0,0,0,0,0,0,0,0,0,0,0,0,0,0,0,0,0,DG19,0,0~
,0,0,0,0,0,0,0,0,0,0,0,0,0)';$S;
    'VDDCR_CPU1_DG57':'(0,0,0,0,0,0,0,0,0,0,0,0,0,0,0,0,0,0,0,0,0,0,0,0,DG57,0,0~
,0,0,0,0,0,0,0,0,0,0,0,0,0)';$S;
    'VDDCR_CPU1_DH19':'(0,0,0,0,0,0,0,0,0,0,0,0,0,0,0,0,0,0,0,0,0,0,0,0,DH19,0,0~
,0,0,0,0,0,0,0,0,0,0,0,0,0)';$S;
    'VDDCR_CPU1_DH20':'(0,0,0,0,0,0,0,0,0,0,0,0,0,0,0,0,0,0,0,0,0,0,0,0,DH20,0,0~
,0,0,0,0,0,0,0,0,0,0,0,0,0)';$S;
    'VDDCR_CPU1_DH22':'(0,0,0,0,0,0,0,0,0,0,0,0,0,0,0,0,0,0,0,0,0,0,0,0,DH22,0,0~
,0,0,0,0,0,0,0,0,0,0,0,0,0)';$S;
    'VDDCR_CPU1_DH23':'(0,0,0,0,0,0,0,0,0,0,0,0,0,0,0,0,0,0,0,0,0,0,0,0,DH23,0,0~
,0,0,0,0,0,0,0,0,0,0,0,0,0)';$S;
    'VDDCR_CPU1_DH25':'(0,0,0,0,0,0,0,0,0,0,0,0,0,0,0,0,0,0,0,0,0,0,0,0,DH25,0,0~
,0,0,0,0,0,0,0,0,0,0,0,0,0)';$S;
    'VDDCR_CPU1_DH26':'(0,0,0,0,0,0,0,0,0,0,0,0,0,0,0,0,0,0,0,0,0,0,0,0,DH26,0,0~
,0,0,0,0,0,0,0,0,0,0,0,0,0)';$S;
    'VDDCR_CPU1_DH28':'(0,0,0,0,0,0,0,0,0,0,0,0,0,0,0,0,0,0,0,0,0,0,0,0,DH28,0,0~
,0,0,0,0,0,0,0,0,0,0,0,0,0)';$S;
    'VDDCR_CPU1_DH29':'(0,0,0,0,0,0,0,0,0,0,0,0,0,0,0,0,0,0,0,0,0,0,0,0,DH29,0,0~
,0,0,0,0,0,0,0,0,0,0,0,0,0)';$S;
    'VDDCR_CPU1_DH31':'(0,0,0,0,0,0,0,0,0,0,0,0,0,0,0,0,0,0,0,0,0,0,0,0,DH31,0,0~
,0,0,0,0,0,0,0,0,0,0,0,0,0)';$S;
    'VDDCR_CPU1_DH32':'(0,0,0,0,0,0,0,0,0,0,0,0,0,0,0,0,0,0,0,0,0,0,0,0,DH32,0,0~
,0,0,0,0,0,0,0,0,0,0,0,0,0)';$S;
    'VDDCR_CPU1_DH34':'(0,0,0,0,0,0,0,0,0,0,0,0,0,0,0,0,0,0,0,0,0,0,0,0,DH34,0,0~
,0,0,0,0,0,0,0,0,0,0,0,0,0)';$S;
    'VDDCR_CPU1_DH35':'(0,0,0,0,0,0,0,0,0,0,0,0,0,0,0,0,0,0,0,0,0,0,0,0,DH35,0,0~
,0,0,0,0,0,0,0,0,0,0,0,0,0)';$S;
    'VDDCR_CPU1_DH41':'(0,0,0,0,0,0,0,0,0,0,0,0,0,0,0,0,0,0,0,0,0,0,0,0,DH41,0,0~
,0,0,0,0,0,0,0,0,0,0,0,0,0)';$S;
    'VDDCR_CPU1_DH42':'(0,0,0,0,0,0,0,0,0,0,0,0,0,0,0,0,0,0,0,0,0,0,0,0,DH42,0,0~
,0,0,0,0,0,0,0,0,0,0,0,0,0)';$S;
    'VDDCR_CPU1_DH44':'(0,0,0,0,0,0,0,0,0,0,0,0,0,0,0,0,0,0,0,0,0,0,0,0,DH44,0,0~
,0,0,0,0,0,0,0,0,0,0,0,0,0)';$S;
    'VDDCR_CPU1_DH53':'(0,0,0,0,0,0,0,0,0,0,0,0,0,0,0,0,0,0,0,0,0,0,0,0,DH53,0,0~
,0,0,0,0,0,0,0,0,0,0,0,0,0)';$S;
    'VDDCR_CPU1_DH54':'(0,0,0,0,0,0,0,0,0,0,0,0,0,0,0,0,0,0,0,0,0,0,0,0,DH54,0,0~
,0,0,0,0,0,0,0,0,0,0,0,0,0)';$S;
    'VDDCR_CPU1_DH56':'(0,0,0,0,0,0,0,0,0,0,0,0,0,0,0,0,0,0,0,0,0,0,0,0,DH56,0,0~
,0,0,0,0,0,0,0,0,0,0,0,0,0)';$S;
    'VDDCR_CPU1_DH57':'(0,0,0,0,0,0,0,0,0,0,0,0,0,0,0,0,0,0,0,0,0,0,0,0,DH57,0,0~
,0,0,0,0,0,0,0,0,0,0,0,0,0)';$S;
    'VDDCR_CPU1_DH45':'(0,0,0,0,0,0,0,0,0,0,0,0,0,0,0,0,0,0,0,0,0,0,0,0,DH45,0,0~
,0,0,0,0,0,0,0,0,0,0,0,0,0)';$S;
    'VDDCR_CPU1_DH47':'(0,0,0,0,0,0,0,0,0,0,0,0,0,0,0,0,0,0,0,0,0,0,0,0,DH47,0,0~
,0,0,0,0,0,0,0,0,0,0,0,0,0)';$S;
    'VDDCR_CPU1_DH48':'(0,0,0,0,0,0,0,0,0,0,0,0,0,0,0,0,0,0,0,0,0,0,0,0,DH48,0,0~
,0,0,0,0,0,0,0,0,0,0,0,0,0)';$S;
    'VDDCR_CPU1_DH50':'(0,0,0,0,0,0,0,0,0,0,0,0,0,0,0,0,0,0,0,0,0,0,0,0,DH50,0,0~
,0,0,0,0,0,0,0,0,0,0,0,0,0)';$S;
    'VDDCR_CPU1_DH51':'(0,0,0,0,0,0,0,0,0,0,0,0,0,0,0,0,0,0,0,0,0,0,0,0,DH51,0,0~
,0,0,0,0,0,0,0,0,0,0,0,0,0)';$S;
    'VDDCR_CPU1_BP24':'(0,0,0,0,0,0,0,0,0,0,0,0,0,0,0,0,0,0,0,0,0,0,0,0,BP24,0,0~
,0,0,0,0,0,0,0,0,0,0,0,0,0)';$S;
    'VDDCR_CPU1_BP28':'(0,0,0,0,0,0,0,0,0,0,0,0,0,0,0,0,0,0,0,0,0,0,0,0,BP28,0,0~
,0,0,0,0,0,0,0,0,0,0,0,0,0)';$S;
    'VDDCR_CPU1_BP32':'(0,0,0,0,0,0,0,0,0,0,0,0,0,0,0,0,0,0,0,0,0,0,0,0,BP32,0,0~
,0,0,0,0,0,0,0,0,0,0,0,0,0)';$S;
    'VDDCR_CPU1_BN27':'(0,0,0,0,0,0,0,0,0,0,0,0,0,0,0,0,0,0,0,0,0,0,0,0,BN27,0,0~
,0,0,0,0,0,0,0,0,0,0,0,0,0)';$S;
    'VDDCR_CPU1_BN35':'(0,0,0,0,0,0,0,0,0,0,0,0,0,0,0,0,0,0,0,0,0,0,0,0,BN35,0,0~
,0,0,0,0,0,0,0,0,0,0,0,0,0)';$S;
    'VDDCR_CPU1_BN46':'(0,0,0,0,0,0,0,0,0,0,0,0,0,0,0,0,0,0,0,0,0,0,0,0,BN46,0,0~
,0,0,0,0,0,0,0,0,0,0,0,0,0)';$S;
    'VDDCR_SOC_B5':'(0,0,0,0,0,0,0,0,0,0,0,0,0,0,0,0,0,0,0,0,0,0,0,0,0,B5,0,0,0,~
0,0,0,0,0,0,0,0,0,0,0)';$S;
    'VDDCR_SOC_C4':'(0,0,0,0,0,0,0,0,0,0,0,0,0,0,0,0,0,0,0,0,0,0,0,0,0,C4,0,0,0,~
0,0,0,0,0,0,0,0,0,0,0)';$S;
    'VDDCR_SOC_E4':'(0,0,0,0,0,0,0,0,0,0,0,0,0,0,0,0,0,0,0,0,0,0,0,0,0,E4,0,0,0,~
0,0,0,0,0,0,0,0,0,0,0)';$S;
    'VDDCR_SOC_E11':'(0,0,0,0,0,0,0,0,0,0,0,0,0,0,0,0,0,0,0,0,0,0,0,0,0,E11,0,0,~
0,0,0,0,0,0,0,0,0,0,0,0)';$S;
    'VDDCR_SOC_H5':'(0,0,0,0,0,0,0,0,0,0,0,0,0,0,0,0,0,0,0,0,0,0,0,0,0,H5,0,0,0,~
0,0,0,0,0,0,0,0,0,0,0)';$S;
    'VDDCR_SOC_H12':'(0,0,0,0,0,0,0,0,0,0,0,0,0,0,0,0,0,0,0,0,0,0,0,0,0,H12,0,0,~
0,0,0,0,0,0,0,0,0,0,0,0)';$S;
    'VDDCR_SOC_H19':'(0,0,0,0,0,0,0,0,0,0,0,0,0,0,0,0,0,0,0,0,0,0,0,0,0,H19,0,0,~
0,0,0,0,0,0,0,0,0,0,0,0)';$S;
    'VDDCR_SOC_K22':'(0,0,0,0,0,0,0,0,0,0,0,0,0,0,0,0,0,0,0,0,0,0,0,0,0,K22,0,0,~
0,0,0,0,0,0,0,0,0,0,0,0)';$S;
    'VDDCR_SOC_L4':'(0,0,0,0,0,0,0,0,0,0,0,0,0,0,0,0,0,0,0,0,0,0,0,0,0,L4,0,0,0,~
0,0,0,0,0,0,0,0,0,0,0)';$S;
    'VDDCR_SOC_L11':'(0,0,0,0,0,0,0,0,0,0,0,0,0,0,0,0,0,0,0,0,0,0,0,0,0,L11,0,0,~
0,0,0,0,0,0,0,0,0,0,0,0)';$S;
    'VDDCR_SOC_L18':'(0,0,0,0,0,0,0,0,0,0,0,0,0,0,0,0,0,0,0,0,0,0,0,0,0,L18,0,0,~
0,0,0,0,0,0,0,0,0,0,0,0)';$S;
    'VDDCR_SOC_P5':'(0,0,0,0,0,0,0,0,0,0,0,0,0,0,0,0,0,0,0,0,0,0,0,0,0,P5,0,0,0,~
0,0,0,0,0,0,0,0,0,0,0)';$S;
    'VDDCR_SOC_P12':'(0,0,0,0,0,0,0,0,0,0,0,0,0,0,0,0,0,0,0,0,0,0,0,0,0,P12,0,0,~
0,0,0,0,0,0,0,0,0,0,0,0)';$S;
    'VDDCR_SOC_P19':'(0,0,0,0,0,0,0,0,0,0,0,0,0,0,0,0,0,0,0,0,0,0,0,0,0,P19,0,0,~
0,0,0,0,0,0,0,0,0,0,0,0)';$S;
    'VDDCR_SOC_P22':'(0,0,0,0,0,0,0,0,0,0,0,0,0,0,0,0,0,0,0,0,0,0,0,0,0,P22,0,0,~
0,0,0,0,0,0,0,0,0,0,0,0)';$S;
    'VDDCR_SOC_U4':'(0,0,0,0,0,0,0,0,0,0,0,0,0,0,0,0,0,0,0,0,0,0,0,0,0,U4,0,0,0,~
0,0,0,0,0,0,0,0,0,0,0)';$S;
    'VDDCR_SOC_U11':'(0,0,0,0,0,0,0,0,0,0,0,0,0,0,0,0,0,0,0,0,0,0,0,0,0,U11,0,0,~
0,0,0,0,0,0,0,0,0,0,0,0)';$S;
    'VDDCR_SOC_U18':'(0,0,0,0,0,0,0,0,0,0,0,0,0,0,0,0,0,0,0,0,0,0,0,0,0,U18,0,0,~
0,0,0,0,0,0,0,0,0,0,0,0)';$S;
    'VDDCR_SOC_V22':'(0,0,0,0,0,0,0,0,0,0,0,0,0,0,0,0,0,0,0,0,0,0,0,0,0,V22,0,0,~
0,0,0,0,0,0,0,0,0,0,0,0)';$S;
    'VDDCR_SOC_Y5':'(0,0,0,0,0,0,0,0,0,0,0,0,0,0,0,0,0,0,0,0,0,0,0,0,0,Y5,0,0,0,~
0,0,0,0,0,0,0,0,0,0,0)';$S;
    'VDDCR_SOC_Y12':'(0,0,0,0,0,0,0,0,0,0,0,0,0,0,0,0,0,0,0,0,0,0,0,0,0,Y12,0,0,~
0,0,0,0,0,0,0,0,0,0,0,0)';$S;
    'VDDCR_SOC_Y19':'(0,0,0,0,0,0,0,0,0,0,0,0,0,0,0,0,0,0,0,0,0,0,0,0,0,Y19,0,0,~
0,0,0,0,0,0,0,0,0,0,0,0)';$S;
    'VDDCR_SOC_AA22':'(0,0,0,0,0,0,0,0,0,0,0,0,0,0,0,0,0,0,0,0,0,0,0,0,0,AA22,0,~
0,0,0,0,0,0,0,0,0,0,0,0,0)';$S;
    'VDDCR_SOC_AC4':'(0,0,0,0,0,0,0,0,0,0,0,0,0,0,0,0,0,0,0,0,0,0,0,0,0,AC4,0,0,~
0,0,0,0,0,0,0,0,0,0,0,0)';$S;
    'VDDCR_SOC_AC11':'(0,0,0,0,0,0,0,0,0,0,0,0,0,0,0,0,0,0,0,0,0,0,0,0,0,AC11,0,~
0,0,0,0,0,0,0,0,0,0,0,0,0)';$S;
    'VDDCR_SOC_AC18':'(0,0,0,0,0,0,0,0,0,0,0,0,0,0,0,0,0,0,0,0,0,0,0,0,0,AC18,0,~
0,0,0,0,0,0,0,0,0,0,0,0,0)';$S;
    'VDDCR_SOC_AD22':'(0,0,0,0,0,0,0,0,0,0,0,0,0,0,0,0,0,0,0,0,0,0,0,0,0,AD22,0,~
0,0,0,0,0,0,0,0,0,0,0,0,0)';$S;
    'VDDCR_SOC_AF5':'(0,0,0,0,0,0,0,0,0,0,0,0,0,0,0,0,0,0,0,0,0,0,0,0,0,AF5,0,0,~
0,0,0,0,0,0,0,0,0,0,0,0)';$S;
    'VDDCR_SOC_AF12':'(0,0,0,0,0,0,0,0,0,0,0,0,0,0,0,0,0,0,0,0,0,0,0,0,0,AF12,0,~
0,0,0,0,0,0,0,0,0,0,0,0,0)';$S;
    'VDDCR_SOC_AF19':'(0,0,0,0,0,0,0,0,0,0,0,0,0,0,0,0,0,0,0,0,0,0,0,0,0,AF19,0,~
0,0,0,0,0,0,0,0,0,0,0,0,0)';$S;
    'VDDCR_SOC_AH22':'(0,0,0,0,0,0,0,0,0,0,0,0,0,0,0,0,0,0,0,0,0,0,0,0,0,AH22,0,~
0,0,0,0,0,0,0,0,0,0,0,0,0)';$S;
    'VDDCR_SOC_AJ4':'(0,0,0,0,0,0,0,0,0,0,0,0,0,0,0,0,0,0,0,0,0,0,0,0,0,AJ4,0,0,~
0,0,0,0,0,0,0,0,0,0,0,0)';$S;
    'VDDCR_SOC_AJ11':'(0,0,0,0,0,0,0,0,0,0,0,0,0,0,0,0,0,0,0,0,0,0,0,0,0,AJ11,0,~
0,0,0,0,0,0,0,0,0,0,0,0,0)';$S;
    'VDDCR_SOC_AJ18':'(0,0,0,0,0,0,0,0,0,0,0,0,0,0,0,0,0,0,0,0,0,0,0,0,0,AJ18,0,~
0,0,0,0,0,0,0,0,0,0,0,0,0)';$S;
    'VDDCR_SOC_AM5':'(0,0,0,0,0,0,0,0,0,0,0,0,0,0,0,0,0,0,0,0,0,0,0,0,0,AM5,0,0,~
0,0,0,0,0,0,0,0,0,0,0,0)';$S;
    'VDDCR_SOC_AM12':'(0,0,0,0,0,0,0,0,0,0,0,0,0,0,0,0,0,0,0,0,0,0,0,0,0,AM12,0,~
0,0,0,0,0,0,0,0,0,0,0,0,0)';$S;
    'VDDCR_SOC_AM19':'(0,0,0,0,0,0,0,0,0,0,0,0,0,0,0,0,0,0,0,0,0,0,0,0,0,AM19,0,~
0,0,0,0,0,0,0,0,0,0,0,0,0)';$S;
    'VDDCR_SOC_AM22':'(0,0,0,0,0,0,0,0,0,0,0,0,0,0,0,0,0,0,0,0,0,0,0,0,0,AM22,0,~
0,0,0,0,0,0,0,0,0,0,0,0,0)';$S;
    'VDDCR_SOC_AR4':'(0,0,0,0,0,0,0,0,0,0,0,0,0,0,0,0,0,0,0,0,0,0,0,0,0,AR4,0,0,~
0,0,0,0,0,0,0,0,0,0,0,0)';$S;
    'VDDCR_SOC_AR11':'(0,0,0,0,0,0,0,0,0,0,0,0,0,0,0,0,0,0,0,0,0,0,0,0,0,AR11,0,~
0,0,0,0,0,0,0,0,0,0,0,0,0)';$S;
    'VDDCR_SOC_AR18':'(0,0,0,0,0,0,0,0,0,0,0,0,0,0,0,0,0,0,0,0,0,0,0,0,0,AR18,0,~
0,0,0,0,0,0,0,0,0,0,0,0,0)';$S;
    'VDDCR_SOC_AT22':'(0,0,0,0,0,0,0,0,0,0,0,0,0,0,0,0,0,0,0,0,0,0,0,0,0,AT22,0,~
0,0,0,0,0,0,0,0,0,0,0,0,0)';$S;
    'VDDCR_SOC_AU23':'(0,0,0,0,0,0,0,0,0,0,0,0,0,0,0,0,0,0,0,0,0,0,0,0,0,AU23,0,~
0,0,0,0,0,0,0,0,0,0,0,0,0)';$S;
    'VDDCR_SOC_AU27':'(0,0,0,0,0,0,0,0,0,0,0,0,0,0,0,0,0,0,0,0,0,0,0,0,0,AU27,0,~
0,0,0,0,0,0,0,0,0,0,0,0,0)';$S;
    'VDDCR_SOC_AU31':'(0,0,0,0,0,0,0,0,0,0,0,0,0,0,0,0,0,0,0,0,0,0,0,0,0,AU31,0,~
0,0,0,0,0,0,0,0,0,0,0,0,0)';$S;
    'VDDCR_SOC_AU35':'(0,0,0,0,0,0,0,0,0,0,0,0,0,0,0,0,0,0,0,0,0,0,0,0,0,AU35,0,~
0,0,0,0,0,0,0,0,0,0,0,0,0)';$S;
    'VDDCR_SOC_AU40':'(0,0,0,0,0,0,0,0,0,0,0,0,0,0,0,0,0,0,0,0,0,0,0,0,0,AU40,0,~
0,0,0,0,0,0,0,0,0,0,0,0,0)';$S;
    'VDDCR_SOC_AV5':'(0,0,0,0,0,0,0,0,0,0,0,0,0,0,0,0,0,0,0,0,0,0,0,0,0,AV5,0,0,~
0,0,0,0,0,0,0,0,0,0,0,0)';$S;
    'VDDCR_SOC_AV12':'(0,0,0,0,0,0,0,0,0,0,0,0,0,0,0,0,0,0,0,0,0,0,0,0,0,AV12,0,~
0,0,0,0,0,0,0,0,0,0,0,0,0)';$S;
    'VDDCR_SOC_AV19':'(0,0,0,0,0,0,0,0,0,0,0,0,0,0,0,0,0,0,0,0,0,0,0,0,0,AV19,0,~
0,0,0,0,0,0,0,0,0,0,0,0,0)';$S;
    'VDDCR_SOC_AV22':'(0,0,0,0,0,0,0,0,0,0,0,0,0,0,0,0,0,0,0,0,0,0,0,0,0,AV22,0,~
0,0,0,0,0,0,0,0,0,0,0,0,0)';$S;
    'VDDCR_SOC_AV24':'(0,0,0,0,0,0,0,0,0,0,0,0,0,0,0,0,0,0,0,0,0,0,0,0,0,AV24,0,~
0,0,0,0,0,0,0,0,0,0,0,0,0)';$S;
    'VDDCR_SOC_AV26':'(0,0,0,0,0,0,0,0,0,0,0,0,0,0,0,0,0,0,0,0,0,0,0,0,0,AV26,0,~
0,0,0,0,0,0,0,0,0,0,0,0,0)';$S;
    'VDDCR_SOC_AV28':'(0,0,0,0,0,0,0,0,0,0,0,0,0,0,0,0,0,0,0,0,0,0,0,0,0,AV28,0,~
0,0,0,0,0,0,0,0,0,0,0,0,0)';$S;
    'VDDCR_SOC_AV30':'(0,0,0,0,0,0,0,0,0,0,0,0,0,0,0,0,0,0,0,0,0,0,0,0,0,AV30,0,~
0,0,0,0,0,0,0,0,0,0,0,0,0)';$S;
    'VDDCR_SOC_AV32':'(0,0,0,0,0,0,0,0,0,0,0,0,0,0,0,0,0,0,0,0,0,0,0,0,0,AV32,0,~
0,0,0,0,0,0,0,0,0,0,0,0,0)';$S;
    'VDDCR_SOC_AV34':'(0,0,0,0,0,0,0,0,0,0,0,0,0,0,0,0,0,0,0,0,0,0,0,0,0,AV34,0,~
0,0,0,0,0,0,0,0,0,0,0,0,0)';$S;
    'VDDCR_SOC_AV36':'(0,0,0,0,0,0,0,0,0,0,0,0,0,0,0,0,0,0,0,0,0,0,0,0,0,AV36,0,~
0,0,0,0,0,0,0,0,0,0,0,0,0)';$S;
    'VDDCR_SOC_AV39':'(0,0,0,0,0,0,0,0,0,0,0,0,0,0,0,0,0,0,0,0,0,0,0,0,0,AV39,0,~
0,0,0,0,0,0,0,0,0,0,0,0,0)';$S;
    'VDDCR_SOC_AV41':'(0,0,0,0,0,0,0,0,0,0,0,0,0,0,0,0,0,0,0,0,0,0,0,0,0,AV41,0,~
0,0,0,0,0,0,0,0,0,0,0,0,0)';$S;
    'VDDCR_SOC_AV43':'(0,0,0,0,0,0,0,0,0,0,0,0,0,0,0,0,0,0,0,0,0,0,0,0,0,AV43,0,~
0,0,0,0,0,0,0,0,0,0,0,0,0)';$S;
    'VDDCR_SOC_AV45':'(0,0,0,0,0,0,0,0,0,0,0,0,0,0,0,0,0,0,0,0,0,0,0,0,0,AV45,0,~
0,0,0,0,0,0,0,0,0,0,0,0,0)';$S;
    'VDDCR_SOC_AV47':'(0,0,0,0,0,0,0,0,0,0,0,0,0,0,0,0,0,0,0,0,0,0,0,0,0,AV47,0,~
0,0,0,0,0,0,0,0,0,0,0,0,0)';$S;
    'VDDCR_SOC_AW23':'(0,0,0,0,0,0,0,0,0,0,0,0,0,0,0,0,0,0,0,0,0,0,0,0,0,AW23,0,~
0,0,0,0,0,0,0,0,0,0,0,0,0)';$S;
    'VDDCR_SOC_AW25':'(0,0,0,0,0,0,0,0,0,0,0,0,0,0,0,0,0,0,0,0,0,0,0,0,0,AW25,0,~
0,0,0,0,0,0,0,0,0,0,0,0,0)';$S;
    'VDDCR_SOC_AW27':'(0,0,0,0,0,0,0,0,0,0,0,0,0,0,0,0,0,0,0,0,0,0,0,0,0,AW27,0,~
0,0,0,0,0,0,0,0,0,0,0,0,0)';$S;
    'VDDCR_SOC_AW48':'(0,0,0,0,0,0,0,0,0,0,0,0,0,0,0,0,0,0,0,0,0,0,0,0,0,AW48,0,~
0,0,0,0,0,0,0,0,0,0,0,0,0)';$S;
    'VDDCR_SOC_AY22':'(0,0,0,0,0,0,0,0,0,0,0,0,0,0,0,0,0,0,0,0,0,0,0,0,0,AY22,0,~
0,0,0,0,0,0,0,0,0,0,0,0,0)';$S;
    'VDDCR_SOC_AY24':'(0,0,0,0,0,0,0,0,0,0,0,0,0,0,0,0,0,0,0,0,0,0,0,0,0,AY24,0,~
0,0,0,0,0,0,0,0,0,0,0,0,0)';$S;
    'VDDCR_SOC_AY26':'(0,0,0,0,0,0,0,0,0,0,0,0,0,0,0,0,0,0,0,0,0,0,0,0,0,AY26,0,~
0,0,0,0,0,0,0,0,0,0,0,0,0)';$S;
    'VDDCR_SOC_AY28':'(0,0,0,0,0,0,0,0,0,0,0,0,0,0,0,0,0,0,0,0,0,0,0,0,0,AY28,0,~
0,0,0,0,0,0,0,0,0,0,0,0,0)';$S;
    'VDDCR_SOC_AY49':'(0,0,0,0,0,0,0,0,0,0,0,0,0,0,0,0,0,0,0,0,0,0,0,0,0,AY49,0,~
0,0,0,0,0,0,0,0,0,0,0,0,0)';$S;
    'VDDCR_SOC_BA4':'(0,0,0,0,0,0,0,0,0,0,0,0,0,0,0,0,0,0,0,0,0,0,0,0,0,BA4,0,0,~
0,0,0,0,0,0,0,0,0,0,0,0)';$S;
    'VDDCR_SOC_BA11':'(0,0,0,0,0,0,0,0,0,0,0,0,0,0,0,0,0,0,0,0,0,0,0,0,0,BA11,0,~
0,0,0,0,0,0,0,0,0,0,0,0,0)';$S;
    'VDDCR_SOC_BA18':'(0,0,0,0,0,0,0,0,0,0,0,0,0,0,0,0,0,0,0,0,0,0,0,0,0,BA18,0,~
0,0,0,0,0,0,0,0,0,0,0,0,0)';$S;
    'VDDCR_SOC_BA23':'(0,0,0,0,0,0,0,0,0,0,0,0,0,0,0,0,0,0,0,0,0,0,0,0,0,BA23,0,~
0,0,0,0,0,0,0,0,0,0,0,0,0)';$S;
    'VDDCR_SOC_BA25':'(0,0,0,0,0,0,0,0,0,0,0,0,0,0,0,0,0,0,0,0,0,0,0,0,0,BA25,0,~
0,0,0,0,0,0,0,0,0,0,0,0,0)';$S;
    'VDDCR_SOC_BA27':'(0,0,0,0,0,0,0,0,0,0,0,0,0,0,0,0,0,0,0,0,0,0,0,0,0,BA27,0,~
0,0,0,0,0,0,0,0,0,0,0,0,0)';$S;
    'VDDCR_SOC_BA48':'(0,0,0,0,0,0,0,0,0,0,0,0,0,0,0,0,0,0,0,0,0,0,0,0,0,BA48,0,~
0,0,0,0,0,0,0,0,0,0,0,0,0)';$S;
    'VDDCR_SOC_BB22':'(0,0,0,0,0,0,0,0,0,0,0,0,0,0,0,0,0,0,0,0,0,0,0,0,0,BB22,0,~
0,0,0,0,0,0,0,0,0,0,0,0,0)';$S;
    'VDDCR_SOC_BB24':'(0,0,0,0,0,0,0,0,0,0,0,0,0,0,0,0,0,0,0,0,0,0,0,0,0,BB24,0,~
0,0,0,0,0,0,0,0,0,0,0,0,0)';$S;
    'VDDCR_SOC_BB26':'(0,0,0,0,0,0,0,0,0,0,0,0,0,0,0,0,0,0,0,0,0,0,0,0,0,BB26,0,~
0,0,0,0,0,0,0,0,0,0,0,0,0)';$S;
    'VDDCR_SOC_BB28':'(0,0,0,0,0,0,0,0,0,0,0,0,0,0,0,0,0,0,0,0,0,0,0,0,0,BB28,0,~
0,0,0,0,0,0,0,0,0,0,0,0,0)';$S;
    'VDDCR_SOC_BB49':'(0,0,0,0,0,0,0,0,0,0,0,0,0,0,0,0,0,0,0,0,0,0,0,0,0,BB49,0,~
0,0,0,0,0,0,0,0,0,0,0,0,0)';$S;
    'VDDCR_SOC_BC23':'(0,0,0,0,0,0,0,0,0,0,0,0,0,0,0,0,0,0,0,0,0,0,0,0,0,BC23,0,~
0,0,0,0,0,0,0,0,0,0,0,0,0)';$S;
    'VDDCR_SOC_BC25':'(0,0,0,0,0,0,0,0,0,0,0,0,0,0,0,0,0,0,0,0,0,0,0,0,0,BC25,0,~
0,0,0,0,0,0,0,0,0,0,0,0,0)';$S;
    'VDDCR_SOC_BC27':'(0,0,0,0,0,0,0,0,0,0,0,0,0,0,0,0,0,0,0,0,0,0,0,0,0,BC27,0,~
0,0,0,0,0,0,0,0,0,0,0,0,0)';$S;
    'VDDCR_SOC_BC48':'(0,0,0,0,0,0,0,0,0,0,0,0,0,0,0,0,0,0,0,0,0,0,0,0,0,BC48,0,~
0,0,0,0,0,0,0,0,0,0,0,0,0)';$S;
    'VDDCR_SOC_BD5':'(0,0,0,0,0,0,0,0,0,0,0,0,0,0,0,0,0,0,0,0,0,0,0,0,0,BD5,0,0,~
0,0,0,0,0,0,0,0,0,0,0,0)';$S;
    'VDDCR_SOC_BD12':'(0,0,0,0,0,0,0,0,0,0,0,0,0,0,0,0,0,0,0,0,0,0,0,0,0,BD12,0,~
0,0,0,0,0,0,0,0,0,0,0,0,0)';$S;
    'VDDCR_SOC_BD19':'(0,0,0,0,0,0,0,0,0,0,0,0,0,0,0,0,0,0,0,0,0,0,0,0,0,BD19,0,~
0,0,0,0,0,0,0,0,0,0,0,0,0)';$S;
    'VDDCR_SOC_BD22':'(0,0,0,0,0,0,0,0,0,0,0,0,0,0,0,0,0,0,0,0,0,0,0,0,0,BD22,0,~
0,0,0,0,0,0,0,0,0,0,0,0,0)';$S;
    'VDDCR_SOC_BD24':'(0,0,0,0,0,0,0,0,0,0,0,0,0,0,0,0,0,0,0,0,0,0,0,0,0,BD24,0,~
0,0,0,0,0,0,0,0,0,0,0,0,0)';$S;
    'VDDCR_SOC_BD26':'(0,0,0,0,0,0,0,0,0,0,0,0,0,0,0,0,0,0,0,0,0,0,0,0,0,BD26,0,~
0,0,0,0,0,0,0,0,0,0,0,0,0)';$S;
    'VDDCR_SOC_BD28':'(0,0,0,0,0,0,0,0,0,0,0,0,0,0,0,0,0,0,0,0,0,0,0,0,0,BD28,0,~
0,0,0,0,0,0,0,0,0,0,0,0,0)';$S;
    'VDDCR_SOC_BD48':'(0,0,0,0,0,0,0,0,0,0,0,0,0,0,0,0,0,0,0,0,0,0,0,0,0,BD48,0,~
0,0,0,0,0,0,0,0,0,0,0,0,0)';$S;
    'VDDCR_SOC_BF23':'(0,0,0,0,0,0,0,0,0,0,0,0,0,0,0,0,0,0,0,0,0,0,0,0,0,BF23,0,~
0,0,0,0,0,0,0,0,0,0,0,0,0)';$S;
    'VDDCR_SOC_BF25':'(0,0,0,0,0,0,0,0,0,0,0,0,0,0,0,0,0,0,0,0,0,0,0,0,0,BF25,0,~
0,0,0,0,0,0,0,0,0,0,0,0,0)';$S;
    'VDDCR_SOC_BF27':'(0,0,0,0,0,0,0,0,0,0,0,0,0,0,0,0,0,0,0,0,0,0,0,0,0,BF27,0,~
0,0,0,0,0,0,0,0,0,0,0,0,0)';$S;
    'VDDCR_SOC_BF48':'(0,0,0,0,0,0,0,0,0,0,0,0,0,0,0,0,0,0,0,0,0,0,0,0,0,BF48,0,~
0,0,0,0,0,0,0,0,0,0,0,0,0)';$S;
    'VDDCR_SOC_BM5':'(0,0,0,0,0,0,0,0,0,0,0,0,0,0,0,0,0,0,0,0,0,0,0,0,0,BM5,0,0,~
0,0,0,0,0,0,0,0,0,0,0,0)';$S;
    'VDDCR_SOC_BJ48':'(0,0,0,0,0,0,0,0,0,0,0,0,0,0,0,0,0,0,0,0,0,0,0,0,0,BJ48,0,~
0,0,0,0,0,0,0,0,0,0,0,0,0)';$S;
    'VDDCR_SOC_BJ11':'(0,0,0,0,0,0,0,0,0,0,0,0,0,0,0,0,0,0,0,0,0,0,0,0,0,BJ11,0,~
0,0,0,0,0,0,0,0,0,0,0,0,0)';$S;
    'VDDCR_SOC_BJ4':'(0,0,0,0,0,0,0,0,0,0,0,0,0,0,0,0,0,0,0,0,0,0,0,0,0,BJ4,0,0,~
0,0,0,0,0,0,0,0,0,0,0,0)';$S;
    'VDDCR_SOC_BH48':'(0,0,0,0,0,0,0,0,0,0,0,0,0,0,0,0,0,0,0,0,0,0,0,0,0,BH48,0,~
0,0,0,0,0,0,0,0,0,0,0,0,0)';$S;
    'VDDCR_SOC_BH25':'(0,0,0,0,0,0,0,0,0,0,0,0,0,0,0,0,0,0,0,0,0,0,0,0,0,BH25,0,~
0,0,0,0,0,0,0,0,0,0,0,0,0)';$S;
    'VDDCR_SOC_BH23':'(0,0,0,0,0,0,0,0,0,0,0,0,0,0,0,0,0,0,0,0,0,0,0,0,0,BH23,0,~
0,0,0,0,0,0,0,0,0,0,0,0,0)';$S;
    'VDDCR_SOC_BG48':'(0,0,0,0,0,0,0,0,0,0,0,0,0,0,0,0,0,0,0,0,0,0,0,0,0,BG48,0,~
0,0,0,0,0,0,0,0,0,0,0,0,0)';$S;
    'VDDCR_SOC_BG28':'(0,0,0,0,0,0,0,0,0,0,0,0,0,0,0,0,0,0,0,0,0,0,0,0,0,BG28,0,~
0,0,0,0,0,0,0,0,0,0,0,0,0)';$S;
    'VDDCR_SOC_BG26':'(0,0,0,0,0,0,0,0,0,0,0,0,0,0,0,0,0,0,0,0,0,0,0,0,0,BG26,0,~
0,0,0,0,0,0,0,0,0,0,0,0,0)';$S;
    'VDDCR_SOC_BG24':'(0,0,0,0,0,0,0,0,0,0,0,0,0,0,0,0,0,0,0,0,0,0,0,0,0,BG24,0,~
0,0,0,0,0,0,0,0,0,0,0,0,0)';$S;
    'VDDCR_SOC_BG22':'(0,0,0,0,0,0,0,0,0,0,0,0,0,0,0,0,0,0,0,0,0,0,0,0,0,BG22,0,~
0,0,0,0,0,0,0,0,0,0,0,0,0)';$S;
    'VDDIO_H57':'(0,0,0,0,0,0,0,0,0,0,0,0,0,0,0,0,0,0,0,0,0,0,0,0,0,0,H57,0,0,0,~
0,0,0,0,0,0,0,0,0,0)';$S;
    'VDDIO_H64':'(0,0,0,0,0,0,0,0,0,0,0,0,0,0,0,0,0,0,0,0,0,0,0,0,0,0,H64,0,0,0,~
0,0,0,0,0,0,0,0,0,0)';$S;
    'VDDIO_H71':'(0,0,0,0,0,0,0,0,0,0,0,0,0,0,0,0,0,0,0,0,0,0,0,0,0,0,H71,0,0,0,~
0,0,0,0,0,0,0,0,0,0)';$S;
    'VDDIO_K54':'(0,0,0,0,0,0,0,0,0,0,0,0,0,0,0,0,0,0,0,0,0,0,0,0,0,0,K54,0,0,0,~
0,0,0,0,0,0,0,0,0,0)';$S;
    'VDDIO_L58':'(0,0,0,0,0,0,0,0,0,0,0,0,0,0,0,0,0,0,0,0,0,0,0,0,0,0,L58,0,0,0,~
0,0,0,0,0,0,0,0,0,0)';$S;
    'VDDIO_L65':'(0,0,0,0,0,0,0,0,0,0,0,0,0,0,0,0,0,0,0,0,0,0,0,0,0,0,L65,0,0,0,~
0,0,0,0,0,0,0,0,0,0)';$S;
    'VDDIO_L72':'(0,0,0,0,0,0,0,0,0,0,0,0,0,0,0,0,0,0,0,0,0,0,0,0,0,0,L72,0,0,0,~
0,0,0,0,0,0,0,0,0,0)';$S;
    'VDDIO_P54':'(0,0,0,0,0,0,0,0,0,0,0,0,0,0,0,0,0,0,0,0,0,0,0,0,0,0,P54,0,0,0,~
0,0,0,0,0,0,0,0,0,0)';$S;
    'VDDIO_P57':'(0,0,0,0,0,0,0,0,0,0,0,0,0,0,0,0,0,0,0,0,0,0,0,0,0,0,P57,0,0,0,~
0,0,0,0,0,0,0,0,0,0)';$S;
    'VDDIO_P64':'(0,0,0,0,0,0,0,0,0,0,0,0,0,0,0,0,0,0,0,0,0,0,0,0,0,0,P64,0,0,0,~
0,0,0,0,0,0,0,0,0,0)';$S;
    'VDDIO_P71':'(0,0,0,0,0,0,0,0,0,0,0,0,0,0,0,0,0,0,0,0,0,0,0,0,0,0,P71,0,0,0,~
0,0,0,0,0,0,0,0,0,0)';$S;
    'VDDIO_U58':'(0,0,0,0,0,0,0,0,0,0,0,0,0,0,0,0,0,0,0,0,0,0,0,0,0,0,U58,0,0,0,~
0,0,0,0,0,0,0,0,0,0)';$S;
    'VDDIO_U65':'(0,0,0,0,0,0,0,0,0,0,0,0,0,0,0,0,0,0,0,0,0,0,0,0,0,0,U65,0,0,0,~
0,0,0,0,0,0,0,0,0,0)';$S;
    'VDDIO_U72':'(0,0,0,0,0,0,0,0,0,0,0,0,0,0,0,0,0,0,0,0,0,0,0,0,0,0,U72,0,0,0,~
0,0,0,0,0,0,0,0,0,0)';$S;
    'VDDIO_V54':'(0,0,0,0,0,0,0,0,0,0,0,0,0,0,0,0,0,0,0,0,0,0,0,0,0,0,V54,0,0,0,~
0,0,0,0,0,0,0,0,0,0)';$S;
    'VDDIO_Y57':'(0,0,0,0,0,0,0,0,0,0,0,0,0,0,0,0,0,0,0,0,0,0,0,0,0,0,Y57,0,0,0,~
0,0,0,0,0,0,0,0,0,0)';$S;
    'VDDIO_Y64':'(0,0,0,0,0,0,0,0,0,0,0,0,0,0,0,0,0,0,0,0,0,0,0,0,0,0,Y64,0,0,0,~
0,0,0,0,0,0,0,0,0,0)';$S;
    'VDDIO_Y71':'(0,0,0,0,0,0,0,0,0,0,0,0,0,0,0,0,0,0,0,0,0,0,0,0,0,0,Y71,0,0,0,~
0,0,0,0,0,0,0,0,0,0)';$S;
    'VDDIO_AA54':'(0,0,0,0,0,0,0,0,0,0,0,0,0,0,0,0,0,0,0,0,0,0,0,0,0,0,AA54,0,0,~
0,0,0,0,0,0,0,0,0,0,0)';$S;
    'VDDIO_AC58':'(0,0,0,0,0,0,0,0,0,0,0,0,0,0,0,0,0,0,0,0,0,0,0,0,0,0,AC58,0,0,~
0,0,0,0,0,0,0,0,0,0,0)';$S;
    'VDDIO_AC65':'(0,0,0,0,0,0,0,0,0,0,0,0,0,0,0,0,0,0,0,0,0,0,0,0,0,0,AC65,0,0,~
0,0,0,0,0,0,0,0,0,0,0)';$S;
    'VDDIO_AC72':'(0,0,0,0,0,0,0,0,0,0,0,0,0,0,0,0,0,0,0,0,0,0,0,0,0,0,AC72,0,0,~
0,0,0,0,0,0,0,0,0,0,0)';$S;
    'VDDIO_AD54':'(0,0,0,0,0,0,0,0,0,0,0,0,0,0,0,0,0,0,0,0,0,0,0,0,0,0,AD54,0,0,~
0,0,0,0,0,0,0,0,0,0,0)';$S;
    'VDDIO_AF57':'(0,0,0,0,0,0,0,0,0,0,0,0,0,0,0,0,0,0,0,0,0,0,0,0,0,0,AF57,0,0,~
0,0,0,0,0,0,0,0,0,0,0)';$S;
    'VDDIO_AF64':'(0,0,0,0,0,0,0,0,0,0,0,0,0,0,0,0,0,0,0,0,0,0,0,0,0,0,AF64,0,0,~
0,0,0,0,0,0,0,0,0,0,0)';$S;
    'VDDIO_AF71':'(0,0,0,0,0,0,0,0,0,0,0,0,0,0,0,0,0,0,0,0,0,0,0,0,0,0,AF71,0,0,~
0,0,0,0,0,0,0,0,0,0,0)';$S;
    'VDDIO_AH54':'(0,0,0,0,0,0,0,0,0,0,0,0,0,0,0,0,0,0,0,0,0,0,0,0,0,0,AH54,0,0,~
0,0,0,0,0,0,0,0,0,0,0)';$S;
    'VDDIO_AJ58':'(0,0,0,0,0,0,0,0,0,0,0,0,0,0,0,0,0,0,0,0,0,0,0,0,0,0,AJ58,0,0,~
0,0,0,0,0,0,0,0,0,0,0)';$S;
    'VDDIO_AJ65':'(0,0,0,0,0,0,0,0,0,0,0,0,0,0,0,0,0,0,0,0,0,0,0,0,0,0,AJ65,0,0,~
0,0,0,0,0,0,0,0,0,0,0)';$S;
    'VDDIO_AJ72':'(0,0,0,0,0,0,0,0,0,0,0,0,0,0,0,0,0,0,0,0,0,0,0,0,0,0,AJ72,0,0,~
0,0,0,0,0,0,0,0,0,0,0)';$S;
    'VDDIO_AM54':'(0,0,0,0,0,0,0,0,0,0,0,0,0,0,0,0,0,0,0,0,0,0,0,0,0,0,AM54,0,0,~
0,0,0,0,0,0,0,0,0,0,0)';$S;
    'VDDIO_AM57':'(0,0,0,0,0,0,0,0,0,0,0,0,0,0,0,0,0,0,0,0,0,0,0,0,0,0,AM57,0,0,~
0,0,0,0,0,0,0,0,0,0,0)';$S;
    'VDDIO_AM64':'(0,0,0,0,0,0,0,0,0,0,0,0,0,0,0,0,0,0,0,0,0,0,0,0,0,0,AM64,0,0,~
0,0,0,0,0,0,0,0,0,0,0)';$S;
    'VDDIO_AM71':'(0,0,0,0,0,0,0,0,0,0,0,0,0,0,0,0,0,0,0,0,0,0,0,0,0,0,AM71,0,0,~
0,0,0,0,0,0,0,0,0,0,0)';$S;
    'VDDIO_AR58':'(0,0,0,0,0,0,0,0,0,0,0,0,0,0,0,0,0,0,0,0,0,0,0,0,0,0,AR58,0,0,~
0,0,0,0,0,0,0,0,0,0,0)';$S;
    'VDDIO_AR65':'(0,0,0,0,0,0,0,0,0,0,0,0,0,0,0,0,0,0,0,0,0,0,0,0,0,0,AR65,0,0,~
0,0,0,0,0,0,0,0,0,0,0)';$S;
    'VDDIO_AR72':'(0,0,0,0,0,0,0,0,0,0,0,0,0,0,0,0,0,0,0,0,0,0,0,0,0,0,AR72,0,0,~
0,0,0,0,0,0,0,0,0,0,0)';$S;
    'VDDIO_AV57':'(0,0,0,0,0,0,0,0,0,0,0,0,0,0,0,0,0,0,0,0,0,0,0,0,0,0,AV57,0,0,~
0,0,0,0,0,0,0,0,0,0,0)';$S;
    'VDDIO_AV64':'(0,0,0,0,0,0,0,0,0,0,0,0,0,0,0,0,0,0,0,0,0,0,0,0,0,0,AV64,0,0,~
0,0,0,0,0,0,0,0,0,0,0)';$S;
    'VDDIO_AV71':'(0,0,0,0,0,0,0,0,0,0,0,0,0,0,0,0,0,0,0,0,0,0,0,0,0,0,AV71,0,0,~
0,0,0,0,0,0,0,0,0,0,0)';$S;
    'VDDIO_BA58':'(0,0,0,0,0,0,0,0,0,0,0,0,0,0,0,0,0,0,0,0,0,0,0,0,0,0,BA58,0,0,~
0,0,0,0,0,0,0,0,0,0,0)';$S;
    'VDDIO_BA65':'(0,0,0,0,0,0,0,0,0,0,0,0,0,0,0,0,0,0,0,0,0,0,0,0,0,0,BA65,0,0,~
0,0,0,0,0,0,0,0,0,0,0)';$S;
    'VDDIO_BA72':'(0,0,0,0,0,0,0,0,0,0,0,0,0,0,0,0,0,0,0,0,0,0,0,0,0,0,BA72,0,0,~
0,0,0,0,0,0,0,0,0,0,0)';$S;
    'VDDIO_BD50':'(0,0,0,0,0,0,0,0,0,0,0,0,0,0,0,0,0,0,0,0,0,0,0,0,0,0,BD50,0,0,~
0,0,0,0,0,0,0,0,0,0,0)';$S;
    'VDDIO_BD52':'(0,0,0,0,0,0,0,0,0,0,0,0,0,0,0,0,0,0,0,0,0,0,0,0,0,0,BD52,0,0,~
0,0,0,0,0,0,0,0,0,0,0)';$S;
    'VDDIO_BD54':'(0,0,0,0,0,0,0,0,0,0,0,0,0,0,0,0,0,0,0,0,0,0,0,0,0,0,BD54,0,0,~
0,0,0,0,0,0,0,0,0,0,0)';$S;
    'VDDIO_BF51':'(0,0,0,0,0,0,0,0,0,0,0,0,0,0,0,0,0,0,0,0,0,0,0,0,0,0,BF51,0,0,~
0,0,0,0,0,0,0,0,0,0,0)';$S;
    'VDDIO_BF53':'(0,0,0,0,0,0,0,0,0,0,0,0,0,0,0,0,0,0,0,0,0,0,0,0,0,0,BF53,0,0,~
0,0,0,0,0,0,0,0,0,0,0)';$S;
    'VDDIO_BF57':'(0,0,0,0,0,0,0,0,0,0,0,0,0,0,0,0,0,0,0,0,0,0,0,0,0,0,BF57,0,0,~
0,0,0,0,0,0,0,0,0,0,0)';$S;
    'VDDIO_BF64':'(0,0,0,0,0,0,0,0,0,0,0,0,0,0,0,0,0,0,0,0,0,0,0,0,0,0,BF64,0,0,~
0,0,0,0,0,0,0,0,0,0,0)';$S;
    'VDDIO_BF71':'(0,0,0,0,0,0,0,0,0,0,0,0,0,0,0,0,0,0,0,0,0,0,0,0,0,0,BF71,0,0,~
0,0,0,0,0,0,0,0,0,0,0)';$S;
    'VDDIO_BG50':'(0,0,0,0,0,0,0,0,0,0,0,0,0,0,0,0,0,0,0,0,0,0,0,0,0,0,BG50,0,0,~
0,0,0,0,0,0,0,0,0,0,0)';$S;
    'VDDIO_BG52':'(0,0,0,0,0,0,0,0,0,0,0,0,0,0,0,0,0,0,0,0,0,0,0,0,0,0,BG52,0,0,~
0,0,0,0,0,0,0,0,0,0,0)';$S;
    'VDDIO_BG54':'(0,0,0,0,0,0,0,0,0,0,0,0,0,0,0,0,0,0,0,0,0,0,0,0,0,0,BG54,0,0,~
0,0,0,0,0,0,0,0,0,0,0)';$S;
    'VDDIO_BH51':'(0,0,0,0,0,0,0,0,0,0,0,0,0,0,0,0,0,0,0,0,0,0,0,0,0,0,BH51,0,0,~
0,0,0,0,0,0,0,0,0,0,0)';$S;
    'VDDIO_BH53':'(0,0,0,0,0,0,0,0,0,0,0,0,0,0,0,0,0,0,0,0,0,0,0,0,0,0,BH53,0,0,~
0,0,0,0,0,0,0,0,0,0,0)';$S;
    'VDDIO_BJ50':'(0,0,0,0,0,0,0,0,0,0,0,0,0,0,0,0,0,0,0,0,0,0,0,0,0,0,BJ50,0,0,~
0,0,0,0,0,0,0,0,0,0,0)';$S;
    'VDDIO_BJ52':'(0,0,0,0,0,0,0,0,0,0,0,0,0,0,0,0,0,0,0,0,0,0,0,0,0,0,BJ52,0,0,~
0,0,0,0,0,0,0,0,0,0,0)';$S;
    'VDDIO_BJ54':'(0,0,0,0,0,0,0,0,0,0,0,0,0,0,0,0,0,0,0,0,0,0,0,0,0,0,BJ54,0,0,~
0,0,0,0,0,0,0,0,0,0,0)';$S;
    'VDDIO_BJ58':'(0,0,0,0,0,0,0,0,0,0,0,0,0,0,0,0,0,0,0,0,0,0,0,0,0,0,BJ58,0,0,~
0,0,0,0,0,0,0,0,0,0,0)';$S;
    'VDDIO_BJ65':'(0,0,0,0,0,0,0,0,0,0,0,0,0,0,0,0,0,0,0,0,0,0,0,0,0,0,BJ65,0,0,~
0,0,0,0,0,0,0,0,0,0,0)';$S;
    'VDDIO_BJ72':'(0,0,0,0,0,0,0,0,0,0,0,0,0,0,0,0,0,0,0,0,0,0,0,0,0,0,BJ72,0,0,~
0,0,0,0,0,0,0,0,0,0,0)';$S;
    'VDDIO_BK51':'(0,0,0,0,0,0,0,0,0,0,0,0,0,0,0,0,0,0,0,0,0,0,0,0,0,0,BK51,0,0,~
0,0,0,0,0,0,0,0,0,0,0)';$S;
    'VDDIO_BK53':'(0,0,0,0,0,0,0,0,0,0,0,0,0,0,0,0,0,0,0,0,0,0,0,0,0,0,BK53,0,0,~
0,0,0,0,0,0,0,0,0,0,0)';$S;
    'VDDIO_BL50':'(0,0,0,0,0,0,0,0,0,0,0,0,0,0,0,0,0,0,0,0,0,0,0,0,0,0,BL50,0,0,~
0,0,0,0,0,0,0,0,0,0,0)';$S;
    'VDDIO_BL52':'(0,0,0,0,0,0,0,0,0,0,0,0,0,0,0,0,0,0,0,0,0,0,0,0,0,0,BL52,0,0,~
0,0,0,0,0,0,0,0,0,0,0)';$S;
    'VDDIO_BL54':'(0,0,0,0,0,0,0,0,0,0,0,0,0,0,0,0,0,0,0,0,0,0,0,0,0,0,BL54,0,0,~
0,0,0,0,0,0,0,0,0,0,0)';$S;
    'VDDIO_BM51':'(0,0,0,0,0,0,0,0,0,0,0,0,0,0,0,0,0,0,0,0,0,0,0,0,0,0,BM51,0,0,~
0,0,0,0,0,0,0,0,0,0,0)';$S;
    'VDDIO_BM53':'(0,0,0,0,0,0,0,0,0,0,0,0,0,0,0,0,0,0,0,0,0,0,0,0,0,0,BM53,0,0,~
0,0,0,0,0,0,0,0,0,0,0)';$S;
    'VDDIO_BM57':'(0,0,0,0,0,0,0,0,0,0,0,0,0,0,0,0,0,0,0,0,0,0,0,0,0,0,BM57,0,0,~
0,0,0,0,0,0,0,0,0,0,0)';$S;
    'VDDIO_BM64':'(0,0,0,0,0,0,0,0,0,0,0,0,0,0,0,0,0,0,0,0,0,0,0,0,0,0,BM64,0,0,~
0,0,0,0,0,0,0,0,0,0,0)';$S;
    'VDDIO_BM71':'(0,0,0,0,0,0,0,0,0,0,0,0,0,0,0,0,0,0,0,0,0,0,0,0,0,0,BM71,0,0,~
0,0,0,0,0,0,0,0,0,0,0)';$S;
    'VDDIO_BN54':'(0,0,0,0,0,0,0,0,0,0,0,0,0,0,0,0,0,0,0,0,0,0,0,0,0,0,BN54,0,0,~
0,0,0,0,0,0,0,0,0,0,0)';$S;
    'VDDIO_BR58':'(0,0,0,0,0,0,0,0,0,0,0,0,0,0,0,0,0,0,0,0,0,0,0,0,0,0,BR58,0,0,~
0,0,0,0,0,0,0,0,0,0,0)';$S;
    'VDDIO_BR65':'(0,0,0,0,0,0,0,0,0,0,0,0,0,0,0,0,0,0,0,0,0,0,0,0,0,0,BR65,0,0,~
0,0,0,0,0,0,0,0,0,0,0)';$S;
    'VDDIO_BR72':'(0,0,0,0,0,0,0,0,0,0,0,0,0,0,0,0,0,0,0,0,0,0,0,0,0,0,BR72,0,0,~
0,0,0,0,0,0,0,0,0,0,0)';$S;
    'VDDIO_BV54':'(0,0,0,0,0,0,0,0,0,0,0,0,0,0,0,0,0,0,0,0,0,0,0,0,0,0,BV54,0,0,~
0,0,0,0,0,0,0,0,0,0,0)';$S;
    'VDDIO_BV57':'(0,0,0,0,0,0,0,0,0,0,0,0,0,0,0,0,0,0,0,0,0,0,0,0,0,0,BV57,0,0,~
0,0,0,0,0,0,0,0,0,0,0)';$S;
    'VDDIO_BV64':'(0,0,0,0,0,0,0,0,0,0,0,0,0,0,0,0,0,0,0,0,0,0,0,0,0,0,BV64,0,0,~
0,0,0,0,0,0,0,0,0,0,0)';$S;
    'VDDIO_BV71':'(0,0,0,0,0,0,0,0,0,0,0,0,0,0,0,0,0,0,0,0,0,0,0,0,0,0,BV71,0,0,~
0,0,0,0,0,0,0,0,0,0,0)';$S;
    'VDDIO_CA58':'(0,0,0,0,0,0,0,0,0,0,0,0,0,0,0,0,0,0,0,0,0,0,0,0,0,0,CA58,0,0,~
0,0,0,0,0,0,0,0,0,0,0)';$S;
    'VDDIO_CA65':'(0,0,0,0,0,0,0,0,0,0,0,0,0,0,0,0,0,0,0,0,0,0,0,0,0,0,CA65,0,0,~
0,0,0,0,0,0,0,0,0,0,0)';$S;
    'VDDIO_CA72':'(0,0,0,0,0,0,0,0,0,0,0,0,0,0,0,0,0,0,0,0,0,0,0,0,0,0,CA72,0,0,~
0,0,0,0,0,0,0,0,0,0,0)';$S;
    'VDDIO_CB54':'(0,0,0,0,0,0,0,0,0,0,0,0,0,0,0,0,0,0,0,0,0,0,0,0,0,0,CB54,0,0,~
0,0,0,0,0,0,0,0,0,0,0)';$S;
    'VDDIO_CD57':'(0,0,0,0,0,0,0,0,0,0,0,0,0,0,0,0,0,0,0,0,0,0,0,0,0,0,CD57,0,0,~
0,0,0,0,0,0,0,0,0,0,0)';$S;
    'VDDIO_CD64':'(0,0,0,0,0,0,0,0,0,0,0,0,0,0,0,0,0,0,0,0,0,0,0,0,0,0,CD64,0,0,~
0,0,0,0,0,0,0,0,0,0,0)';$S;
    'VDDIO_CD71':'(0,0,0,0,0,0,0,0,0,0,0,0,0,0,0,0,0,0,0,0,0,0,0,0,0,0,CD71,0,0,~
0,0,0,0,0,0,0,0,0,0,0)';$S;
    'VDDIO_CF54':'(0,0,0,0,0,0,0,0,0,0,0,0,0,0,0,0,0,0,0,0,0,0,0,0,0,0,CF54,0,0,~
0,0,0,0,0,0,0,0,0,0,0)';$S;
    'VDDIO_CG58':'(0,0,0,0,0,0,0,0,0,0,0,0,0,0,0,0,0,0,0,0,0,0,0,0,0,0,CG58,0,0,~
0,0,0,0,0,0,0,0,0,0,0)';$S;
    'VDDIO_CG65':'(0,0,0,0,0,0,0,0,0,0,0,0,0,0,0,0,0,0,0,0,0,0,0,0,0,0,CG65,0,0,~
0,0,0,0,0,0,0,0,0,0,0)';$S;
    'VDDIO_CG72':'(0,0,0,0,0,0,0,0,0,0,0,0,0,0,0,0,0,0,0,0,0,0,0,0,0,0,CG72,0,0,~
0,0,0,0,0,0,0,0,0,0,0)';$S;
    'VDDIO_CJ54':'(0,0,0,0,0,0,0,0,0,0,0,0,0,0,0,0,0,0,0,0,0,0,0,0,0,0,CJ54,0,0,~
0,0,0,0,0,0,0,0,0,0,0)';$S;
    'VDDIO_CK57':'(0,0,0,0,0,0,0,0,0,0,0,0,0,0,0,0,0,0,0,0,0,0,0,0,0,0,CK57,0,0,~
0,0,0,0,0,0,0,0,0,0,0)';$S;
    'VDDIO_CK64':'(0,0,0,0,0,0,0,0,0,0,0,0,0,0,0,0,0,0,0,0,0,0,0,0,0,0,CK64,0,0,~
0,0,0,0,0,0,0,0,0,0,0)';$S;
    'VDDIO_CK71':'(0,0,0,0,0,0,0,0,0,0,0,0,0,0,0,0,0,0,0,0,0,0,0,0,0,0,CK71,0,0,~
0,0,0,0,0,0,0,0,0,0,0)';$S;
    'VDDIO_CM54':'(0,0,0,0,0,0,0,0,0,0,0,0,0,0,0,0,0,0,0,0,0,0,0,0,0,0,CM54,0,0,~
0,0,0,0,0,0,0,0,0,0,0)';$S;
    'VDDIO_CN58':'(0,0,0,0,0,0,0,0,0,0,0,0,0,0,0,0,0,0,0,0,0,0,0,0,0,0,CN58,0,0,~
0,0,0,0,0,0,0,0,0,0,0)';$S;
    'VDDIO_CN65':'(0,0,0,0,0,0,0,0,0,0,0,0,0,0,0,0,0,0,0,0,0,0,0,0,0,0,CN65,0,0,~
0,0,0,0,0,0,0,0,0,0,0)';$S;
    'VDDIO_CN72':'(0,0,0,0,0,0,0,0,0,0,0,0,0,0,0,0,0,0,0,0,0,0,0,0,0,0,CN72,0,0,~
0,0,0,0,0,0,0,0,0,0,0)';$S;
    'VDDIO_CT54':'(0,0,0,0,0,0,0,0,0,0,0,0,0,0,0,0,0,0,0,0,0,0,0,0,0,0,CT54,0,0,~
0,0,0,0,0,0,0,0,0,0,0)';$S;
    'VDDIO_CT57':'(0,0,0,0,0,0,0,0,0,0,0,0,0,0,0,0,0,0,0,0,0,0,0,0,0,0,CT57,0,0,~
0,0,0,0,0,0,0,0,0,0,0)';$S;
    'VDD_11_S3_BJ18':'(0,0,0,0,0,0,0,0,0,0,0,0,0,0,0,0,0,0,0,0,0,0,0,0,0,0,BJ18,~
0,0,0,0,0,0,0,0,0,0,0,0,0)';$S;
    'VDD_11_S3_BJ23':'(0,0,0,0,0,0,0,0,0,0,0,0,0,0,0,0,0,0,0,0,0,0,0,0,0,0,BJ23,~
0,0,0,0,0,0,0,0,0,0,0,0,0)';$S;
    'VDD_11_S3_BJ25':'(0,0,0,0,0,0,0,0,0,0,0,0,0,0,0,0,0,0,0,0,0,0,0,0,0,0,BJ25,~
0,0,0,0,0,0,0,0,0,0,0,0,0)';$S;
    'VDD_11_S3_BJ27':'(0,0,0,0,0,0,0,0,0,0,0,0,0,0,0,0,0,0,0,0,0,0,0,0,0,0,BJ27,~
0,0,0,0,0,0,0,0,0,0,0,0,0)';$S;
    'VDD_11_S3_BK22':'(0,0,0,0,0,0,0,0,0,0,0,0,0,0,0,0,0,0,0,0,0,0,0,0,0,0,BK22,~
0,0,0,0,0,0,0,0,0,0,0,0,0)';$S;
    'VDD_11_S3_BK24':'(0,0,0,0,0,0,0,0,0,0,0,0,0,0,0,0,0,0,0,0,0,0,0,0,0,0,BK24,~
0,0,0,0,0,0,0,0,0,0,0,0,0)';$S;
    'VDD_11_S3_BK26':'(0,0,0,0,0,0,0,0,0,0,0,0,0,0,0,0,0,0,0,0,0,0,0,0,0,0,BK26,~
0,0,0,0,0,0,0,0,0,0,0,0,0)';$S;
    'VDD_11_S3_BK28':'(0,0,0,0,0,0,0,0,0,0,0,0,0,0,0,0,0,0,0,0,0,0,0,0,0,0,BK28,~
0,0,0,0,0,0,0,0,0,0,0,0,0)';$S;
    'VDD_11_S3_BK49':'(0,0,0,0,0,0,0,0,0,0,0,0,0,0,0,0,0,0,0,0,0,0,0,0,0,0,BK49,~
0,0,0,0,0,0,0,0,0,0,0,0,0)';$S;
    'VDD_11_S3_BL23':'(0,0,0,0,0,0,0,0,0,0,0,0,0,0,0,0,0,0,0,0,0,0,0,0,0,0,BL23,~
0,0,0,0,0,0,0,0,0,0,0,0,0)';$S;
    'VDD_11_S3_BL25':'(0,0,0,0,0,0,0,0,0,0,0,0,0,0,0,0,0,0,0,0,0,0,0,0,0,0,BL25,~
0,0,0,0,0,0,0,0,0,0,0,0,0)';$S;
    'VDD_11_S3_BL27':'(0,0,0,0,0,0,0,0,0,0,0,0,0,0,0,0,0,0,0,0,0,0,0,0,0,0,BL27,~
0,0,0,0,0,0,0,0,0,0,0,0,0)';$S;
    'VDD_11_S3_BL48':'(0,0,0,0,0,0,0,0,0,0,0,0,0,0,0,0,0,0,0,0,0,0,0,0,0,0,BL48,~
0,0,0,0,0,0,0,0,0,0,0,0,0)';$S;
    'VDD_11_S3_BM12':'(0,0,0,0,0,0,0,0,0,0,0,0,0,0,0,0,0,0,0,0,0,0,0,0,0,0,BM12,~
0,0,0,0,0,0,0,0,0,0,0,0,0)';$S;
    'VDD_11_S3_BM19':'(0,0,0,0,0,0,0,0,0,0,0,0,0,0,0,0,0,0,0,0,0,0,0,0,0,0,BM19,~
0,0,0,0,0,0,0,0,0,0,0,0,0)';$S;
    'VDD_11_S3_BM22':'(0,0,0,0,0,0,0,0,0,0,0,0,0,0,0,0,0,0,0,0,0,0,0,0,0,0,BM22,~
0,0,0,0,0,0,0,0,0,0,0,0,0)';$S;
    'VDD_11_S3_BM24':'(0,0,0,0,0,0,0,0,0,0,0,0,0,0,0,0,0,0,0,0,0,0,0,0,0,0,BM24,~
0,0,0,0,0,0,0,0,0,0,0,0,0)';$S;
    'VDD_11_S3_BM26':'(0,0,0,0,0,0,0,0,0,0,0,0,0,0,0,0,0,0,0,0,0,0,0,0,0,0,BM26,~
0,0,0,0,0,0,0,0,0,0,0,0,0)';$S;
    'VDD_11_S3_BM28':'(0,0,0,0,0,0,0,0,0,0,0,0,0,0,0,0,0,0,0,0,0,0,0,0,0,0,BM28,~
0,0,0,0,0,0,0,0,0,0,0,0,0)';$S;
    'VDD_11_S3_BM30':'(0,0,0,0,0,0,0,0,0,0,0,0,0,0,0,0,0,0,0,0,0,0,0,0,0,0,BM30,~
0,0,0,0,0,0,0,0,0,0,0,0,0)';$S;
    'VDD_11_S3_BM32':'(0,0,0,0,0,0,0,0,0,0,0,0,0,0,0,0,0,0,0,0,0,0,0,0,0,0,BM32,~
0,0,0,0,0,0,0,0,0,0,0,0,0)';$S;
    'VDD_11_S3_BM34':'(0,0,0,0,0,0,0,0,0,0,0,0,0,0,0,0,0,0,0,0,0,0,0,0,0,0,BM34,~
0,0,0,0,0,0,0,0,0,0,0,0,0)';$S;
    'VDD_11_S3_BM36':'(0,0,0,0,0,0,0,0,0,0,0,0,0,0,0,0,0,0,0,0,0,0,0,0,0,0,BM36,~
0,0,0,0,0,0,0,0,0,0,0,0,0)';$S;
    'VDD_11_S3_BM39':'(0,0,0,0,0,0,0,0,0,0,0,0,0,0,0,0,0,0,0,0,0,0,0,0,0,0,BM39,~
0,0,0,0,0,0,0,0,0,0,0,0,0)';$S;
    'VDD_11_S3_BM41':'(0,0,0,0,0,0,0,0,0,0,0,0,0,0,0,0,0,0,0,0,0,0,0,0,0,0,BM41,~
0,0,0,0,0,0,0,0,0,0,0,0,0)';$S;
    'VDD_11_S3_BM43':'(0,0,0,0,0,0,0,0,0,0,0,0,0,0,0,0,0,0,0,0,0,0,0,0,0,0,BM43,~
0,0,0,0,0,0,0,0,0,0,0,0,0)';$S;
    'VDD_11_S3_BM45':'(0,0,0,0,0,0,0,0,0,0,0,0,0,0,0,0,0,0,0,0,0,0,0,0,0,0,BM45,~
0,0,0,0,0,0,0,0,0,0,0,0,0)';$S;
    'VDD_11_S3_BM47':'(0,0,0,0,0,0,0,0,0,0,0,0,0,0,0,0,0,0,0,0,0,0,0,0,0,0,BM47,~
0,0,0,0,0,0,0,0,0,0,0,0,0)';$S;
    'VDD_11_S3_BM49':'(0,0,0,0,0,0,0,0,0,0,0,0,0,0,0,0,0,0,0,0,0,0,0,0,0,0,BM49,~
0,0,0,0,0,0,0,0,0,0,0,0,0)';$S;
    'VDD_11_S3_BN25':'(0,0,0,0,0,0,0,0,0,0,0,0,0,0,0,0,0,0,0,0,0,0,0,0,0,0,BN25,~
0,0,0,0,0,0,0,0,0,0,0,0,0)';$S;
    'VDD_11_S3_BN29':'(0,0,0,0,0,0,0,0,0,0,0,0,0,0,0,0,0,0,0,0,0,0,0,0,0,0,BN29,~
0,0,0,0,0,0,0,0,0,0,0,0,0)';$S;
    'VDD_11_S3_BN33':'(0,0,0,0,0,0,0,0,0,0,0,0,0,0,0,0,0,0,0,0,0,0,0,0,0,0,BN33,~
0,0,0,0,0,0,0,0,0,0,0,0,0)';$S;
    'VDD_11_S3_BN40':'(0,0,0,0,0,0,0,0,0,0,0,0,0,0,0,0,0,0,0,0,0,0,0,0,0,0,BN40,~
0,0,0,0,0,0,0,0,0,0,0,0,0)';$S;
    'VDD_11_S3_BN44':'(0,0,0,0,0,0,0,0,0,0,0,0,0,0,0,0,0,0,0,0,0,0,0,0,0,0,BN44,~
0,0,0,0,0,0,0,0,0,0,0,0,0)';$S;
    'VDD_11_S3_BN48':'(0,0,0,0,0,0,0,0,0,0,0,0,0,0,0,0,0,0,0,0,0,0,0,0,0,0,BN48,~
0,0,0,0,0,0,0,0,0,0,0,0,0)';$S;
    'VDD_11_S3_BP22':'(0,0,0,0,0,0,0,0,0,0,0,0,0,0,0,0,0,0,0,0,0,0,0,0,0,0,BP22,~
0,0,0,0,0,0,0,0,0,0,0,0,0)';$S;
    'VDD_11_S3_BR4':'(0,0,0,0,0,0,0,0,0,0,0,0,0,0,0,0,0,0,0,0,0,0,0,0,0,0,BR4,0,~
0,0,0,0,0,0,0,0,0,0,0,0)';$S;
    'VDD_11_S3_BR11':'(0,0,0,0,0,0,0,0,0,0,0,0,0,0,0,0,0,0,0,0,0,0,0,0,0,0,BR11,~
0,0,0,0,0,0,0,0,0,0,0,0,0)';$S;
    'VDD_11_S3_BR18':'(0,0,0,0,0,0,0,0,0,0,0,0,0,0,0,0,0,0,0,0,0,0,0,0,0,0,BR18,~
0,0,0,0,0,0,0,0,0,0,0,0,0)';$S;
    'VDD_11_S3_BV5':'(0,0,0,0,0,0,0,0,0,0,0,0,0,0,0,0,0,0,0,0,0,0,0,0,0,0,BV5,0,~
0,0,0,0,0,0,0,0,0,0,0,0)';$S;
    'VDD_11_S3_BV12':'(0,0,0,0,0,0,0,0,0,0,0,0,0,0,0,0,0,0,0,0,0,0,0,0,0,0,BV12,~
0,0,0,0,0,0,0,0,0,0,0,0,0)';$S;
    'VDD_11_S3_BV19':'(0,0,0,0,0,0,0,0,0,0,0,0,0,0,0,0,0,0,0,0,0,0,0,0,0,0,BV19,~
0,0,0,0,0,0,0,0,0,0,0,0,0)';$S;
    'VDD_11_S3_BV22':'(0,0,0,0,0,0,0,0,0,0,0,0,0,0,0,0,0,0,0,0,0,0,0,0,0,0,BV22,~
0,0,0,0,0,0,0,0,0,0,0,0,0)';$S;
    'VDD_11_S3_CA4':'(0,0,0,0,0,0,0,0,0,0,0,0,0,0,0,0,0,0,0,0,0,0,0,0,0,0,CA4,0,~
0,0,0,0,0,0,0,0,0,0,0,0)';$S;
    'VDD_11_S3_CA11':'(0,0,0,0,0,0,0,0,0,0,0,0,0,0,0,0,0,0,0,0,0,0,0,0,0,0,CA11,~
0,0,0,0,0,0,0,0,0,0,0,0,0)';$S;
    'VDD_11_S3_CA18':'(0,0,0,0,0,0,0,0,0,0,0,0,0,0,0,0,0,0,0,0,0,0,0,0,0,0,CA18,~
0,0,0,0,0,0,0,0,0,0,0,0,0)';$S;
    'VDD_11_S3_CB22':'(0,0,0,0,0,0,0,0,0,0,0,0,0,0,0,0,0,0,0,0,0,0,0,0,0,0,CB22,~
0,0,0,0,0,0,0,0,0,0,0,0,0)';$S;
    'VDD_11_S3_CD5':'(0,0,0,0,0,0,0,0,0,0,0,0,0,0,0,0,0,0,0,0,0,0,0,0,0,0,CD5,0,~
0,0,0,0,0,0,0,0,0,0,0,0)';$S;
    'VDD_11_S3_CD12':'(0,0,0,0,0,0,0,0,0,0,0,0,0,0,0,0,0,0,0,0,0,0,0,0,0,0,CD12,~
0,0,0,0,0,0,0,0,0,0,0,0,0)';$S;
    'VDD_11_S3_CD19':'(0,0,0,0,0,0,0,0,0,0,0,0,0,0,0,0,0,0,0,0,0,0,0,0,0,0,CD19,~
0,0,0,0,0,0,0,0,0,0,0,0,0)';$S;
    'VDD_11_S3_CF22':'(0,0,0,0,0,0,0,0,0,0,0,0,0,0,0,0,0,0,0,0,0,0,0,0,0,0,CF22,~
0,0,0,0,0,0,0,0,0,0,0,0,0)';$S;
    'VDD_11_S3_CG4':'(0,0,0,0,0,0,0,0,0,0,0,0,0,0,0,0,0,0,0,0,0,0,0,0,0,0,CG4,0,~
0,0,0,0,0,0,0,0,0,0,0,0)';$S;
    'VDD_11_S3_CG11':'(0,0,0,0,0,0,0,0,0,0,0,0,0,0,0,0,0,0,0,0,0,0,0,0,0,0,CG11,~
0,0,0,0,0,0,0,0,0,0,0,0,0)';$S;
    'VDD_11_S3_CG18':'(0,0,0,0,0,0,0,0,0,0,0,0,0,0,0,0,0,0,0,0,0,0,0,0,0,0,CG18,~
0,0,0,0,0,0,0,0,0,0,0,0,0)';$S;
    'VDD_11_S3_CJ22':'(0,0,0,0,0,0,0,0,0,0,0,0,0,0,0,0,0,0,0,0,0,0,0,0,0,0,CJ22,~
0,0,0,0,0,0,0,0,0,0,0,0,0)';$S;
    'VDD_11_S3_CK5':'(0,0,0,0,0,0,0,0,0,0,0,0,0,0,0,0,0,0,0,0,0,0,0,0,0,0,CK5,0,~
0,0,0,0,0,0,0,0,0,0,0,0)';$S;
    'VDD_11_S3_CK12':'(0,0,0,0,0,0,0,0,0,0,0,0,0,0,0,0,0,0,0,0,0,0,0,0,0,0,CK12,~
0,0,0,0,0,0,0,0,0,0,0,0,0)';$S;
    'VDD_11_S3_CK19':'(0,0,0,0,0,0,0,0,0,0,0,0,0,0,0,0,0,0,0,0,0,0,0,0,0,0,CK19,~
0,0,0,0,0,0,0,0,0,0,0,0,0)';$S;
    'VDD_11_S3_CM22':'(0,0,0,0,0,0,0,0,0,0,0,0,0,0,0,0,0,0,0,0,0,0,0,0,0,0,CM22,~
0,0,0,0,0,0,0,0,0,0,0,0,0)';$S;
    'VDD_11_S3_CN4':'(0,0,0,0,0,0,0,0,0,0,0,0,0,0,0,0,0,0,0,0,0,0,0,0,0,0,CN4,0,~
0,0,0,0,0,0,0,0,0,0,0,0)';$S;
    'VDD_11_S3_CN11':'(0,0,0,0,0,0,0,0,0,0,0,0,0,0,0,0,0,0,0,0,0,0,0,0,0,0,CN11,~
0,0,0,0,0,0,0,0,0,0,0,0,0)';$S;
    'VDD_11_S3_CN18':'(0,0,0,0,0,0,0,0,0,0,0,0,0,0,0,0,0,0,0,0,0,0,0,0,0,0,CN18,~
0,0,0,0,0,0,0,0,0,0,0,0,0)';$S;
    'VDD_11_S3_CT5':'(0,0,0,0,0,0,0,0,0,0,0,0,0,0,0,0,0,0,0,0,0,0,0,0,0,0,CT5,0,~
0,0,0,0,0,0,0,0,0,0,0,0)';$S;
    'VDD_18_S5_AU54':'(0,0,0,0,0,0,0,0,0,0,0,0,0,0,0,0,0,0,0,0,0,0,0,0,0,0,AU54,~
0,0,0,0,0,0,0,0,0,0,0,0,0)';$S;
    'VDD_18_S5_AR52':'(0,0,0,0,0,0,0,0,0,0,0,0,0,0,0,0,0,0,0,0,0,0,0,0,0,0,AR52,~
0,0,0,0,0,0,0,0,0,0,0,0,0)';$S;
    'VDD_18_S5_AR54':'(0,0,0,0,0,0,0,0,0,0,0,0,0,0,0,0,0,0,0,0,0,0,0,0,0,0,AR54,~
0,0,0,0,0,0,0,0,0,0,0,0,0)';$S;
    'VDD_18_S5_AT51':'(0,0,0,0,0,0,0,0,0,0,0,0,0,0,0,0,0,0,0,0,0,0,0,0,0,0,AT51,~
0,0,0,0,0,0,0,0,0,0,0,0,0)';$S;
    'VDD_18_S5_AT53':'(0,0,0,0,0,0,0,0,0,0,0,0,0,0,0,0,0,0,0,0,0,0,0,0,0,0,AT53,~
0,0,0,0,0,0,0,0,0,0,0,0,0)';$S;
    'VDD_18_S5_AU50':'(0,0,0,0,0,0,0,0,0,0,0,0,0,0,0,0,0,0,0,0,0,0,0,0,0,0,AU50,~
0,0,0,0,0,0,0,0,0,0,0,0,0)';$S;
    'VDD_18_S5_AU52':'(0,0,0,0,0,0,0,0,0,0,0,0,0,0,0,0,0,0,0,0,0,0,0,0,0,0,AU52,~
0,0,0,0,0,0,0,0,0,0,0,0,0)';$S;
    'VDD_18_S5_AV49':'(0,0,0,0,0,0,0,0,0,0,0,0,0,0,0,0,0,0,0,0,0,0,0,0,0,0,AV49,~
0,0,0,0,0,0,0,0,0,0,0,0,0)';$S;
    'VDD_18_S5_AV51':'(0,0,0,0,0,0,0,0,0,0,0,0,0,0,0,0,0,0,0,0,0,0,0,0,0,0,AV51,~
0,0,0,0,0,0,0,0,0,0,0,0,0)';$S;
    'VDD_18_S5_AV53':'(0,0,0,0,0,0,0,0,0,0,0,0,0,0,0,0,0,0,0,0,0,0,0,0,0,0,AV53,~
0,0,0,0,0,0,0,0,0,0,0,0,0)';$S;
    'VDD_18_S5_AW50':'(0,0,0,0,0,0,0,0,0,0,0,0,0,0,0,0,0,0,0,0,0,0,0,0,0,0,AW50,~
0,0,0,0,0,0,0,0,0,0,0,0,0)';$S;
    'VDD_18_S5_BC52':'(0,0,0,0,0,0,0,0,0,0,0,0,0,0,0,0,0,0,0,0,0,0,0,0,0,0,BC52,~
0,0,0,0,0,0,0,0,0,0,0,0,0)';$S;
    'VDD_18_S5_BC54':'(0,0,0,0,0,0,0,0,0,0,0,0,0,0,0,0,0,0,0,0,0,0,0,0,0,0,BC54,~
0,0,0,0,0,0,0,0,0,0,0,0,0)';$S;
    'VDD_18_S5_AW52':'(0,0,0,0,0,0,0,0,0,0,0,0,0,0,0,0,0,0,0,0,0,0,0,0,0,0,AW52,~
0,0,0,0,0,0,0,0,0,0,0,0,0)';$S;
    'VDD_18_S5_AW54':'(0,0,0,0,0,0,0,0,0,0,0,0,0,0,0,0,0,0,0,0,0,0,0,0,0,0,AW54,~
0,0,0,0,0,0,0,0,0,0,0,0,0)';$S;
    'VDD_18_S5_AY51':'(0,0,0,0,0,0,0,0,0,0,0,0,0,0,0,0,0,0,0,0,0,0,0,0,0,0,AY51,~
0,0,0,0,0,0,0,0,0,0,0,0,0)';$S;
    'VDD_18_S5_AY53':'(0,0,0,0,0,0,0,0,0,0,0,0,0,0,0,0,0,0,0,0,0,0,0,0,0,0,AY53,~
0,0,0,0,0,0,0,0,0,0,0,0,0)';$S;
    'VDD_18_S5_BA50':'(0,0,0,0,0,0,0,0,0,0,0,0,0,0,0,0,0,0,0,0,0,0,0,0,0,0,BA50,~
0,0,0,0,0,0,0,0,0,0,0,0,0)';$S;
    'VDD_18_S5_BA52':'(0,0,0,0,0,0,0,0,0,0,0,0,0,0,0,0,0,0,0,0,0,0,0,0,0,0,BA52,~
0,0,0,0,0,0,0,0,0,0,0,0,0)';$S;
    'VDD_18_S5_BA54':'(0,0,0,0,0,0,0,0,0,0,0,0,0,0,0,0,0,0,0,0,0,0,0,0,0,0,BA54,~
0,0,0,0,0,0,0,0,0,0,0,0,0)';$S;
    'VDD_18_S5_BB51':'(0,0,0,0,0,0,0,0,0,0,0,0,0,0,0,0,0,0,0,0,0,0,0,0,0,0,BB51,~
0,0,0,0,0,0,0,0,0,0,0,0,0)';$S;
    'VDD_18_S5_BB53':'(0,0,0,0,0,0,0,0,0,0,0,0,0,0,0,0,0,0,0,0,0,0,0,0,0,0,BB53,~
0,0,0,0,0,0,0,0,0,0,0,0,0)';$S;
    'VDD_11_S3_CT12':'(0,0,0,0,0,0,0,0,0,0,0,0,0,0,0,0,0,0,0,0,0,0,0,0,0,0,CT12,~
0,0,0,0,0,0,0,0,0,0,0,0,0)';$S;
    'VDD_33_S5_BN52':'(0,0,0,0,0,0,0,0,0,0,0,0,0,0,0,0,0,0,0,0,0,0,0,0,0,0,BN52,~
0,0,0,0,0,0,0,0,0,0,0,0,0)';$S;
    'VDD_33_S5_BP51':'(0,0,0,0,0,0,0,0,0,0,0,0,0,0,0,0,0,0,0,0,0,0,0,0,0,0,BP51,~
0,0,0,0,0,0,0,0,0,0,0,0,0)';$S;
    'VDDIO_AUDIO':'(0,0,0,0,0,0,0,0,0,0,0,0,0,0,0,0,0,0,0,0,0,0,0,0,0,0,BH27,0,0~
,0,0,0,0,0,0,0,0,0,0,0)';$S;
    'VDDBT_RTC_G':'(0,0,0,0,0,0,0,0,0,0,0,0,0,0,0,0,0,0,0,0,0,0,0,0,0,0,BN23,0,0~
,0,0,0,0,0,0,0,0,0,0,0)';$S;
    'VDDIO_DG71':'(0,0,0,0,0,0,0,0,0,0,0,0,0,0,0,0,0,0,0,0,0,0,0,0,0,0,DG71,0,0,~
0,0,0,0,0,0,0,0,0,0,0)';$S;
    'VDDIO_DG64':'(0,0,0,0,0,0,0,0,0,0,0,0,0,0,0,0,0,0,0,0,0,0,0,0,0,0,DG64,0,0,~
0,0,0,0,0,0,0,0,0,0,0)';$S;
    'VDDIO_DE72':'(0,0,0,0,0,0,0,0,0,0,0,0,0,0,0,0,0,0,0,0,0,0,0,0,0,0,DE72,0,0,~
0,0,0,0,0,0,0,0,0,0,0)';$S;
    'VDDIO_DE65':'(0,0,0,0,0,0,0,0,0,0,0,0,0,0,0,0,0,0,0,0,0,0,0,0,0,0,DE65,0,0,~
0,0,0,0,0,0,0,0,0,0,0)';$S;
    'VDDIO_DE58':'(0,0,0,0,0,0,0,0,0,0,0,0,0,0,0,0,0,0,0,0,0,0,0,0,0,0,DE58,0,0,~
0,0,0,0,0,0,0,0,0,0,0)';$S;
    'VDDIO_DB71':'(0,0,0,0,0,0,0,0,0,0,0,0,0,0,0,0,0,0,0,0,0,0,0,0,0,0,DB71,0,0,~
0,0,0,0,0,0,0,0,0,0,0)';$S;
    'VDDIO_DB64':'(0,0,0,0,0,0,0,0,0,0,0,0,0,0,0,0,0,0,0,0,0,0,0,0,0,0,DB64,0,0,~
0,0,0,0,0,0,0,0,0,0,0)';$S;
    'VDDIO_DB57':'(0,0,0,0,0,0,0,0,0,0,0,0,0,0,0,0,0,0,0,0,0,0,0,0,0,0,DB57,0,0,~
0,0,0,0,0,0,0,0,0,0,0)';$S;
    'VDDIO_CY54':'(0,0,0,0,0,0,0,0,0,0,0,0,0,0,0,0,0,0,0,0,0,0,0,0,0,0,CY54,0,0,~
0,0,0,0,0,0,0,0,0,0,0)';$S;
    'VDDIO_CW72':'(0,0,0,0,0,0,0,0,0,0,0,0,0,0,0,0,0,0,0,0,0,0,0,0,0,0,CW72,0,0,~
0,0,0,0,0,0,0,0,0,0,0)';$S;
    'VDDIO_CW65':'(0,0,0,0,0,0,0,0,0,0,0,0,0,0,0,0,0,0,0,0,0,0,0,0,0,0,CW65,0,0,~
0,0,0,0,0,0,0,0,0,0,0)';$S;
    'VDDIO_CW58':'(0,0,0,0,0,0,0,0,0,0,0,0,0,0,0,0,0,0,0,0,0,0,0,0,0,0,CW58,0,0,~
0,0,0,0,0,0,0,0,0,0,0)';$S;
    'VDDIO_CT71':'(0,0,0,0,0,0,0,0,0,0,0,0,0,0,0,0,0,0,0,0,0,0,0,0,0,0,CT71,0,0,~
0,0,0,0,0,0,0,0,0,0,0)';$S;
    'VDDIO_CT64':'(0,0,0,0,0,0,0,0,0,0,0,0,0,0,0,0,0,0,0,0,0,0,0,0,0,0,CT64,0,0,~
0,0,0,0,0,0,0,0,0,0,0)';$S;
    'VDD_11_S3_DG5':'(0,0,0,0,0,0,0,0,0,0,0,0,0,0,0,0,0,0,0,0,0,0,0,0,0,0,DG5,0,~
0,0,0,0,0,0,0,0,0,0,0,0)';$S;
    'VDD_11_S3_DE18':'(0,0,0,0,0,0,0,0,0,0,0,0,0,0,0,0,0,0,0,0,0,0,0,0,0,0,DE18,~
0,0,0,0,0,0,0,0,0,0,0,0,0)';$S;
    'VDD_11_S3_DE11':'(0,0,0,0,0,0,0,0,0,0,0,0,0,0,0,0,0,0,0,0,0,0,0,0,0,0,DE11,~
0,0,0,0,0,0,0,0,0,0,0,0,0)';$S;
    'VDD_11_S3_DE4':'(0,0,0,0,0,0,0,0,0,0,0,0,0,0,0,0,0,0,0,0,0,0,0,0,0,0,DE4,0,~
0,0,0,0,0,0,0,0,0,0,0,0)';$S;
    'VDD_11_S3_DB19':'(0,0,0,0,0,0,0,0,0,0,0,0,0,0,0,0,0,0,0,0,0,0,0,0,0,0,DB19,~
0,0,0,0,0,0,0,0,0,0,0,0,0)';$S;
    'VDD_11_S3_DB12':'(0,0,0,0,0,0,0,0,0,0,0,0,0,0,0,0,0,0,0,0,0,0,0,0,0,0,DB12,~
0,0,0,0,0,0,0,0,0,0,0,0,0)';$S;
    'VDD_11_S3_DB5':'(0,0,0,0,0,0,0,0,0,0,0,0,0,0,0,0,0,0,0,0,0,0,0,0,0,0,DB5,0,~
0,0,0,0,0,0,0,0,0,0,0,0)';$S;
    'VDD_11_S3_CY22':'(0,0,0,0,0,0,0,0,0,0,0,0,0,0,0,0,0,0,0,0,0,0,0,0,0,0,CY22,~
0,0,0,0,0,0,0,0,0,0,0,0,0)';$S;
    'VDD_11_S3_CW18':'(0,0,0,0,0,0,0,0,0,0,0,0,0,0,0,0,0,0,0,0,0,0,0,0,0,0,CW18,~
0,0,0,0,0,0,0,0,0,0,0,0,0)';$S;
    'VDD_11_S3_CW11':'(0,0,0,0,0,0,0,0,0,0,0,0,0,0,0,0,0,0,0,0,0,0,0,0,0,0,CW11,~
0,0,0,0,0,0,0,0,0,0,0,0,0)';$S;
    'VDD_11_S3_CW4':'(0,0,0,0,0,0,0,0,0,0,0,0,0,0,0,0,0,0,0,0,0,0,0,0,0,0,CW4,0,~
0,0,0,0,0,0,0,0,0,0,0,0)';$S;
    'VDD_11_S3_CT22':'(0,0,0,0,0,0,0,0,0,0,0,0,0,0,0,0,0,0,0,0,0,0,0,0,0,0,CT22,~
0,0,0,0,0,0,0,0,0,0,0,0,0)';$S;
    'VDD_11_S3_CT19':'(0,0,0,0,0,0,0,0,0,0,0,0,0,0,0,0,0,0,0,0,0,0,0,0,0,0,CT19,~
0,0,0,0,0,0,0,0,0,0,0,0,0)';$S;
    'VSS_H37':'(0,0,0,0,0,0,0,0,0,0,0,0,0,0,0,0,0,0,0,0,0,0,0,0,0,0,0,H37,0,0,0,~
0,0,0,0,0,0,0,0,0)';$S;
    'VSS_H39':'(0,0,0,0,0,0,0,0,0,0,0,0,0,0,0,0,0,0,0,0,0,0,0,0,0,0,0,H39,0,0,0,~
0,0,0,0,0,0,0,0,0)';$S;
    'VSS_H42':'(0,0,0,0,0,0,0,0,0,0,0,0,0,0,0,0,0,0,0,0,0,0,0,0,0,0,0,H42,0,0,0,~
0,0,0,0,0,0,0,0,0)';$S;
    'VSS_H45':'(0,0,0,0,0,0,0,0,0,0,0,0,0,0,0,0,0,0,0,0,0,0,0,0,0,0,0,H45,0,0,0,~
0,0,0,0,0,0,0,0,0)';$S;
    'VSS_H48':'(0,0,0,0,0,0,0,0,0,0,0,0,0,0,0,0,0,0,0,0,0,0,0,0,0,0,0,H48,0,0,0,~
0,0,0,0,0,0,0,0,0)';$S;
    'VSS_H51':'(0,0,0,0,0,0,0,0,0,0,0,0,0,0,0,0,0,0,0,0,0,0,0,0,0,0,0,H51,0,0,0,~
0,0,0,0,0,0,0,0,0)';$S;
    'VSS_H54':'(0,0,0,0,0,0,0,0,0,0,0,0,0,0,0,0,0,0,0,0,0,0,0,0,0,0,0,H54,0,0,0,~
0,0,0,0,0,0,0,0,0)';$S;
    'VSS_H59':'(0,0,0,0,0,0,0,0,0,0,0,0,0,0,0,0,0,0,0,0,0,0,0,0,0,0,0,H59,0,0,0,~
0,0,0,0,0,0,0,0,0)';$S;
    'VSS_H61':'(0,0,0,0,0,0,0,0,0,0,0,0,0,0,0,0,0,0,0,0,0,0,0,0,0,0,0,H61,0,0,0,~
0,0,0,0,0,0,0,0,0)';$S;
    'VSS_H66':'(0,0,0,0,0,0,0,0,0,0,0,0,0,0,0,0,0,0,0,0,0,0,0,0,0,0,0,H66,0,0,0,~
0,0,0,0,0,0,0,0,0)';$S;
    'VSS_H68':'(0,0,0,0,0,0,0,0,0,0,0,0,0,0,0,0,0,0,0,0,0,0,0,0,0,0,0,H68,0,0,0,~
0,0,0,0,0,0,0,0,0)';$S;
    'VSS_H73':'(0,0,0,0,0,0,0,0,0,0,0,0,0,0,0,0,0,0,0,0,0,0,0,0,0,0,0,H73,0,0,0,~
0,0,0,0,0,0,0,0,0)';$S;
    'VSS_J1':'(0,0,0,0,0,0,0,0,0,0,0,0,0,0,0,0,0,0,0,0,0,0,0,0,0,0,0,J1,0,0,0,0,~
0,0,0,0,0,0,0,0)';$S;
    'VSS_J4':'(0,0,0,0,0,0,0,0,0,0,0,0,0,0,0,0,0,0,0,0,0,0,0,0,0,0,0,J4,0,0,0,0,~
0,0,0,0,0,0,0,0)';$S;
    'VSS_J6':'(0,0,0,0,0,0,0,0,0,0,0,0,0,0,0,0,0,0,0,0,0,0,0,0,0,0,0,J6,0,0,0,0,~
0,0,0,0,0,0,0,0)';$S;
    'VSS_J8':'(0,0,0,0,0,0,0,0,0,0,0,0,0,0,0,0,0,0,0,0,0,0,0,0,0,0,0,J8,0,0,0,0,~
0,0,0,0,0,0,0,0)';$S;
    'VSS_J11':'(0,0,0,0,0,0,0,0,0,0,0,0,0,0,0,0,0,0,0,0,0,0,0,0,0,0,0,J11,0,0,0,~
0,0,0,0,0,0,0,0,0)';$S;
    'VSS_J13':'(0,0,0,0,0,0,0,0,0,0,0,0,0,0,0,0,0,0,0,0,0,0,0,0,0,0,0,J13,0,0,0,~
0,0,0,0,0,0,0,0,0)';$S;
    'VSS_A3':'(0,0,0,0,0,0,0,0,0,0,0,0,0,0,0,0,0,0,0,0,0,0,0,0,0,0,0,A3,0,0,0,0,~
0,0,0,0,0,0,0,0)';$S;
    'VSS_A9':'(0,0,0,0,0,0,0,0,0,0,0,0,0,0,0,0,0,0,0,0,0,0,0,0,0,0,0,A9,0,0,0,0,~
0,0,0,0,0,0,0,0)';$S;
    'VSS_A15':'(0,0,0,0,0,0,0,0,0,0,0,0,0,0,0,0,0,0,0,0,0,0,0,0,0,0,0,A15,0,0,0,~
0,0,0,0,0,0,0,0,0)';$S;
    'VSS_A21':'(0,0,0,0,0,0,0,0,0,0,0,0,0,0,0,0,0,0,0,0,0,0,0,0,0,0,0,A21,0,0,0,~
0,0,0,0,0,0,0,0,0)';$S;
    'VSS_A27':'(0,0,0,0,0,0,0,0,0,0,0,0,0,0,0,0,0,0,0,0,0,0,0,0,0,0,0,A27,0,0,0,~
0,0,0,0,0,0,0,0,0)';$S;
    'VSS_A43':'(0,0,0,0,0,0,0,0,0,0,0,0,0,0,0,0,0,0,0,0,0,0,0,0,0,0,0,A43,0,0,0,~
0,0,0,0,0,0,0,0,0)';$S;
    'VSS_A44':'(0,0,0,0,0,0,0,0,0,0,0,0,0,0,0,0,0,0,0,0,0,0,0,0,0,0,0,A44,0,0,0,~
0,0,0,0,0,0,0,0,0)';$S;
    'VSS_A47':'(0,0,0,0,0,0,0,0,0,0,0,0,0,0,0,0,0,0,0,0,0,0,0,0,0,0,0,A47,0,0,0,~
0,0,0,0,0,0,0,0,0)';$S;
    'VSS_A49':'(0,0,0,0,0,0,0,0,0,0,0,0,0,0,0,0,0,0,0,0,0,0,0,0,0,0,0,A49,0,0,0,~
0,0,0,0,0,0,0,0,0)';$S;
    'VSS_A53':'(0,0,0,0,0,0,0,0,0,0,0,0,0,0,0,0,0,0,0,0,0,0,0,0,0,0,0,A53,0,0,0,~
0,0,0,0,0,0,0,0,0)';$S;
    'VSS_A61':'(0,0,0,0,0,0,0,0,0,0,0,0,0,0,0,0,0,0,0,0,0,0,0,0,0,0,0,A61,0,0,0,~
0,0,0,0,0,0,0,0,0)';$S;
    'VSS_A67':'(0,0,0,0,0,0,0,0,0,0,0,0,0,0,0,0,0,0,0,0,0,0,0,0,0,0,0,A67,0,0,0,~
0,0,0,0,0,0,0,0,0)';$S;
    'VSS_A72':'(0,0,0,0,0,0,0,0,0,0,0,0,0,0,0,0,0,0,0,0,0,0,0,0,0,0,0,A72,0,0,0,~
0,0,0,0,0,0,0,0,0)';$S;
    'VSS_A73':'(0,0,0,0,0,0,0,0,0,0,0,0,0,0,0,0,0,0,0,0,0,0,0,0,0,0,0,A73,0,0,0,~
0,0,0,0,0,0,0,0,0)';$S;
    'VSS_B7':'(0,0,0,0,0,0,0,0,0,0,0,0,0,0,0,0,0,0,0,0,0,0,0,0,0,0,0,B7,0,0,0,0,~
0,0,0,0,0,0,0,0)';$S;
    'VSS_B8':'(0,0,0,0,0,0,0,0,0,0,0,0,0,0,0,0,0,0,0,0,0,0,0,0,0,0,0,B8,0,0,0,0,~
0,0,0,0,0,0,0,0)';$S;
    'VSS_B10':'(0,0,0,0,0,0,0,0,0,0,0,0,0,0,0,0,0,0,0,0,0,0,0,0,0,0,0,B10,0,0,0,~
0,0,0,0,0,0,0,0,0)';$S;
    'VSS_B11':'(0,0,0,0,0,0,0,0,0,0,0,0,0,0,0,0,0,0,0,0,0,0,0,0,0,0,0,B11,0,0,0,~
0,0,0,0,0,0,0,0,0)';$S;
    'VSS_B13':'(0,0,0,0,0,0,0,0,0,0,0,0,0,0,0,0,0,0,0,0,0,0,0,0,0,0,0,B13,0,0,0,~
0,0,0,0,0,0,0,0,0)';$S;
    'VSS_B18':'(0,0,0,0,0,0,0,0,0,0,0,0,0,0,0,0,0,0,0,0,0,0,0,0,0,0,0,B18,0,0,0,~
0,0,0,0,0,0,0,0,0)';$S;
    'VSS_B24':'(0,0,0,0,0,0,0,0,0,0,0,0,0,0,0,0,0,0,0,0,0,0,0,0,0,0,0,B24,0,0,0,~
0,0,0,0,0,0,0,0,0)';$S;
    'VSS_B27':'(0,0,0,0,0,0,0,0,0,0,0,0,0,0,0,0,0,0,0,0,0,0,0,0,0,0,0,B27,0,0,0,~
0,0,0,0,0,0,0,0,0)';$S;
    'VSS_B30':'(0,0,0,0,0,0,0,0,0,0,0,0,0,0,0,0,0,0,0,0,0,0,0,0,0,0,0,B30,0,0,0,~
0,0,0,0,0,0,0,0,0)';$S;
    'VSS_B33':'(0,0,0,0,0,0,0,0,0,0,0,0,0,0,0,0,0,0,0,0,0,0,0,0,0,0,0,B33,0,0,0,~
0,0,0,0,0,0,0,0,0)';$S;
    'VSS_B37':'(0,0,0,0,0,0,0,0,0,0,0,0,0,0,0,0,0,0,0,0,0,0,0,0,0,0,0,B37,0,0,0,~
0,0,0,0,0,0,0,0,0)';$S;
    'VSS_B39':'(0,0,0,0,0,0,0,0,0,0,0,0,0,0,0,0,0,0,0,0,0,0,0,0,0,0,0,B39,0,0,0,~
0,0,0,0,0,0,0,0,0)';$S;
    'VSS_B43':'(0,0,0,0,0,0,0,0,0,0,0,0,0,0,0,0,0,0,0,0,0,0,0,0,0,0,0,B43,0,0,0,~
0,0,0,0,0,0,0,0,0)';$S;
    'VSS_B46':'(0,0,0,0,0,0,0,0,0,0,0,0,0,0,0,0,0,0,0,0,0,0,0,0,0,0,0,B46,0,0,0,~
0,0,0,0,0,0,0,0,0)';$S;
    'VSS_B49':'(0,0,0,0,0,0,0,0,0,0,0,0,0,0,0,0,0,0,0,0,0,0,0,0,0,0,0,B49,0,0,0,~
0,0,0,0,0,0,0,0,0)';$S;
    'VSS_B52':'(0,0,0,0,0,0,0,0,0,0,0,0,0,0,0,0,0,0,0,0,0,0,0,0,0,0,0,B52,0,0,0,~
0,0,0,0,0,0,0,0,0)';$S;
    'VSS_B55':'(0,0,0,0,0,0,0,0,0,0,0,0,0,0,0,0,0,0,0,0,0,0,0,0,0,0,0,B55,0,0,0,~
0,0,0,0,0,0,0,0,0)';$S;
    'VSS_B59':'(0,0,0,0,0,0,0,0,0,0,0,0,0,0,0,0,0,0,0,0,0,0,0,0,0,0,0,B59,0,0,0,~
0,0,0,0,0,0,0,0,0)';$S;
    'VSS_B62':'(0,0,0,0,0,0,0,0,0,0,0,0,0,0,0,0,0,0,0,0,0,0,0,0,0,0,0,B62,0,0,0,~
0,0,0,0,0,0,0,0,0)';$S;
    'VSS_B65':'(0,0,0,0,0,0,0,0,0,0,0,0,0,0,0,0,0,0,0,0,0,0,0,0,0,0,0,B65,0,0,0,~
0,0,0,0,0,0,0,0,0)';$S;
    'VSS_B68':'(0,0,0,0,0,0,0,0,0,0,0,0,0,0,0,0,0,0,0,0,0,0,0,0,0,0,0,B68,0,0,0,~
0,0,0,0,0,0,0,0,0)';$S;
    'VSS_B70':'(0,0,0,0,0,0,0,0,0,0,0,0,0,0,0,0,0,0,0,0,0,0,0,0,0,0,0,B70,0,0,0,~
0,0,0,0,0,0,0,0,0)';$S;
    'VSS_C1':'(0,0,0,0,0,0,0,0,0,0,0,0,0,0,0,0,0,0,0,0,0,0,0,0,0,0,0,C1,0,0,0,0,~
0,0,0,0,0,0,0,0)';$S;
    'VSS_C5':'(0,0,0,0,0,0,0,0,0,0,0,0,0,0,0,0,0,0,0,0,0,0,0,0,0,0,0,C5,0,0,0,0,~
0,0,0,0,0,0,0,0)';$S;
    'VSS_C8':'(0,0,0,0,0,0,0,0,0,0,0,0,0,0,0,0,0,0,0,0,0,0,0,0,0,0,0,C8,0,0,0,0,~
0,0,0,0,0,0,0,0)';$S;
    'VSS_C10':'(0,0,0,0,0,0,0,0,0,0,0,0,0,0,0,0,0,0,0,0,0,0,0,0,0,0,0,C10,0,0,0,~
0,0,0,0,0,0,0,0,0)';$S;
    'VSS_C11':'(0,0,0,0,0,0,0,0,0,0,0,0,0,0,0,0,0,0,0,0,0,0,0,0,0,0,0,C11,0,0,0,~
0,0,0,0,0,0,0,0,0)';$S;
    'VSS_C13':'(0,0,0,0,0,0,0,0,0,0,0,0,0,0,0,0,0,0,0,0,0,0,0,0,0,0,0,C13,0,0,0,~
0,0,0,0,0,0,0,0,0)';$S;
    'VSS_C15':'(0,0,0,0,0,0,0,0,0,0,0,0,0,0,0,0,0,0,0,0,0,0,0,0,0,0,0,C15,0,0,0,~
0,0,0,0,0,0,0,0,0)';$S;
    'VSS_C21':'(0,0,0,0,0,0,0,0,0,0,0,0,0,0,0,0,0,0,0,0,0,0,0,0,0,0,0,C21,0,0,0,~
0,0,0,0,0,0,0,0,0)';$S;
    'VSS_C24':'(0,0,0,0,0,0,0,0,0,0,0,0,0,0,0,0,0,0,0,0,0,0,0,0,0,0,0,C24,0,0,0,~
0,0,0,0,0,0,0,0,0)';$S;
    'VSS_C27':'(0,0,0,0,0,0,0,0,0,0,0,0,0,0,0,0,0,0,0,0,0,0,0,0,0,0,0,C27,0,0,0,~
0,0,0,0,0,0,0,0,0)';$S;
    'VSS_C30':'(0,0,0,0,0,0,0,0,0,0,0,0,0,0,0,0,0,0,0,0,0,0,0,0,0,0,0,C30,0,0,0,~
0,0,0,0,0,0,0,0,0)';$S;
    'VSS_C36':'(0,0,0,0,0,0,0,0,0,0,0,0,0,0,0,0,0,0,0,0,0,0,0,0,0,0,0,C36,0,0,0,~
0,0,0,0,0,0,0,0,0)';$S;
    'VSS_C40':'(0,0,0,0,0,0,0,0,0,0,0,0,0,0,0,0,0,0,0,0,0,0,0,0,0,0,0,C40,0,0,0,~
0,0,0,0,0,0,0,0,0)';$S;
    'VSS_C43':'(0,0,0,0,0,0,0,0,0,0,0,0,0,0,0,0,0,0,0,0,0,0,0,0,0,0,0,C43,0,0,0,~
0,0,0,0,0,0,0,0,0)';$S;
    'VSS_C46':'(0,0,0,0,0,0,0,0,0,0,0,0,0,0,0,0,0,0,0,0,0,0,0,0,0,0,0,C46,0,0,0,~
0,0,0,0,0,0,0,0,0)';$S;
    'VSS_C49':'(0,0,0,0,0,0,0,0,0,0,0,0,0,0,0,0,0,0,0,0,0,0,0,0,0,0,0,C49,0,0,0,~
0,0,0,0,0,0,0,0,0)';$S;
    'VSS_C52':'(0,0,0,0,0,0,0,0,0,0,0,0,0,0,0,0,0,0,0,0,0,0,0,0,0,0,0,C52,0,0,0,~
0,0,0,0,0,0,0,0,0)';$S;
    'VSS_C55':'(0,0,0,0,0,0,0,0,0,0,0,0,0,0,0,0,0,0,0,0,0,0,0,0,0,0,0,C55,0,0,0,~
0,0,0,0,0,0,0,0,0)';$S;
    'VSS_C56':'(0,0,0,0,0,0,0,0,0,0,0,0,0,0,0,0,0,0,0,0,0,0,0,0,0,0,0,C56,0,0,0,~
0,0,0,0,0,0,0,0,0)';$S;
    'VSS_C57':'(0,0,0,0,0,0,0,0,0,0,0,0,0,0,0,0,0,0,0,0,0,0,0,0,0,0,0,C57,0,0,0,~
0,0,0,0,0,0,0,0,0)';$S;
    'VSS_C61':'(0,0,0,0,0,0,0,0,0,0,0,0,0,0,0,0,0,0,0,0,0,0,0,0,0,0,0,C61,0,0,0,~
0,0,0,0,0,0,0,0,0)';$S;
    'VSS_C64':'(0,0,0,0,0,0,0,0,0,0,0,0,0,0,0,0,0,0,0,0,0,0,0,0,0,0,0,C64,0,0,0,~
0,0,0,0,0,0,0,0,0)';$S;
    'VSS_C67':'(0,0,0,0,0,0,0,0,0,0,0,0,0,0,0,0,0,0,0,0,0,0,0,0,0,0,0,C67,0,0,0,~
0,0,0,0,0,0,0,0,0)';$S;
    'VSS_C69':'(0,0,0,0,0,0,0,0,0,0,0,0,0,0,0,0,0,0,0,0,0,0,0,0,0,0,0,C69,0,0,0,~
0,0,0,0,0,0,0,0,0)';$S;
    'VSS_C71':'(0,0,0,0,0,0,0,0,0,0,0,0,0,0,0,0,0,0,0,0,0,0,0,0,0,0,0,C71,0,0,0,~
0,0,0,0,0,0,0,0,0)';$S;
    'VSS_C73':'(0,0,0,0,0,0,0,0,0,0,0,0,0,0,0,0,0,0,0,0,0,0,0,0,0,0,0,C73,0,0,0,~
0,0,0,0,0,0,0,0,0)';$S;
    'VSS_C75':'(0,0,0,0,0,0,0,0,0,0,0,0,0,0,0,0,0,0,0,0,0,0,0,0,0,0,0,C75,0,0,0,~
0,0,0,0,0,0,0,0,0)';$S;
    'VSS_D2':'(0,0,0,0,0,0,0,0,0,0,0,0,0,0,0,0,0,0,0,0,0,0,0,0,0,0,0,D2,0,0,0,0,~
0,0,0,0,0,0,0,0)';$S;
    'VSS_D3':'(0,0,0,0,0,0,0,0,0,0,0,0,0,0,0,0,0,0,0,0,0,0,0,0,0,0,0,D3,0,0,0,0,~
0,0,0,0,0,0,0,0)';$S;
    'VSS_D5':'(0,0,0,0,0,0,0,0,0,0,0,0,0,0,0,0,0,0,0,0,0,0,0,0,0,0,0,D5,0,0,0,0,~
0,0,0,0,0,0,0,0)';$S;
    'VSS_D6':'(0,0,0,0,0,0,0,0,0,0,0,0,0,0,0,0,0,0,0,0,0,0,0,0,0,0,0,D6,0,0,0,0,~
0,0,0,0,0,0,0,0)';$S;
    'VSS_D9':'(0,0,0,0,0,0,0,0,0,0,0,0,0,0,0,0,0,0,0,0,0,0,0,0,0,0,0,D9,0,0,0,0,~
0,0,0,0,0,0,0,0)';$S;
    'VSS_D10':'(0,0,0,0,0,0,0,0,0,0,0,0,0,0,0,0,0,0,0,0,0,0,0,0,0,0,0,D10,0,0,0,~
0,0,0,0,0,0,0,0,0)';$S;
    'VSS_D12':'(0,0,0,0,0,0,0,0,0,0,0,0,0,0,0,0,0,0,0,0,0,0,0,0,0,0,0,D12,0,0,0,~
0,0,0,0,0,0,0,0,0)';$S;
    'VSS_D13':'(0,0,0,0,0,0,0,0,0,0,0,0,0,0,0,0,0,0,0,0,0,0,0,0,0,0,0,D13,0,0,0,~
0,0,0,0,0,0,0,0,0)';$S;
    'VSS_D16':'(0,0,0,0,0,0,0,0,0,0,0,0,0,0,0,0,0,0,0,0,0,0,0,0,0,0,0,D16,0,0,0,~
0,0,0,0,0,0,0,0,0)';$S;
    'VSS_D17':'(0,0,0,0,0,0,0,0,0,0,0,0,0,0,0,0,0,0,0,0,0,0,0,0,0,0,0,D17,0,0,0,~
0,0,0,0,0,0,0,0,0)';$S;
    'VSS_D19':'(0,0,0,0,0,0,0,0,0,0,0,0,0,0,0,0,0,0,0,0,0,0,0,0,0,0,0,D19,0,0,0,~
0,0,0,0,0,0,0,0,0)';$S;
    'VSS_D20':'(0,0,0,0,0,0,0,0,0,0,0,0,0,0,0,0,0,0,0,0,0,0,0,0,0,0,0,D20,0,0,0,~
0,0,0,0,0,0,0,0,0)';$S;
    'VSS_D21':'(0,0,0,0,0,0,0,0,0,0,0,0,0,0,0,0,0,0,0,0,0,0,0,0,0,0,0,D21,0,0,0,~
0,0,0,0,0,0,0,0,0)';$S;
    'VSS_D24':'(0,0,0,0,0,0,0,0,0,0,0,0,0,0,0,0,0,0,0,0,0,0,0,0,0,0,0,D24,0,0,0,~
0,0,0,0,0,0,0,0,0)';$S;
    'VSS_D25':'(0,0,0,0,0,0,0,0,0,0,0,0,0,0,0,0,0,0,0,0,0,0,0,0,0,0,0,D25,0,0,0,~
0,0,0,0,0,0,0,0,0)';$S;
    'VSS_D26':'(0,0,0,0,0,0,0,0,0,0,0,0,0,0,0,0,0,0,0,0,0,0,0,0,0,0,0,D26,0,0,0,~
0,0,0,0,0,0,0,0,0)';$S;
    'VSS_D27':'(0,0,0,0,0,0,0,0,0,0,0,0,0,0,0,0,0,0,0,0,0,0,0,0,0,0,0,D27,0,0,0,~
0,0,0,0,0,0,0,0,0)';$S;
    'VSS_D28':'(0,0,0,0,0,0,0,0,0,0,0,0,0,0,0,0,0,0,0,0,0,0,0,0,0,0,0,D28,0,0,0,~
0,0,0,0,0,0,0,0,0)';$S;
    'VSS_D29':'(0,0,0,0,0,0,0,0,0,0,0,0,0,0,0,0,0,0,0,0,0,0,0,0,0,0,0,D29,0,0,0,~
0,0,0,0,0,0,0,0,0)';$S;
    'VSS_D30':'(0,0,0,0,0,0,0,0,0,0,0,0,0,0,0,0,0,0,0,0,0,0,0,0,0,0,0,D30,0,0,0,~
0,0,0,0,0,0,0,0,0)';$S;
    'VSS_D31':'(0,0,0,0,0,0,0,0,0,0,0,0,0,0,0,0,0,0,0,0,0,0,0,0,0,0,0,D31,0,0,0,~
0,0,0,0,0,0,0,0,0)';$S;
    'VSS_D35':'(0,0,0,0,0,0,0,0,0,0,0,0,0,0,0,0,0,0,0,0,0,0,0,0,0,0,0,D35,0,0,0,~
0,0,0,0,0,0,0,0,0)';$S;
    'VSS_D37':'(0,0,0,0,0,0,0,0,0,0,0,0,0,0,0,0,0,0,0,0,0,0,0,0,0,0,0,D37,0,0,0,~
0,0,0,0,0,0,0,0,0)';$S;
    'VSS_D39':'(0,0,0,0,0,0,0,0,0,0,0,0,0,0,0,0,0,0,0,0,0,0,0,0,0,0,0,D39,0,0,0,~
0,0,0,0,0,0,0,0,0)';$S;
    'VSS_D40':'(0,0,0,0,0,0,0,0,0,0,0,0,0,0,0,0,0,0,0,0,0,0,0,0,0,0,0,D40,0,0,0,~
0,0,0,0,0,0,0,0,0)';$S;
    'VSS_D41':'(0,0,0,0,0,0,0,0,0,0,0,0,0,0,0,0,0,0,0,0,0,0,0,0,0,0,0,D41,0,0,0,~
0,0,0,0,0,0,0,0,0)';$S;
    'VSS_D42':'(0,0,0,0,0,0,0,0,0,0,0,0,0,0,0,0,0,0,0,0,0,0,0,0,0,0,0,D42,0,0,0,~
0,0,0,0,0,0,0,0,0)';$S;
    'VSS_D43':'(0,0,0,0,0,0,0,0,0,0,0,0,0,0,0,0,0,0,0,0,0,0,0,0,0,0,0,D43,0,0,0,~
0,0,0,0,0,0,0,0,0)';$S;
    'VSS_D44':'(0,0,0,0,0,0,0,0,0,0,0,0,0,0,0,0,0,0,0,0,0,0,0,0,0,0,0,D44,0,0,0,~
0,0,0,0,0,0,0,0,0)';$S;
    'VSS_D45':'(0,0,0,0,0,0,0,0,0,0,0,0,0,0,0,0,0,0,0,0,0,0,0,0,0,0,0,D45,0,0,0,~
0,0,0,0,0,0,0,0,0)';$S;
    'VSS_D46':'(0,0,0,0,0,0,0,0,0,0,0,0,0,0,0,0,0,0,0,0,0,0,0,0,0,0,0,D46,0,0,0,~
0,0,0,0,0,0,0,0,0)';$S;
    'VSS_D47':'(0,0,0,0,0,0,0,0,0,0,0,0,0,0,0,0,0,0,0,0,0,0,0,0,0,0,0,D47,0,0,0,~
0,0,0,0,0,0,0,0,0)';$S;
    'VSS_D48':'(0,0,0,0,0,0,0,0,0,0,0,0,0,0,0,0,0,0,0,0,0,0,0,0,0,0,0,D48,0,0,0,~
0,0,0,0,0,0,0,0,0)';$S;
    'VSS_D49':'(0,0,0,0,0,0,0,0,0,0,0,0,0,0,0,0,0,0,0,0,0,0,0,0,0,0,0,D49,0,0,0,~
0,0,0,0,0,0,0,0,0)';$S;
    'VSS_D50':'(0,0,0,0,0,0,0,0,0,0,0,0,0,0,0,0,0,0,0,0,0,0,0,0,0,0,0,D50,0,0,0,~
0,0,0,0,0,0,0,0,0)';$S;
    'VSS_D51':'(0,0,0,0,0,0,0,0,0,0,0,0,0,0,0,0,0,0,0,0,0,0,0,0,0,0,0,D51,0,0,0,~
0,0,0,0,0,0,0,0,0)';$S;
    'VSS_D52':'(0,0,0,0,0,0,0,0,0,0,0,0,0,0,0,0,0,0,0,0,0,0,0,0,0,0,0,D52,0,0,0,~
0,0,0,0,0,0,0,0,0)';$S;
    'VSS_D53':'(0,0,0,0,0,0,0,0,0,0,0,0,0,0,0,0,0,0,0,0,0,0,0,0,0,0,0,D53,0,0,0,~
0,0,0,0,0,0,0,0,0)';$S;
    'VSS_D54':'(0,0,0,0,0,0,0,0,0,0,0,0,0,0,0,0,0,0,0,0,0,0,0,0,0,0,0,D54,0,0,0,~
0,0,0,0,0,0,0,0,0)';$S;
    'VSS_D57':'(0,0,0,0,0,0,0,0,0,0,0,0,0,0,0,0,0,0,0,0,0,0,0,0,0,0,0,D57,0,0,0,~
0,0,0,0,0,0,0,0,0)';$S;
    'VSS_D59':'(0,0,0,0,0,0,0,0,0,0,0,0,0,0,0,0,0,0,0,0,0,0,0,0,0,0,0,D59,0,0,0,~
0,0,0,0,0,0,0,0,0)';$S;
    'VSS_D60':'(0,0,0,0,0,0,0,0,0,0,0,0,0,0,0,0,0,0,0,0,0,0,0,0,0,0,0,D60,0,0,0,~
0,0,0,0,0,0,0,0,0)';$S;
    'VSS_D61':'(0,0,0,0,0,0,0,0,0,0,0,0,0,0,0,0,0,0,0,0,0,0,0,0,0,0,0,D61,0,0,0,~
0,0,0,0,0,0,0,0,0)';$S;
    'VSS_D63':'(0,0,0,0,0,0,0,0,0,0,0,0,0,0,0,0,0,0,0,0,0,0,0,0,0,0,0,D63,0,0,0,~
0,0,0,0,0,0,0,0,0)';$S;
    'VSS_D64':'(0,0,0,0,0,0,0,0,0,0,0,0,0,0,0,0,0,0,0,0,0,0,0,0,0,0,0,D64,0,0,0,~
0,0,0,0,0,0,0,0,0)';$S;
    'VSS_D66':'(0,0,0,0,0,0,0,0,0,0,0,0,0,0,0,0,0,0,0,0,0,0,0,0,0,0,0,D66,0,0,0,~
0,0,0,0,0,0,0,0,0)';$S;
    'VSS_D67':'(0,0,0,0,0,0,0,0,0,0,0,0,0,0,0,0,0,0,0,0,0,0,0,0,0,0,0,D67,0,0,0,~
0,0,0,0,0,0,0,0,0)';$S;
    'VSS_D70':'(0,0,0,0,0,0,0,0,0,0,0,0,0,0,0,0,0,0,0,0,0,0,0,0,0,0,0,D70,0,0,0,~
0,0,0,0,0,0,0,0,0)';$S;
    'VSS_D71':'(0,0,0,0,0,0,0,0,0,0,0,0,0,0,0,0,0,0,0,0,0,0,0,0,0,0,0,D71,0,0,0,~
0,0,0,0,0,0,0,0,0)';$S;
    'VSS_D73':'(0,0,0,0,0,0,0,0,0,0,0,0,0,0,0,0,0,0,0,0,0,0,0,0,0,0,0,D73,0,0,0,~
0,0,0,0,0,0,0,0,0)';$S;
    'VSS_D74':'(0,0,0,0,0,0,0,0,0,0,0,0,0,0,0,0,0,0,0,0,0,0,0,0,0,0,0,D74,0,0,0,~
0,0,0,0,0,0,0,0,0)';$S;
    'VSS_E1':'(0,0,0,0,0,0,0,0,0,0,0,0,0,0,0,0,0,0,0,0,0,0,0,0,0,0,0,E1,0,0,0,0,~
0,0,0,0,0,0,0,0)';$S;
    'VSS_E3':'(0,0,0,0,0,0,0,0,0,0,0,0,0,0,0,0,0,0,0,0,0,0,0,0,0,0,0,E3,0,0,0,0,~
0,0,0,0,0,0,0,0)';$S;
    'VSS_E6':'(0,0,0,0,0,0,0,0,0,0,0,0,0,0,0,0,0,0,0,0,0,0,0,0,0,0,0,E6,0,0,0,0,~
0,0,0,0,0,0,0,0)';$S;
    'VSS_E7':'(0,0,0,0,0,0,0,0,0,0,0,0,0,0,0,0,0,0,0,0,0,0,0,0,0,0,0,E7,0,0,0,0,~
0,0,0,0,0,0,0,0)';$S;
    'VSS_E8':'(0,0,0,0,0,0,0,0,0,0,0,0,0,0,0,0,0,0,0,0,0,0,0,0,0,0,0,E8,0,0,0,0,~
0,0,0,0,0,0,0,0)';$S;
    'VSS_E10':'(0,0,0,0,0,0,0,0,0,0,0,0,0,0,0,0,0,0,0,0,0,0,0,0,0,0,0,E10,0,0,0,~
0,0,0,0,0,0,0,0,0)';$S;
    'VSS_E13':'(0,0,0,0,0,0,0,0,0,0,0,0,0,0,0,0,0,0,0,0,0,0,0,0,0,0,0,E13,0,0,0,~
0,0,0,0,0,0,0,0,0)';$S;
    'VSS_E14':'(0,0,0,0,0,0,0,0,0,0,0,0,0,0,0,0,0,0,0,0,0,0,0,0,0,0,0,E14,0,0,0,~
0,0,0,0,0,0,0,0,0)';$S;
    'VSS_E15':'(0,0,0,0,0,0,0,0,0,0,0,0,0,0,0,0,0,0,0,0,0,0,0,0,0,0,0,E15,0,0,0,~
0,0,0,0,0,0,0,0,0)';$S;
    'VSS_E17':'(0,0,0,0,0,0,0,0,0,0,0,0,0,0,0,0,0,0,0,0,0,0,0,0,0,0,0,E17,0,0,0,~
0,0,0,0,0,0,0,0,0)';$S;
    'VSS_E18':'(0,0,0,0,0,0,0,0,0,0,0,0,0,0,0,0,0,0,0,0,0,0,0,0,0,0,0,E18,0,0,0,~
0,0,0,0,0,0,0,0,0)';$S;
    'VSS_E20':'(0,0,0,0,0,0,0,0,0,0,0,0,0,0,0,0,0,0,0,0,0,0,0,0,0,0,0,E20,0,0,0,~
0,0,0,0,0,0,0,0,0)';$S;
    'VSS_E21':'(0,0,0,0,0,0,0,0,0,0,0,0,0,0,0,0,0,0,0,0,0,0,0,0,0,0,0,E21,0,0,0,~
0,0,0,0,0,0,0,0,0)';$S;
    'VSS_E52':'(0,0,0,0,0,0,0,0,0,0,0,0,0,0,0,0,0,0,0,0,0,0,0,0,0,0,0,E52,0,0,0,~
0,0,0,0,0,0,0,0,0)';$S;
    'VSS_E53':'(0,0,0,0,0,0,0,0,0,0,0,0,0,0,0,0,0,0,0,0,0,0,0,0,0,0,0,E53,0,0,0,~
0,0,0,0,0,0,0,0,0)';$S;
    'VSS_E55':'(0,0,0,0,0,0,0,0,0,0,0,0,0,0,0,0,0,0,0,0,0,0,0,0,0,0,0,E55,0,0,0,~
0,0,0,0,0,0,0,0,0)';$S;
    'VSS_E56':'(0,0,0,0,0,0,0,0,0,0,0,0,0,0,0,0,0,0,0,0,0,0,0,0,0,0,0,E56,0,0,0,~
0,0,0,0,0,0,0,0,0)';$S;
    'VSS_E58':'(0,0,0,0,0,0,0,0,0,0,0,0,0,0,0,0,0,0,0,0,0,0,0,0,0,0,0,E58,0,0,0,~
0,0,0,0,0,0,0,0,0)';$S;
    'VSS_E59':'(0,0,0,0,0,0,0,0,0,0,0,0,0,0,0,0,0,0,0,0,0,0,0,0,0,0,0,E59,0,0,0,~
0,0,0,0,0,0,0,0,0)';$S;
    'VSS_E61':'(0,0,0,0,0,0,0,0,0,0,0,0,0,0,0,0,0,0,0,0,0,0,0,0,0,0,0,E61,0,0,0,~
0,0,0,0,0,0,0,0,0)';$S;
    'VSS_E62':'(0,0,0,0,0,0,0,0,0,0,0,0,0,0,0,0,0,0,0,0,0,0,0,0,0,0,0,E62,0,0,0,~
0,0,0,0,0,0,0,0,0)';$S;
    'VSS_E63':'(0,0,0,0,0,0,0,0,0,0,0,0,0,0,0,0,0,0,0,0,0,0,0,0,0,0,0,E63,0,0,0,~
0,0,0,0,0,0,0,0,0)';$S;
    'VSS_E65':'(0,0,0,0,0,0,0,0,0,0,0,0,0,0,0,0,0,0,0,0,0,0,0,0,0,0,0,E65,0,0,0,~
0,0,0,0,0,0,0,0,0)';$S;
    'VSS_E66':'(0,0,0,0,0,0,0,0,0,0,0,0,0,0,0,0,0,0,0,0,0,0,0,0,0,0,0,E66,0,0,0,~
0,0,0,0,0,0,0,0,0)';$S;
    'VSS_E68':'(0,0,0,0,0,0,0,0,0,0,0,0,0,0,0,0,0,0,0,0,0,0,0,0,0,0,0,E68,0,0,0,~
0,0,0,0,0,0,0,0,0)';$S;
    'VSS_E69':'(0,0,0,0,0,0,0,0,0,0,0,0,0,0,0,0,0,0,0,0,0,0,0,0,0,0,0,E69,0,0,0,~
0,0,0,0,0,0,0,0,0)';$S;
    'VSS_E70':'(0,0,0,0,0,0,0,0,0,0,0,0,0,0,0,0,0,0,0,0,0,0,0,0,0,0,0,E70,0,0,0,~
0,0,0,0,0,0,0,0,0)';$S;
    'VSS_E72':'(0,0,0,0,0,0,0,0,0,0,0,0,0,0,0,0,0,0,0,0,0,0,0,0,0,0,0,E72,0,0,0,~
0,0,0,0,0,0,0,0,0)';$S;
    'VSS_E73':'(0,0,0,0,0,0,0,0,0,0,0,0,0,0,0,0,0,0,0,0,0,0,0,0,0,0,0,E73,0,0,0,~
0,0,0,0,0,0,0,0,0)';$S;
    'VSS_E75':'(0,0,0,0,0,0,0,0,0,0,0,0,0,0,0,0,0,0,0,0,0,0,0,0,0,0,0,E75,0,0,0,~
0,0,0,0,0,0,0,0,0)';$S;
    'VSS_F3':'(0,0,0,0,0,0,0,0,0,0,0,0,0,0,0,0,0,0,0,0,0,0,0,0,0,0,0,F3,0,0,0,0,~
0,0,0,0,0,0,0,0)';$S;
    'VSS_F5':'(0,0,0,0,0,0,0,0,0,0,0,0,0,0,0,0,0,0,0,0,0,0,0,0,0,0,0,F5,0,0,0,0,~
0,0,0,0,0,0,0,0)';$S;
    'VSS_F8':'(0,0,0,0,0,0,0,0,0,0,0,0,0,0,0,0,0,0,0,0,0,0,0,0,0,0,0,F8,0,0,0,0,~
0,0,0,0,0,0,0,0)';$S;
    'VSS_F10':'(0,0,0,0,0,0,0,0,0,0,0,0,0,0,0,0,0,0,0,0,0,0,0,0,0,0,0,F10,0,0,0,~
0,0,0,0,0,0,0,0,0)';$S;
    'VSS_F12':'(0,0,0,0,0,0,0,0,0,0,0,0,0,0,0,0,0,0,0,0,0,0,0,0,0,0,0,F12,0,0,0,~
0,0,0,0,0,0,0,0,0)';$S;
    'VSS_F15':'(0,0,0,0,0,0,0,0,0,0,0,0,0,0,0,0,0,0,0,0,0,0,0,0,0,0,0,F15,0,0,0,~
0,0,0,0,0,0,0,0,0)';$S;
    'VSS_F17':'(0,0,0,0,0,0,0,0,0,0,0,0,0,0,0,0,0,0,0,0,0,0,0,0,0,0,0,F17,0,0,0,~
0,0,0,0,0,0,0,0,0)';$S;
    'VSS_F19':'(0,0,0,0,0,0,0,0,0,0,0,0,0,0,0,0,0,0,0,0,0,0,0,0,0,0,0,F19,0,0,0,~
0,0,0,0,0,0,0,0,0)';$S;
    'VSS_F23':'(0,0,0,0,0,0,0,0,0,0,0,0,0,0,0,0,0,0,0,0,0,0,0,0,0,0,0,F23,0,0,0,~
0,0,0,0,0,0,0,0,0)';$S;
    'VSS_F24':'(0,0,0,0,0,0,0,0,0,0,0,0,0,0,0,0,0,0,0,0,0,0,0,0,0,0,0,F24,0,0,0,~
0,0,0,0,0,0,0,0,0)';$S;
    'VSS_F26':'(0,0,0,0,0,0,0,0,0,0,0,0,0,0,0,0,0,0,0,0,0,0,0,0,0,0,0,F26,0,0,0,~
0,0,0,0,0,0,0,0,0)';$S;
    'VSS_F27':'(0,0,0,0,0,0,0,0,0,0,0,0,0,0,0,0,0,0,0,0,0,0,0,0,0,0,0,F27,0,0,0,~
0,0,0,0,0,0,0,0,0)';$S;
    'VSS_F29':'(0,0,0,0,0,0,0,0,0,0,0,0,0,0,0,0,0,0,0,0,0,0,0,0,0,0,0,F29,0,0,0,~
0,0,0,0,0,0,0,0,0)';$S;
    'VSS_F30':'(0,0,0,0,0,0,0,0,0,0,0,0,0,0,0,0,0,0,0,0,0,0,0,0,0,0,0,F30,0,0,0,~
0,0,0,0,0,0,0,0,0)';$S;
    'VSS_F32':'(0,0,0,0,0,0,0,0,0,0,0,0,0,0,0,0,0,0,0,0,0,0,0,0,0,0,0,F32,0,0,0,~
0,0,0,0,0,0,0,0,0)';$S;
    'VSS_F33':'(0,0,0,0,0,0,0,0,0,0,0,0,0,0,0,0,0,0,0,0,0,0,0,0,0,0,0,F33,0,0,0,~
0,0,0,0,0,0,0,0,0)';$S;
    'VSS_F35':'(0,0,0,0,0,0,0,0,0,0,0,0,0,0,0,0,0,0,0,0,0,0,0,0,0,0,0,F35,0,0,0,~
0,0,0,0,0,0,0,0,0)';$S;
    'VSS_F36':'(0,0,0,0,0,0,0,0,0,0,0,0,0,0,0,0,0,0,0,0,0,0,0,0,0,0,0,F36,0,0,0,~
0,0,0,0,0,0,0,0,0)';$S;
    'VSS_F37':'(0,0,0,0,0,0,0,0,0,0,0,0,0,0,0,0,0,0,0,0,0,0,0,0,0,0,0,F37,0,0,0,~
0,0,0,0,0,0,0,0,0)';$S;
    'VSS_F39':'(0,0,0,0,0,0,0,0,0,0,0,0,0,0,0,0,0,0,0,0,0,0,0,0,0,0,0,F39,0,0,0,~
0,0,0,0,0,0,0,0,0)';$S;
    'VSS_F40':'(0,0,0,0,0,0,0,0,0,0,0,0,0,0,0,0,0,0,0,0,0,0,0,0,0,0,0,F40,0,0,0,~
0,0,0,0,0,0,0,0,0)';$S;
    'VSS_F41':'(0,0,0,0,0,0,0,0,0,0,0,0,0,0,0,0,0,0,0,0,0,0,0,0,0,0,0,F41,0,0,0,~
0,0,0,0,0,0,0,0,0)';$S;
    'VSS_F43':'(0,0,0,0,0,0,0,0,0,0,0,0,0,0,0,0,0,0,0,0,0,0,0,0,0,0,0,F43,0,0,0,~
0,0,0,0,0,0,0,0,0)';$S;
    'VSS_F44':'(0,0,0,0,0,0,0,0,0,0,0,0,0,0,0,0,0,0,0,0,0,0,0,0,0,0,0,F44,0,0,0,~
0,0,0,0,0,0,0,0,0)';$S;
    'VSS_F46':'(0,0,0,0,0,0,0,0,0,0,0,0,0,0,0,0,0,0,0,0,0,0,0,0,0,0,0,F46,0,0,0,~
0,0,0,0,0,0,0,0,0)';$S;
    'VSS_F47':'(0,0,0,0,0,0,0,0,0,0,0,0,0,0,0,0,0,0,0,0,0,0,0,0,0,0,0,F47,0,0,0,~
0,0,0,0,0,0,0,0,0)';$S;
    'VSS_F49':'(0,0,0,0,0,0,0,0,0,0,0,0,0,0,0,0,0,0,0,0,0,0,0,0,0,0,0,F49,0,0,0,~
0,0,0,0,0,0,0,0,0)';$S;
    'VSS_F50':'(0,0,0,0,0,0,0,0,0,0,0,0,0,0,0,0,0,0,0,0,0,0,0,0,0,0,0,F50,0,0,0,~
0,0,0,0,0,0,0,0,0)';$S;
    'VSS_F52':'(0,0,0,0,0,0,0,0,0,0,0,0,0,0,0,0,0,0,0,0,0,0,0,0,0,0,0,F52,0,0,0,~
0,0,0,0,0,0,0,0,0)';$S;
    'VSS_F53':'(0,0,0,0,0,0,0,0,0,0,0,0,0,0,0,0,0,0,0,0,0,0,0,0,0,0,0,F53,0,0,0,~
0,0,0,0,0,0,0,0,0)';$S;
    'VSS_F57':'(0,0,0,0,0,0,0,0,0,0,0,0,0,0,0,0,0,0,0,0,0,0,0,0,0,0,0,F57,0,0,0,~
0,0,0,0,0,0,0,0,0)';$S;
    'VSS_F59':'(0,0,0,0,0,0,0,0,0,0,0,0,0,0,0,0,0,0,0,0,0,0,0,0,0,0,0,F59,0,0,0,~
0,0,0,0,0,0,0,0,0)';$S;
    'VSS_F61':'(0,0,0,0,0,0,0,0,0,0,0,0,0,0,0,0,0,0,0,0,0,0,0,0,0,0,0,F61,0,0,0,~
0,0,0,0,0,0,0,0,0)';$S;
    'VSS_F64':'(0,0,0,0,0,0,0,0,0,0,0,0,0,0,0,0,0,0,0,0,0,0,0,0,0,0,0,F64,0,0,0,~
0,0,0,0,0,0,0,0,0)';$S;
    'VSS_F66':'(0,0,0,0,0,0,0,0,0,0,0,0,0,0,0,0,0,0,0,0,0,0,0,0,0,0,0,F66,0,0,0,~
0,0,0,0,0,0,0,0,0)';$S;
    'VSS_F68':'(0,0,0,0,0,0,0,0,0,0,0,0,0,0,0,0,0,0,0,0,0,0,0,0,0,0,0,F68,0,0,0,~
0,0,0,0,0,0,0,0,0)';$S;
    'VSS_F71':'(0,0,0,0,0,0,0,0,0,0,0,0,0,0,0,0,0,0,0,0,0,0,0,0,0,0,0,F71,0,0,0,~
0,0,0,0,0,0,0,0,0)';$S;
    'VSS_F73':'(0,0,0,0,0,0,0,0,0,0,0,0,0,0,0,0,0,0,0,0,0,0,0,0,0,0,0,F73,0,0,0,~
0,0,0,0,0,0,0,0,0)';$S;
    'VSS_G1':'(0,0,0,0,0,0,0,0,0,0,0,0,0,0,0,0,0,0,0,0,0,0,0,0,0,0,0,G1,0,0,0,0,~
0,0,0,0,0,0,0,0)';$S;
    'VSS_G4':'(0,0,0,0,0,0,0,0,0,0,0,0,0,0,0,0,0,0,0,0,0,0,0,0,0,0,0,G4,0,0,0,0,~
0,0,0,0,0,0,0,0)';$S;
    'VSS_G6':'(0,0,0,0,0,0,0,0,0,0,0,0,0,0,0,0,0,0,0,0,0,0,0,0,0,0,0,G6,0,0,0,0,~
0,0,0,0,0,0,0,0)';$S;
    'VSS_G8':'(0,0,0,0,0,0,0,0,0,0,0,0,0,0,0,0,0,0,0,0,0,0,0,0,0,0,0,G8,0,0,0,0,~
0,0,0,0,0,0,0,0)';$S;
    'VSS_G11':'(0,0,0,0,0,0,0,0,0,0,0,0,0,0,0,0,0,0,0,0,0,0,0,0,0,0,0,G11,0,0,0,~
0,0,0,0,0,0,0,0,0)';$S;
    'VSS_G13':'(0,0,0,0,0,0,0,0,0,0,0,0,0,0,0,0,0,0,0,0,0,0,0,0,0,0,0,G13,0,0,0,~
0,0,0,0,0,0,0,0,0)';$S;
    'VSS_G15':'(0,0,0,0,0,0,0,0,0,0,0,0,0,0,0,0,0,0,0,0,0,0,0,0,0,0,0,G15,0,0,0,~
0,0,0,0,0,0,0,0,0)';$S;
    'VSS_G18':'(0,0,0,0,0,0,0,0,0,0,0,0,0,0,0,0,0,0,0,0,0,0,0,0,0,0,0,G18,0,0,0,~
0,0,0,0,0,0,0,0,0)';$S;
    'VSS_G20':'(0,0,0,0,0,0,0,0,0,0,0,0,0,0,0,0,0,0,0,0,0,0,0,0,0,0,0,G20,0,0,0,~
0,0,0,0,0,0,0,0,0)';$S;
    'VSS_G22':'(0,0,0,0,0,0,0,0,0,0,0,0,0,0,0,0,0,0,0,0,0,0,0,0,0,0,0,G22,0,0,0,~
0,0,0,0,0,0,0,0,0)';$S;
    'VSS_G25':'(0,0,0,0,0,0,0,0,0,0,0,0,0,0,0,0,0,0,0,0,0,0,0,0,0,0,0,G25,0,0,0,~
0,0,0,0,0,0,0,0,0)';$S;
    'VSS_G28':'(0,0,0,0,0,0,0,0,0,0,0,0,0,0,0,0,0,0,0,0,0,0,0,0,0,0,0,G28,0,0,0,~
0,0,0,0,0,0,0,0,0)';$S;
    'VSS_G31':'(0,0,0,0,0,0,0,0,0,0,0,0,0,0,0,0,0,0,0,0,0,0,0,0,0,0,0,G31,0,0,0,~
0,0,0,0,0,0,0,0,0)';$S;
    'VSS_G34':'(0,0,0,0,0,0,0,0,0,0,0,0,0,0,0,0,0,0,0,0,0,0,0,0,0,0,0,G34,0,0,0,~
0,0,0,0,0,0,0,0,0)';$S;
    'VSS_G42':'(0,0,0,0,0,0,0,0,0,0,0,0,0,0,0,0,0,0,0,0,0,0,0,0,0,0,0,G42,0,0,0,~
0,0,0,0,0,0,0,0,0)';$S;
    'VSS_G45':'(0,0,0,0,0,0,0,0,0,0,0,0,0,0,0,0,0,0,0,0,0,0,0,0,0,0,0,G45,0,0,0,~
0,0,0,0,0,0,0,0,0)';$S;
    'VSS_G48':'(0,0,0,0,0,0,0,0,0,0,0,0,0,0,0,0,0,0,0,0,0,0,0,0,0,0,0,G48,0,0,0,~
0,0,0,0,0,0,0,0,0)';$S;
    'VSS_G51':'(0,0,0,0,0,0,0,0,0,0,0,0,0,0,0,0,0,0,0,0,0,0,0,0,0,0,0,G51,0,0,0,~
0,0,0,0,0,0,0,0,0)';$S;
    'VSS_G54':'(0,0,0,0,0,0,0,0,0,0,0,0,0,0,0,0,0,0,0,0,0,0,0,0,0,0,0,G54,0,0,0,~
0,0,0,0,0,0,0,0,0)';$S;
    'VSS_G56':'(0,0,0,0,0,0,0,0,0,0,0,0,0,0,0,0,0,0,0,0,0,0,0,0,0,0,0,G56,0,0,0,~
0,0,0,0,0,0,0,0,0)';$S;
    'VSS_G58':'(0,0,0,0,0,0,0,0,0,0,0,0,0,0,0,0,0,0,0,0,0,0,0,0,0,0,0,G58,0,0,0,~
0,0,0,0,0,0,0,0,0)';$S;
    'VSS_G61':'(0,0,0,0,0,0,0,0,0,0,0,0,0,0,0,0,0,0,0,0,0,0,0,0,0,0,0,G61,0,0,0,~
0,0,0,0,0,0,0,0,0)';$S;
    'VSS_G63':'(0,0,0,0,0,0,0,0,0,0,0,0,0,0,0,0,0,0,0,0,0,0,0,0,0,0,0,G63,0,0,0,~
0,0,0,0,0,0,0,0,0)';$S;
    'VSS_G65':'(0,0,0,0,0,0,0,0,0,0,0,0,0,0,0,0,0,0,0,0,0,0,0,0,0,0,0,G65,0,0,0,~
0,0,0,0,0,0,0,0,0)';$S;
    'VSS_G68':'(0,0,0,0,0,0,0,0,0,0,0,0,0,0,0,0,0,0,0,0,0,0,0,0,0,0,0,G68,0,0,0,~
0,0,0,0,0,0,0,0,0)';$S;
    'VSS_G70':'(0,0,0,0,0,0,0,0,0,0,0,0,0,0,0,0,0,0,0,0,0,0,0,0,0,0,0,G70,0,0,0,~
0,0,0,0,0,0,0,0,0)';$S;
    'VSS_G72':'(0,0,0,0,0,0,0,0,0,0,0,0,0,0,0,0,0,0,0,0,0,0,0,0,0,0,0,G72,0,0,0,~
0,0,0,0,0,0,0,0,0)';$S;
    'VSS_G75':'(0,0,0,0,0,0,0,0,0,0,0,0,0,0,0,0,0,0,0,0,0,0,0,0,0,0,0,G75,0,0,0,~
0,0,0,0,0,0,0,0,0)';$S;
    'VSS_H3':'(0,0,0,0,0,0,0,0,0,0,0,0,0,0,0,0,0,0,0,0,0,0,0,0,0,0,0,H3,0,0,0,0,~
0,0,0,0,0,0,0,0)';$S;
    'VSS_H8':'(0,0,0,0,0,0,0,0,0,0,0,0,0,0,0,0,0,0,0,0,0,0,0,0,0,0,0,H8,0,0,0,0,~
0,0,0,0,0,0,0,0)';$S;
    'VSS_H10':'(0,0,0,0,0,0,0,0,0,0,0,0,0,0,0,0,0,0,0,0,0,0,0,0,0,0,0,H10,0,0,0,~
0,0,0,0,0,0,0,0,0)';$S;
    'VSS_H15':'(0,0,0,0,0,0,0,0,0,0,0,0,0,0,0,0,0,0,0,0,0,0,0,0,0,0,0,H15,0,0,0,~
0,0,0,0,0,0,0,0,0)';$S;
    'VSS_H17':'(0,0,0,0,0,0,0,0,0,0,0,0,0,0,0,0,0,0,0,0,0,0,0,0,0,0,0,H17,0,0,0,~
0,0,0,0,0,0,0,0,0)';$S;
    'VSS_H22':'(0,0,0,0,0,0,0,0,0,0,0,0,0,0,0,0,0,0,0,0,0,0,0,0,0,0,0,H22,0,0,0,~
0,0,0,0,0,0,0,0,0)';$S;
    'VSS_H25':'(0,0,0,0,0,0,0,0,0,0,0,0,0,0,0,0,0,0,0,0,0,0,0,0,0,0,0,H25,0,0,0,~
0,0,0,0,0,0,0,0,0)';$S;
    'VSS_H28':'(0,0,0,0,0,0,0,0,0,0,0,0,0,0,0,0,0,0,0,0,0,0,0,0,0,0,0,H28,0,0,0,~
0,0,0,0,0,0,0,0,0)';$S;
    'VSS_H31':'(0,0,0,0,0,0,0,0,0,0,0,0,0,0,0,0,0,0,0,0,0,0,0,0,0,0,0,H31,0,0,0,~
0,0,0,0,0,0,0,0,0)';$S;
    'VSS_H34':'(0,0,0,0,0,0,0,0,0,0,0,0,0,0,0,0,0,0,0,0,0,0,0,0,0,0,0,H34,0,0,0,~
0,0,0,0,0,0,0,0,0)';$S;
    'VSS_R48':'(0,0,0,0,0,0,0,0,0,0,0,0,0,0,0,0,0,0,0,0,0,0,0,0,0,0,0,0,R48,0,0,~
0,0,0,0,0,0,0,0,0)';$S;
    'VSS_R51':'(0,0,0,0,0,0,0,0,0,0,0,0,0,0,0,0,0,0,0,0,0,0,0,0,0,0,0,0,R51,0,0,~
0,0,0,0,0,0,0,0,0)';$S;
    'VSS_R54':'(0,0,0,0,0,0,0,0,0,0,0,0,0,0,0,0,0,0,0,0,0,0,0,0,0,0,0,0,R54,0,0,~
0,0,0,0,0,0,0,0,0)';$S;
    'VSS_R56':'(0,0,0,0,0,0,0,0,0,0,0,0,0,0,0,0,0,0,0,0,0,0,0,0,0,0,0,0,R56,0,0,~
0,0,0,0,0,0,0,0,0)';$S;
    'VSS_R58':'(0,0,0,0,0,0,0,0,0,0,0,0,0,0,0,0,0,0,0,0,0,0,0,0,0,0,0,0,R58,0,0,~
0,0,0,0,0,0,0,0,0)';$S;
    'VSS_R61':'(0,0,0,0,0,0,0,0,0,0,0,0,0,0,0,0,0,0,0,0,0,0,0,0,0,0,0,0,R61,0,0,~
0,0,0,0,0,0,0,0,0)';$S;
    'VSS_R63':'(0,0,0,0,0,0,0,0,0,0,0,0,0,0,0,0,0,0,0,0,0,0,0,0,0,0,0,0,R63,0,0,~
0,0,0,0,0,0,0,0,0)';$S;
    'VSS_R65':'(0,0,0,0,0,0,0,0,0,0,0,0,0,0,0,0,0,0,0,0,0,0,0,0,0,0,0,0,R65,0,0,~
0,0,0,0,0,0,0,0,0)';$S;
    'VSS_R68':'(0,0,0,0,0,0,0,0,0,0,0,0,0,0,0,0,0,0,0,0,0,0,0,0,0,0,0,0,R68,0,0,~
0,0,0,0,0,0,0,0,0)';$S;
    'VSS_R70':'(0,0,0,0,0,0,0,0,0,0,0,0,0,0,0,0,0,0,0,0,0,0,0,0,0,0,0,0,R70,0,0,~
0,0,0,0,0,0,0,0,0)';$S;
    'VSS_R72':'(0,0,0,0,0,0,0,0,0,0,0,0,0,0,0,0,0,0,0,0,0,0,0,0,0,0,0,0,R72,0,0,~
0,0,0,0,0,0,0,0,0)';$S;
    'VSS_R75':'(0,0,0,0,0,0,0,0,0,0,0,0,0,0,0,0,0,0,0,0,0,0,0,0,0,0,0,0,R75,0,0,~
0,0,0,0,0,0,0,0,0)';$S;
    'VSS_T3':'(0,0,0,0,0,0,0,0,0,0,0,0,0,0,0,0,0,0,0,0,0,0,0,0,0,0,0,0,T3,0,0,0,~
0,0,0,0,0,0,0,0)';$S;
    'VSS_T5':'(0,0,0,0,0,0,0,0,0,0,0,0,0,0,0,0,0,0,0,0,0,0,0,0,0,0,0,0,T5,0,0,0,~
0,0,0,0,0,0,0,0)';$S;
    'VSS_T8':'(0,0,0,0,0,0,0,0,0,0,0,0,0,0,0,0,0,0,0,0,0,0,0,0,0,0,0,0,T8,0,0,0,~
0,0,0,0,0,0,0,0)';$S;
    'VSS_T10':'(0,0,0,0,0,0,0,0,0,0,0,0,0,0,0,0,0,0,0,0,0,0,0,0,0,0,0,0,T10,0,0,~
0,0,0,0,0,0,0,0,0)';$S;
    'VSS_T12':'(0,0,0,0,0,0,0,0,0,0,0,0,0,0,0,0,0,0,0,0,0,0,0,0,0,0,0,0,T12,0,0,~
0,0,0,0,0,0,0,0,0)';$S;
    'VSS_T15':'(0,0,0,0,0,0,0,0,0,0,0,0,0,0,0,0,0,0,0,0,0,0,0,0,0,0,0,0,T15,0,0,~
0,0,0,0,0,0,0,0,0)';$S;
    'VSS_T17':'(0,0,0,0,0,0,0,0,0,0,0,0,0,0,0,0,0,0,0,0,0,0,0,0,0,0,0,0,T17,0,0,~
0,0,0,0,0,0,0,0,0)';$S;
    'VSS_T19':'(0,0,0,0,0,0,0,0,0,0,0,0,0,0,0,0,0,0,0,0,0,0,0,0,0,0,0,0,T19,0,0,~
0,0,0,0,0,0,0,0,0)';$S;
    'VSS_T22':'(0,0,0,0,0,0,0,0,0,0,0,0,0,0,0,0,0,0,0,0,0,0,0,0,0,0,0,0,T22,0,0,~
0,0,0,0,0,0,0,0,0)';$S;
    'VSS_T25':'(0,0,0,0,0,0,0,0,0,0,0,0,0,0,0,0,0,0,0,0,0,0,0,0,0,0,0,0,T25,0,0,~
0,0,0,0,0,0,0,0,0)';$S;
    'VSS_T28':'(0,0,0,0,0,0,0,0,0,0,0,0,0,0,0,0,0,0,0,0,0,0,0,0,0,0,0,0,T28,0,0,~
0,0,0,0,0,0,0,0,0)';$S;
    'VSS_T31':'(0,0,0,0,0,0,0,0,0,0,0,0,0,0,0,0,0,0,0,0,0,0,0,0,0,0,0,0,T31,0,0,~
0,0,0,0,0,0,0,0,0)';$S;
    'VSS_T34':'(0,0,0,0,0,0,0,0,0,0,0,0,0,0,0,0,0,0,0,0,0,0,0,0,0,0,0,0,T34,0,0,~
0,0,0,0,0,0,0,0,0)';$S;
    'VSS_T37':'(0,0,0,0,0,0,0,0,0,0,0,0,0,0,0,0,0,0,0,0,0,0,0,0,0,0,0,0,T37,0,0,~
0,0,0,0,0,0,0,0,0)';$S;
    'VSS_T39':'(0,0,0,0,0,0,0,0,0,0,0,0,0,0,0,0,0,0,0,0,0,0,0,0,0,0,0,0,T39,0,0,~
0,0,0,0,0,0,0,0,0)';$S;
    'VSS_T42':'(0,0,0,0,0,0,0,0,0,0,0,0,0,0,0,0,0,0,0,0,0,0,0,0,0,0,0,0,T42,0,0,~
0,0,0,0,0,0,0,0,0)';$S;
    'VSS_T45':'(0,0,0,0,0,0,0,0,0,0,0,0,0,0,0,0,0,0,0,0,0,0,0,0,0,0,0,0,T45,0,0,~
0,0,0,0,0,0,0,0,0)';$S;
    'VSS_T48':'(0,0,0,0,0,0,0,0,0,0,0,0,0,0,0,0,0,0,0,0,0,0,0,0,0,0,0,0,T48,0,0,~
0,0,0,0,0,0,0,0,0)';$S;
    'VSS_T51':'(0,0,0,0,0,0,0,0,0,0,0,0,0,0,0,0,0,0,0,0,0,0,0,0,0,0,0,0,T51,0,0,~
0,0,0,0,0,0,0,0,0)';$S;
    'VSS_T54':'(0,0,0,0,0,0,0,0,0,0,0,0,0,0,0,0,0,0,0,0,0,0,0,0,0,0,0,0,T54,0,0,~
0,0,0,0,0,0,0,0,0)';$S;
    'VSS_T57':'(0,0,0,0,0,0,0,0,0,0,0,0,0,0,0,0,0,0,0,0,0,0,0,0,0,0,0,0,T57,0,0,~
0,0,0,0,0,0,0,0,0)';$S;
    'VSS_T59':'(0,0,0,0,0,0,0,0,0,0,0,0,0,0,0,0,0,0,0,0,0,0,0,0,0,0,0,0,T59,0,0,~
0,0,0,0,0,0,0,0,0)';$S;
    'VSS_T61':'(0,0,0,0,0,0,0,0,0,0,0,0,0,0,0,0,0,0,0,0,0,0,0,0,0,0,0,0,T61,0,0,~
0,0,0,0,0,0,0,0,0)';$S;
    'VSS_T64':'(0,0,0,0,0,0,0,0,0,0,0,0,0,0,0,0,0,0,0,0,0,0,0,0,0,0,0,0,T64,0,0,~
0,0,0,0,0,0,0,0,0)';$S;
    'VSS_J15':'(0,0,0,0,0,0,0,0,0,0,0,0,0,0,0,0,0,0,0,0,0,0,0,0,0,0,0,0,J15,0,0,~
0,0,0,0,0,0,0,0,0)';$S;
    'VSS_J18':'(0,0,0,0,0,0,0,0,0,0,0,0,0,0,0,0,0,0,0,0,0,0,0,0,0,0,0,0,J18,0,0,~
0,0,0,0,0,0,0,0,0)';$S;
    'VSS_J20':'(0,0,0,0,0,0,0,0,0,0,0,0,0,0,0,0,0,0,0,0,0,0,0,0,0,0,0,0,J20,0,0,~
0,0,0,0,0,0,0,0,0)';$S;
    'VSS_J22':'(0,0,0,0,0,0,0,0,0,0,0,0,0,0,0,0,0,0,0,0,0,0,0,0,0,0,0,0,J22,0,0,~
0,0,0,0,0,0,0,0,0)';$S;
    'VSS_J25':'(0,0,0,0,0,0,0,0,0,0,0,0,0,0,0,0,0,0,0,0,0,0,0,0,0,0,0,0,J25,0,0,~
0,0,0,0,0,0,0,0,0)';$S;
    'VSS_J28':'(0,0,0,0,0,0,0,0,0,0,0,0,0,0,0,0,0,0,0,0,0,0,0,0,0,0,0,0,J28,0,0,~
0,0,0,0,0,0,0,0,0)';$S;
    'VSS_J31':'(0,0,0,0,0,0,0,0,0,0,0,0,0,0,0,0,0,0,0,0,0,0,0,0,0,0,0,0,J31,0,0,~
0,0,0,0,0,0,0,0,0)';$S;
    'VSS_J34':'(0,0,0,0,0,0,0,0,0,0,0,0,0,0,0,0,0,0,0,0,0,0,0,0,0,0,0,0,J34,0,0,~
0,0,0,0,0,0,0,0,0)';$S;
    'VSS_J42':'(0,0,0,0,0,0,0,0,0,0,0,0,0,0,0,0,0,0,0,0,0,0,0,0,0,0,0,0,J42,0,0,~
0,0,0,0,0,0,0,0,0)';$S;
    'VSS_J45':'(0,0,0,0,0,0,0,0,0,0,0,0,0,0,0,0,0,0,0,0,0,0,0,0,0,0,0,0,J45,0,0,~
0,0,0,0,0,0,0,0,0)';$S;
    'VSS_J48':'(0,0,0,0,0,0,0,0,0,0,0,0,0,0,0,0,0,0,0,0,0,0,0,0,0,0,0,0,J48,0,0,~
0,0,0,0,0,0,0,0,0)';$S;
    'VSS_J51':'(0,0,0,0,0,0,0,0,0,0,0,0,0,0,0,0,0,0,0,0,0,0,0,0,0,0,0,0,J51,0,0,~
0,0,0,0,0,0,0,0,0)';$S;
    'VSS_J54':'(0,0,0,0,0,0,0,0,0,0,0,0,0,0,0,0,0,0,0,0,0,0,0,0,0,0,0,0,J54,0,0,~
0,0,0,0,0,0,0,0,0)';$S;
    'VSS_J56':'(0,0,0,0,0,0,0,0,0,0,0,0,0,0,0,0,0,0,0,0,0,0,0,0,0,0,0,0,J56,0,0,~
0,0,0,0,0,0,0,0,0)';$S;
    'VSS_J58':'(0,0,0,0,0,0,0,0,0,0,0,0,0,0,0,0,0,0,0,0,0,0,0,0,0,0,0,0,J58,0,0,~
0,0,0,0,0,0,0,0,0)';$S;
    'VSS_J61':'(0,0,0,0,0,0,0,0,0,0,0,0,0,0,0,0,0,0,0,0,0,0,0,0,0,0,0,0,J61,0,0,~
0,0,0,0,0,0,0,0,0)';$S;
    'VSS_J63':'(0,0,0,0,0,0,0,0,0,0,0,0,0,0,0,0,0,0,0,0,0,0,0,0,0,0,0,0,J63,0,0,~
0,0,0,0,0,0,0,0,0)';$S;
    'VSS_J65':'(0,0,0,0,0,0,0,0,0,0,0,0,0,0,0,0,0,0,0,0,0,0,0,0,0,0,0,0,J65,0,0,~
0,0,0,0,0,0,0,0,0)';$S;
    'VSS_J68':'(0,0,0,0,0,0,0,0,0,0,0,0,0,0,0,0,0,0,0,0,0,0,0,0,0,0,0,0,J68,0,0,~
0,0,0,0,0,0,0,0,0)';$S;
    'VSS_J70':'(0,0,0,0,0,0,0,0,0,0,0,0,0,0,0,0,0,0,0,0,0,0,0,0,0,0,0,0,J70,0,0,~
0,0,0,0,0,0,0,0,0)';$S;
    'VSS_J72':'(0,0,0,0,0,0,0,0,0,0,0,0,0,0,0,0,0,0,0,0,0,0,0,0,0,0,0,0,J72,0,0,~
0,0,0,0,0,0,0,0,0)';$S;
    'VSS_J75':'(0,0,0,0,0,0,0,0,0,0,0,0,0,0,0,0,0,0,0,0,0,0,0,0,0,0,0,0,J75,0,0,~
0,0,0,0,0,0,0,0,0)';$S;
    'VSS_K3':'(0,0,0,0,0,0,0,0,0,0,0,0,0,0,0,0,0,0,0,0,0,0,0,0,0,0,0,0,K3,0,0,0,~
0,0,0,0,0,0,0,0)';$S;
    'VSS_K5':'(0,0,0,0,0,0,0,0,0,0,0,0,0,0,0,0,0,0,0,0,0,0,0,0,0,0,0,0,K5,0,0,0,~
0,0,0,0,0,0,0,0)';$S;
    'VSS_K8':'(0,0,0,0,0,0,0,0,0,0,0,0,0,0,0,0,0,0,0,0,0,0,0,0,0,0,0,0,K8,0,0,0,~
0,0,0,0,0,0,0,0)';$S;
    'VSS_K10':'(0,0,0,0,0,0,0,0,0,0,0,0,0,0,0,0,0,0,0,0,0,0,0,0,0,0,0,0,K10,0,0,~
0,0,0,0,0,0,0,0,0)';$S;
    'VSS_K12':'(0,0,0,0,0,0,0,0,0,0,0,0,0,0,0,0,0,0,0,0,0,0,0,0,0,0,0,0,K12,0,0,~
0,0,0,0,0,0,0,0,0)';$S;
    'VSS_K15':'(0,0,0,0,0,0,0,0,0,0,0,0,0,0,0,0,0,0,0,0,0,0,0,0,0,0,0,0,K15,0,0,~
0,0,0,0,0,0,0,0,0)';$S;
    'VSS_K17':'(0,0,0,0,0,0,0,0,0,0,0,0,0,0,0,0,0,0,0,0,0,0,0,0,0,0,0,0,K17,0,0,~
0,0,0,0,0,0,0,0,0)';$S;
    'VSS_K19':'(0,0,0,0,0,0,0,0,0,0,0,0,0,0,0,0,0,0,0,0,0,0,0,0,0,0,0,0,K19,0,0,~
0,0,0,0,0,0,0,0,0)';$S;
    'VSS_K24':'(0,0,0,0,0,0,0,0,0,0,0,0,0,0,0,0,0,0,0,0,0,0,0,0,0,0,0,0,K24,0,0,~
0,0,0,0,0,0,0,0,0)';$S;
    'VSS_K25':'(0,0,0,0,0,0,0,0,0,0,0,0,0,0,0,0,0,0,0,0,0,0,0,0,0,0,0,0,K25,0,0,~
0,0,0,0,0,0,0,0,0)';$S;
    'VSS_K26':'(0,0,0,0,0,0,0,0,0,0,0,0,0,0,0,0,0,0,0,0,0,0,0,0,0,0,0,0,K26,0,0,~
0,0,0,0,0,0,0,0,0)';$S;
    'VSS_K27':'(0,0,0,0,0,0,0,0,0,0,0,0,0,0,0,0,0,0,0,0,0,0,0,0,0,0,0,0,K27,0,0,~
0,0,0,0,0,0,0,0,0)';$S;
    'VSS_K28':'(0,0,0,0,0,0,0,0,0,0,0,0,0,0,0,0,0,0,0,0,0,0,0,0,0,0,0,0,K28,0,0,~
0,0,0,0,0,0,0,0,0)';$S;
    'VSS_K29':'(0,0,0,0,0,0,0,0,0,0,0,0,0,0,0,0,0,0,0,0,0,0,0,0,0,0,0,0,K29,0,0,~
0,0,0,0,0,0,0,0,0)';$S;
    'VSS_K30':'(0,0,0,0,0,0,0,0,0,0,0,0,0,0,0,0,0,0,0,0,0,0,0,0,0,0,0,0,K30,0,0,~
0,0,0,0,0,0,0,0,0)';$S;
    'VSS_K31':'(0,0,0,0,0,0,0,0,0,0,0,0,0,0,0,0,0,0,0,0,0,0,0,0,0,0,0,0,K31,0,0,~
0,0,0,0,0,0,0,0,0)';$S;
    'VSS_K32':'(0,0,0,0,0,0,0,0,0,0,0,0,0,0,0,0,0,0,0,0,0,0,0,0,0,0,0,0,K32,0,0,~
0,0,0,0,0,0,0,0,0)';$S;
    'VSS_K33':'(0,0,0,0,0,0,0,0,0,0,0,0,0,0,0,0,0,0,0,0,0,0,0,0,0,0,0,0,K33,0,0,~
0,0,0,0,0,0,0,0,0)';$S;
    'VSS_K34':'(0,0,0,0,0,0,0,0,0,0,0,0,0,0,0,0,0,0,0,0,0,0,0,0,0,0,0,0,K34,0,0,~
0,0,0,0,0,0,0,0,0)';$S;
    'VSS_K37':'(0,0,0,0,0,0,0,0,0,0,0,0,0,0,0,0,0,0,0,0,0,0,0,0,0,0,0,0,K37,0,0,~
0,0,0,0,0,0,0,0,0)';$S;
    'VSS_K39':'(0,0,0,0,0,0,0,0,0,0,0,0,0,0,0,0,0,0,0,0,0,0,0,0,0,0,0,0,K39,0,0,~
0,0,0,0,0,0,0,0,0)';$S;
    'VSS_K42':'(0,0,0,0,0,0,0,0,0,0,0,0,0,0,0,0,0,0,0,0,0,0,0,0,0,0,0,0,K42,0,0,~
0,0,0,0,0,0,0,0,0)';$S;
    'VSS_K43':'(0,0,0,0,0,0,0,0,0,0,0,0,0,0,0,0,0,0,0,0,0,0,0,0,0,0,0,0,K43,0,0,~
0,0,0,0,0,0,0,0,0)';$S;
    'VSS_K44':'(0,0,0,0,0,0,0,0,0,0,0,0,0,0,0,0,0,0,0,0,0,0,0,0,0,0,0,0,K44,0,0,~
0,0,0,0,0,0,0,0,0)';$S;
    'VSS_K45':'(0,0,0,0,0,0,0,0,0,0,0,0,0,0,0,0,0,0,0,0,0,0,0,0,0,0,0,0,K45,0,0,~
0,0,0,0,0,0,0,0,0)';$S;
    'VSS_K46':'(0,0,0,0,0,0,0,0,0,0,0,0,0,0,0,0,0,0,0,0,0,0,0,0,0,0,0,0,K46,0,0,~
0,0,0,0,0,0,0,0,0)';$S;
    'VSS_K47':'(0,0,0,0,0,0,0,0,0,0,0,0,0,0,0,0,0,0,0,0,0,0,0,0,0,0,0,0,K47,0,0,~
0,0,0,0,0,0,0,0,0)';$S;
    'VSS_K48':'(0,0,0,0,0,0,0,0,0,0,0,0,0,0,0,0,0,0,0,0,0,0,0,0,0,0,0,0,K48,0,0,~
0,0,0,0,0,0,0,0,0)';$S;
    'VSS_K49':'(0,0,0,0,0,0,0,0,0,0,0,0,0,0,0,0,0,0,0,0,0,0,0,0,0,0,0,0,K49,0,0,~
0,0,0,0,0,0,0,0,0)';$S;
    'VSS_K50':'(0,0,0,0,0,0,0,0,0,0,0,0,0,0,0,0,0,0,0,0,0,0,0,0,0,0,0,0,K50,0,0,~
0,0,0,0,0,0,0,0,0)';$S;
    'VSS_K51':'(0,0,0,0,0,0,0,0,0,0,0,0,0,0,0,0,0,0,0,0,0,0,0,0,0,0,0,0,K51,0,0,~
0,0,0,0,0,0,0,0,0)';$S;
    'VSS_K52':'(0,0,0,0,0,0,0,0,0,0,0,0,0,0,0,0,0,0,0,0,0,0,0,0,0,0,0,0,K52,0,0,~
0,0,0,0,0,0,0,0,0)';$S;
    'VSS_K53':'(0,0,0,0,0,0,0,0,0,0,0,0,0,0,0,0,0,0,0,0,0,0,0,0,0,0,0,0,K53,0,0,~
0,0,0,0,0,0,0,0,0)';$S;
    'VSS_K57':'(0,0,0,0,0,0,0,0,0,0,0,0,0,0,0,0,0,0,0,0,0,0,0,0,0,0,0,0,K57,0,0,~
0,0,0,0,0,0,0,0,0)';$S;
    'VSS_K61':'(0,0,0,0,0,0,0,0,0,0,0,0,0,0,0,0,0,0,0,0,0,0,0,0,0,0,0,0,K61,0,0,~
0,0,0,0,0,0,0,0,0)';$S;
    'VSS_K64':'(0,0,0,0,0,0,0,0,0,0,0,0,0,0,0,0,0,0,0,0,0,0,0,0,0,0,0,0,K64,0,0,~
0,0,0,0,0,0,0,0,0)';$S;
    'VSS_K66':'(0,0,0,0,0,0,0,0,0,0,0,0,0,0,0,0,0,0,0,0,0,0,0,0,0,0,0,0,K66,0,0,~
0,0,0,0,0,0,0,0,0)';$S;
    'VSS_K68':'(0,0,0,0,0,0,0,0,0,0,0,0,0,0,0,0,0,0,0,0,0,0,0,0,0,0,0,0,K68,0,0,~
0,0,0,0,0,0,0,0,0)';$S;
    'VSS_K71':'(0,0,0,0,0,0,0,0,0,0,0,0,0,0,0,0,0,0,0,0,0,0,0,0,0,0,0,0,K71,0,0,~
0,0,0,0,0,0,0,0,0)';$S;
    'VSS_K73':'(0,0,0,0,0,0,0,0,0,0,0,0,0,0,0,0,0,0,0,0,0,0,0,0,0,0,0,0,K73,0,0,~
0,0,0,0,0,0,0,0,0)';$S;
    'VSS_L1':'(0,0,0,0,0,0,0,0,0,0,0,0,0,0,0,0,0,0,0,0,0,0,0,0,0,0,0,0,L1,0,0,0,~
0,0,0,0,0,0,0,0)';$S;
    'VSS_L6':'(0,0,0,0,0,0,0,0,0,0,0,0,0,0,0,0,0,0,0,0,0,0,0,0,0,0,0,0,L6,0,0,0,~
0,0,0,0,0,0,0,0)';$S;
    'VSS_L8':'(0,0,0,0,0,0,0,0,0,0,0,0,0,0,0,0,0,0,0,0,0,0,0,0,0,0,0,0,L8,0,0,0,~
0,0,0,0,0,0,0,0)';$S;
    'VSS_L13':'(0,0,0,0,0,0,0,0,0,0,0,0,0,0,0,0,0,0,0,0,0,0,0,0,0,0,0,0,L13,0,0,~
0,0,0,0,0,0,0,0,0)';$S;
    'VSS_L15':'(0,0,0,0,0,0,0,0,0,0,0,0,0,0,0,0,0,0,0,0,0,0,0,0,0,0,0,0,L15,0,0,~
0,0,0,0,0,0,0,0,0)';$S;
    'VSS_L20':'(0,0,0,0,0,0,0,0,0,0,0,0,0,0,0,0,0,0,0,0,0,0,0,0,0,0,0,0,L20,0,0,~
0,0,0,0,0,0,0,0,0)';$S;
    'VSS_L22':'(0,0,0,0,0,0,0,0,0,0,0,0,0,0,0,0,0,0,0,0,0,0,0,0,0,0,0,0,L22,0,0,~
0,0,0,0,0,0,0,0,0)';$S;
    'VSS_L25':'(0,0,0,0,0,0,0,0,0,0,0,0,0,0,0,0,0,0,0,0,0,0,0,0,0,0,0,0,L25,0,0,~
0,0,0,0,0,0,0,0,0)';$S;
    'VSS_L28':'(0,0,0,0,0,0,0,0,0,0,0,0,0,0,0,0,0,0,0,0,0,0,0,0,0,0,0,0,L28,0,0,~
0,0,0,0,0,0,0,0,0)';$S;
    'VSS_L31':'(0,0,0,0,0,0,0,0,0,0,0,0,0,0,0,0,0,0,0,0,0,0,0,0,0,0,0,0,L31,0,0,~
0,0,0,0,0,0,0,0,0)';$S;
    'VSS_L34':'(0,0,0,0,0,0,0,0,0,0,0,0,0,0,0,0,0,0,0,0,0,0,0,0,0,0,0,0,L34,0,0,~
0,0,0,0,0,0,0,0,0)';$S;
    'VSS_L35':'(0,0,0,0,0,0,0,0,0,0,0,0,0,0,0,0,0,0,0,0,0,0,0,0,0,0,0,0,L35,0,0,~
0,0,0,0,0,0,0,0,0)';$S;
    'VSS_L36':'(0,0,0,0,0,0,0,0,0,0,0,0,0,0,0,0,0,0,0,0,0,0,0,0,0,0,0,0,L36,0,0,~
0,0,0,0,0,0,0,0,0)';$S;
    'VSS_L40':'(0,0,0,0,0,0,0,0,0,0,0,0,0,0,0,0,0,0,0,0,0,0,0,0,0,0,0,0,L40,0,0,~
0,0,0,0,0,0,0,0,0)';$S;
    'VSS_L41':'(0,0,0,0,0,0,0,0,0,0,0,0,0,0,0,0,0,0,0,0,0,0,0,0,0,0,0,0,L41,0,0,~
0,0,0,0,0,0,0,0,0)';$S;
    'VSS_L42':'(0,0,0,0,0,0,0,0,0,0,0,0,0,0,0,0,0,0,0,0,0,0,0,0,0,0,0,0,L42,0,0,~
0,0,0,0,0,0,0,0,0)';$S;
    'VSS_L45':'(0,0,0,0,0,0,0,0,0,0,0,0,0,0,0,0,0,0,0,0,0,0,0,0,0,0,0,0,L45,0,0,~
0,0,0,0,0,0,0,0,0)';$S;
    'VSS_L48':'(0,0,0,0,0,0,0,0,0,0,0,0,0,0,0,0,0,0,0,0,0,0,0,0,0,0,0,0,L48,0,0,~
0,0,0,0,0,0,0,0,0)';$S;
    'VSS_L51':'(0,0,0,0,0,0,0,0,0,0,0,0,0,0,0,0,0,0,0,0,0,0,0,0,0,0,0,0,L51,0,0,~
0,0,0,0,0,0,0,0,0)';$S;
    'VSS_L54':'(0,0,0,0,0,0,0,0,0,0,0,0,0,0,0,0,0,0,0,0,0,0,0,0,0,0,0,0,L54,0,0,~
0,0,0,0,0,0,0,0,0)';$S;
    'VSS_L56':'(0,0,0,0,0,0,0,0,0,0,0,0,0,0,0,0,0,0,0,0,0,0,0,0,0,0,0,0,L56,0,0,~
0,0,0,0,0,0,0,0,0)';$S;
    'VSS_L61':'(0,0,0,0,0,0,0,0,0,0,0,0,0,0,0,0,0,0,0,0,0,0,0,0,0,0,0,0,L61,0,0,~
0,0,0,0,0,0,0,0,0)';$S;
    'VSS_L63':'(0,0,0,0,0,0,0,0,0,0,0,0,0,0,0,0,0,0,0,0,0,0,0,0,0,0,0,0,L63,0,0,~
0,0,0,0,0,0,0,0,0)';$S;
    'VSS_L68':'(0,0,0,0,0,0,0,0,0,0,0,0,0,0,0,0,0,0,0,0,0,0,0,0,0,0,0,0,L68,0,0,~
0,0,0,0,0,0,0,0,0)';$S;
    'VSS_L70':'(0,0,0,0,0,0,0,0,0,0,0,0,0,0,0,0,0,0,0,0,0,0,0,0,0,0,0,0,L70,0,0,~
0,0,0,0,0,0,0,0,0)';$S;
    'VSS_L75':'(0,0,0,0,0,0,0,0,0,0,0,0,0,0,0,0,0,0,0,0,0,0,0,0,0,0,0,0,L75,0,0,~
0,0,0,0,0,0,0,0,0)';$S;
    'VSS_M3':'(0,0,0,0,0,0,0,0,0,0,0,0,0,0,0,0,0,0,0,0,0,0,0,0,0,0,0,0,M3,0,0,0,~
0,0,0,0,0,0,0,0)';$S;
    'VSS_M5':'(0,0,0,0,0,0,0,0,0,0,0,0,0,0,0,0,0,0,0,0,0,0,0,0,0,0,0,0,M5,0,0,0,~
0,0,0,0,0,0,0,0)';$S;
    'VSS_M8':'(0,0,0,0,0,0,0,0,0,0,0,0,0,0,0,0,0,0,0,0,0,0,0,0,0,0,0,0,M8,0,0,0,~
0,0,0,0,0,0,0,0)';$S;
    'VSS_M10':'(0,0,0,0,0,0,0,0,0,0,0,0,0,0,0,0,0,0,0,0,0,0,0,0,0,0,0,0,M10,0,0,~
0,0,0,0,0,0,0,0,0)';$S;
    'VSS_M12':'(0,0,0,0,0,0,0,0,0,0,0,0,0,0,0,0,0,0,0,0,0,0,0,0,0,0,0,0,M12,0,0,~
0,0,0,0,0,0,0,0,0)';$S;
    'VSS_M15':'(0,0,0,0,0,0,0,0,0,0,0,0,0,0,0,0,0,0,0,0,0,0,0,0,0,0,0,0,M15,0,0,~
0,0,0,0,0,0,0,0,0)';$S;
    'VSS_M17':'(0,0,0,0,0,0,0,0,0,0,0,0,0,0,0,0,0,0,0,0,0,0,0,0,0,0,0,0,M17,0,0,~
0,0,0,0,0,0,0,0,0)';$S;
    'VSS_M19':'(0,0,0,0,0,0,0,0,0,0,0,0,0,0,0,0,0,0,0,0,0,0,0,0,0,0,0,0,M19,0,0,~
0,0,0,0,0,0,0,0,0)';$S;
    'VSS_M22':'(0,0,0,0,0,0,0,0,0,0,0,0,0,0,0,0,0,0,0,0,0,0,0,0,0,0,0,0,M22,0,0,~
0,0,0,0,0,0,0,0,0)';$S;
    'VSS_M25':'(0,0,0,0,0,0,0,0,0,0,0,0,0,0,0,0,0,0,0,0,0,0,0,0,0,0,0,0,M25,0,0,~
0,0,0,0,0,0,0,0,0)';$S;
    'VSS_M28':'(0,0,0,0,0,0,0,0,0,0,0,0,0,0,0,0,0,0,0,0,0,0,0,0,0,0,0,0,M28,0,0,~
0,0,0,0,0,0,0,0,0)';$S;
    'VSS_M31':'(0,0,0,0,0,0,0,0,0,0,0,0,0,0,0,0,0,0,0,0,0,0,0,0,0,0,0,0,M31,0,0,~
0,0,0,0,0,0,0,0,0)';$S;
    'VSS_M34':'(0,0,0,0,0,0,0,0,0,0,0,0,0,0,0,0,0,0,0,0,0,0,0,0,0,0,0,0,M34,0,0,~
0,0,0,0,0,0,0,0,0)';$S;
    'VSS_M37':'(0,0,0,0,0,0,0,0,0,0,0,0,0,0,0,0,0,0,0,0,0,0,0,0,0,0,0,0,M37,0,0,~
0,0,0,0,0,0,0,0,0)';$S;
    'VSS_M39':'(0,0,0,0,0,0,0,0,0,0,0,0,0,0,0,0,0,0,0,0,0,0,0,0,0,0,0,0,M39,0,0,~
0,0,0,0,0,0,0,0,0)';$S;
    'VSS_M42':'(0,0,0,0,0,0,0,0,0,0,0,0,0,0,0,0,0,0,0,0,0,0,0,0,0,0,0,0,M42,0,0,~
0,0,0,0,0,0,0,0,0)';$S;
    'VSS_M45':'(0,0,0,0,0,0,0,0,0,0,0,0,0,0,0,0,0,0,0,0,0,0,0,0,0,0,0,0,M45,0,0,~
0,0,0,0,0,0,0,0,0)';$S;
    'VSS_M48':'(0,0,0,0,0,0,0,0,0,0,0,0,0,0,0,0,0,0,0,0,0,0,0,0,0,0,0,0,M48,0,0,~
0,0,0,0,0,0,0,0,0)';$S;
    'VSS_M51':'(0,0,0,0,0,0,0,0,0,0,0,0,0,0,0,0,0,0,0,0,0,0,0,0,0,0,0,0,M51,0,0,~
0,0,0,0,0,0,0,0,0)';$S;
    'VSS_M54':'(0,0,0,0,0,0,0,0,0,0,0,0,0,0,0,0,0,0,0,0,0,0,0,0,0,0,0,0,M54,0,0,~
0,0,0,0,0,0,0,0,0)';$S;
    'VSS_M57':'(0,0,0,0,0,0,0,0,0,0,0,0,0,0,0,0,0,0,0,0,0,0,0,0,0,0,0,0,M57,0,0,~
0,0,0,0,0,0,0,0,0)';$S;
    'VSS_M59':'(0,0,0,0,0,0,0,0,0,0,0,0,0,0,0,0,0,0,0,0,0,0,0,0,0,0,0,0,M59,0,0,~
0,0,0,0,0,0,0,0,0)';$S;
    'VSS_M61':'(0,0,0,0,0,0,0,0,0,0,0,0,0,0,0,0,0,0,0,0,0,0,0,0,0,0,0,0,M61,0,0,~
0,0,0,0,0,0,0,0,0)';$S;
    'VSS_M64':'(0,0,0,0,0,0,0,0,0,0,0,0,0,0,0,0,0,0,0,0,0,0,0,0,0,0,0,0,M64,0,0,~
0,0,0,0,0,0,0,0,0)';$S;
    'VSS_M66':'(0,0,0,0,0,0,0,0,0,0,0,0,0,0,0,0,0,0,0,0,0,0,0,0,0,0,0,0,M66,0,0,~
0,0,0,0,0,0,0,0,0)';$S;
    'VSS_M68':'(0,0,0,0,0,0,0,0,0,0,0,0,0,0,0,0,0,0,0,0,0,0,0,0,0,0,0,0,M68,0,0,~
0,0,0,0,0,0,0,0,0)';$S;
    'VSS_M71':'(0,0,0,0,0,0,0,0,0,0,0,0,0,0,0,0,0,0,0,0,0,0,0,0,0,0,0,0,M71,0,0,~
0,0,0,0,0,0,0,0,0)';$S;
    'VSS_M73':'(0,0,0,0,0,0,0,0,0,0,0,0,0,0,0,0,0,0,0,0,0,0,0,0,0,0,0,0,M73,0,0,~
0,0,0,0,0,0,0,0,0)';$S;
    'VSS_N1':'(0,0,0,0,0,0,0,0,0,0,0,0,0,0,0,0,0,0,0,0,0,0,0,0,0,0,0,0,N1,0,0,0,~
0,0,0,0,0,0,0,0)';$S;
    'VSS_N4':'(0,0,0,0,0,0,0,0,0,0,0,0,0,0,0,0,0,0,0,0,0,0,0,0,0,0,0,0,N4,0,0,0,~
0,0,0,0,0,0,0,0)';$S;
    'VSS_N6':'(0,0,0,0,0,0,0,0,0,0,0,0,0,0,0,0,0,0,0,0,0,0,0,0,0,0,0,0,N6,0,0,0,~
0,0,0,0,0,0,0,0)';$S;
    'VSS_N8':'(0,0,0,0,0,0,0,0,0,0,0,0,0,0,0,0,0,0,0,0,0,0,0,0,0,0,0,0,N8,0,0,0,~
0,0,0,0,0,0,0,0)';$S;
    'VSS_N11':'(0,0,0,0,0,0,0,0,0,0,0,0,0,0,0,0,0,0,0,0,0,0,0,0,0,0,0,0,N11,0,0,~
0,0,0,0,0,0,0,0,0)';$S;
    'VSS_N13':'(0,0,0,0,0,0,0,0,0,0,0,0,0,0,0,0,0,0,0,0,0,0,0,0,0,0,0,0,N13,0,0,~
0,0,0,0,0,0,0,0,0)';$S;
    'VSS_N15':'(0,0,0,0,0,0,0,0,0,0,0,0,0,0,0,0,0,0,0,0,0,0,0,0,0,0,0,0,N15,0,0,~
0,0,0,0,0,0,0,0,0)';$S;
    'VSS_N18':'(0,0,0,0,0,0,0,0,0,0,0,0,0,0,0,0,0,0,0,0,0,0,0,0,0,0,0,0,N18,0,0,~
0,0,0,0,0,0,0,0,0)';$S;
    'VSS_N20':'(0,0,0,0,0,0,0,0,0,0,0,0,0,0,0,0,0,0,0,0,0,0,0,0,0,0,0,0,N20,0,0,~
0,0,0,0,0,0,0,0,0)';$S;
    'VSS_N22':'(0,0,0,0,0,0,0,0,0,0,0,0,0,0,0,0,0,0,0,0,0,0,0,0,0,0,0,0,N22,0,0,~
0,0,0,0,0,0,0,0,0)';$S;
    'VSS_N25':'(0,0,0,0,0,0,0,0,0,0,0,0,0,0,0,0,0,0,0,0,0,0,0,0,0,0,0,0,N25,0,0,~
0,0,0,0,0,0,0,0,0)';$S;
    'VSS_N28':'(0,0,0,0,0,0,0,0,0,0,0,0,0,0,0,0,0,0,0,0,0,0,0,0,0,0,0,0,N28,0,0,~
0,0,0,0,0,0,0,0,0)';$S;
    'VSS_N31':'(0,0,0,0,0,0,0,0,0,0,0,0,0,0,0,0,0,0,0,0,0,0,0,0,0,0,0,0,N31,0,0,~
0,0,0,0,0,0,0,0,0)';$S;
    'VSS_N34':'(0,0,0,0,0,0,0,0,0,0,0,0,0,0,0,0,0,0,0,0,0,0,0,0,0,0,0,0,N34,0,0,~
0,0,0,0,0,0,0,0,0)';$S;
    'VSS_N42':'(0,0,0,0,0,0,0,0,0,0,0,0,0,0,0,0,0,0,0,0,0,0,0,0,0,0,0,0,N42,0,0,~
0,0,0,0,0,0,0,0,0)';$S;
    'VSS_N45':'(0,0,0,0,0,0,0,0,0,0,0,0,0,0,0,0,0,0,0,0,0,0,0,0,0,0,0,0,N45,0,0,~
0,0,0,0,0,0,0,0,0)';$S;
    'VSS_N48':'(0,0,0,0,0,0,0,0,0,0,0,0,0,0,0,0,0,0,0,0,0,0,0,0,0,0,0,0,N48,0,0,~
0,0,0,0,0,0,0,0,0)';$S;
    'VSS_N51':'(0,0,0,0,0,0,0,0,0,0,0,0,0,0,0,0,0,0,0,0,0,0,0,0,0,0,0,0,N51,0,0,~
0,0,0,0,0,0,0,0,0)';$S;
    'VSS_N54':'(0,0,0,0,0,0,0,0,0,0,0,0,0,0,0,0,0,0,0,0,0,0,0,0,0,0,0,0,N54,0,0,~
0,0,0,0,0,0,0,0,0)';$S;
    'VSS_N56':'(0,0,0,0,0,0,0,0,0,0,0,0,0,0,0,0,0,0,0,0,0,0,0,0,0,0,0,0,N56,0,0,~
0,0,0,0,0,0,0,0,0)';$S;
    'VSS_N58':'(0,0,0,0,0,0,0,0,0,0,0,0,0,0,0,0,0,0,0,0,0,0,0,0,0,0,0,0,N58,0,0,~
0,0,0,0,0,0,0,0,0)';$S;
    'VSS_N61':'(0,0,0,0,0,0,0,0,0,0,0,0,0,0,0,0,0,0,0,0,0,0,0,0,0,0,0,0,N61,0,0,~
0,0,0,0,0,0,0,0,0)';$S;
    'VSS_N63':'(0,0,0,0,0,0,0,0,0,0,0,0,0,0,0,0,0,0,0,0,0,0,0,0,0,0,0,0,N63,0,0,~
0,0,0,0,0,0,0,0,0)';$S;
    'VSS_N65':'(0,0,0,0,0,0,0,0,0,0,0,0,0,0,0,0,0,0,0,0,0,0,0,0,0,0,0,0,N65,0,0,~
0,0,0,0,0,0,0,0,0)';$S;
    'VSS_N68':'(0,0,0,0,0,0,0,0,0,0,0,0,0,0,0,0,0,0,0,0,0,0,0,0,0,0,0,0,N68,0,0,~
0,0,0,0,0,0,0,0,0)';$S;
    'VSS_N70':'(0,0,0,0,0,0,0,0,0,0,0,0,0,0,0,0,0,0,0,0,0,0,0,0,0,0,0,0,N70,0,0,~
0,0,0,0,0,0,0,0,0)';$S;
    'VSS_N72':'(0,0,0,0,0,0,0,0,0,0,0,0,0,0,0,0,0,0,0,0,0,0,0,0,0,0,0,0,N72,0,0,~
0,0,0,0,0,0,0,0,0)';$S;
    'VSS_N75':'(0,0,0,0,0,0,0,0,0,0,0,0,0,0,0,0,0,0,0,0,0,0,0,0,0,0,0,0,N75,0,0,~
0,0,0,0,0,0,0,0,0)';$S;
    'VSS_P3':'(0,0,0,0,0,0,0,0,0,0,0,0,0,0,0,0,0,0,0,0,0,0,0,0,0,0,0,0,P3,0,0,0,~
0,0,0,0,0,0,0,0)';$S;
    'VSS_P8':'(0,0,0,0,0,0,0,0,0,0,0,0,0,0,0,0,0,0,0,0,0,0,0,0,0,0,0,0,P8,0,0,0,~
0,0,0,0,0,0,0,0)';$S;
    'VSS_P10':'(0,0,0,0,0,0,0,0,0,0,0,0,0,0,0,0,0,0,0,0,0,0,0,0,0,0,0,0,P10,0,0,~
0,0,0,0,0,0,0,0,0)';$S;
    'VSS_P15':'(0,0,0,0,0,0,0,0,0,0,0,0,0,0,0,0,0,0,0,0,0,0,0,0,0,0,0,0,P15,0,0,~
0,0,0,0,0,0,0,0,0)';$S;
    'VSS_P17':'(0,0,0,0,0,0,0,0,0,0,0,0,0,0,0,0,0,0,0,0,0,0,0,0,0,0,0,0,P17,0,0,~
0,0,0,0,0,0,0,0,0)';$S;
    'VSS_P23':'(0,0,0,0,0,0,0,0,0,0,0,0,0,0,0,0,0,0,0,0,0,0,0,0,0,0,0,0,P23,0,0,~
0,0,0,0,0,0,0,0,0)';$S;
    'VSS_P24':'(0,0,0,0,0,0,0,0,0,0,0,0,0,0,0,0,0,0,0,0,0,0,0,0,0,0,0,0,P24,0,0,~
0,0,0,0,0,0,0,0,0)';$S;
    'VSS_P26':'(0,0,0,0,0,0,0,0,0,0,0,0,0,0,0,0,0,0,0,0,0,0,0,0,0,0,0,0,P26,0,0,~
0,0,0,0,0,0,0,0,0)';$S;
    'VSS_P27':'(0,0,0,0,0,0,0,0,0,0,0,0,0,0,0,0,0,0,0,0,0,0,0,0,0,0,0,0,P27,0,0,~
0,0,0,0,0,0,0,0,0)';$S;
    'VSS_P28':'(0,0,0,0,0,0,0,0,0,0,0,0,0,0,0,0,0,0,0,0,0,0,0,0,0,0,0,0,P28,0,0,~
0,0,0,0,0,0,0,0,0)';$S;
    'VSS_P29':'(0,0,0,0,0,0,0,0,0,0,0,0,0,0,0,0,0,0,0,0,0,0,0,0,0,0,0,0,P29,0,0,~
0,0,0,0,0,0,0,0,0)';$S;
    'VSS_P30':'(0,0,0,0,0,0,0,0,0,0,0,0,0,0,0,0,0,0,0,0,0,0,0,0,0,0,0,0,P30,0,0,~
0,0,0,0,0,0,0,0,0)';$S;
    'VSS_P31':'(0,0,0,0,0,0,0,0,0,0,0,0,0,0,0,0,0,0,0,0,0,0,0,0,0,0,0,0,P31,0,0,~
0,0,0,0,0,0,0,0,0)';$S;
    'VSS_P32':'(0,0,0,0,0,0,0,0,0,0,0,0,0,0,0,0,0,0,0,0,0,0,0,0,0,0,0,0,P32,0,0,~
0,0,0,0,0,0,0,0,0)';$S;
    'VSS_P33':'(0,0,0,0,0,0,0,0,0,0,0,0,0,0,0,0,0,0,0,0,0,0,0,0,0,0,0,0,P33,0,0,~
0,0,0,0,0,0,0,0,0)';$S;
    'VSS_P34':'(0,0,0,0,0,0,0,0,0,0,0,0,0,0,0,0,0,0,0,0,0,0,0,0,0,0,0,0,P34,0,0,~
0,0,0,0,0,0,0,0,0)';$S;
    'VSS_P37':'(0,0,0,0,0,0,0,0,0,0,0,0,0,0,0,0,0,0,0,0,0,0,0,0,0,0,0,0,P37,0,0,~
0,0,0,0,0,0,0,0,0)';$S;
    'VSS_P39':'(0,0,0,0,0,0,0,0,0,0,0,0,0,0,0,0,0,0,0,0,0,0,0,0,0,0,0,0,P39,0,0,~
0,0,0,0,0,0,0,0,0)';$S;
    'VSS_P42':'(0,0,0,0,0,0,0,0,0,0,0,0,0,0,0,0,0,0,0,0,0,0,0,0,0,0,0,0,P42,0,0,~
0,0,0,0,0,0,0,0,0)';$S;
    'VSS_P43':'(0,0,0,0,0,0,0,0,0,0,0,0,0,0,0,0,0,0,0,0,0,0,0,0,0,0,0,0,P43,0,0,~
0,0,0,0,0,0,0,0,0)';$S;
    'VSS_P44':'(0,0,0,0,0,0,0,0,0,0,0,0,0,0,0,0,0,0,0,0,0,0,0,0,0,0,0,0,P44,0,0,~
0,0,0,0,0,0,0,0,0)';$S;
    'VSS_P45':'(0,0,0,0,0,0,0,0,0,0,0,0,0,0,0,0,0,0,0,0,0,0,0,0,0,0,0,0,P45,0,0,~
0,0,0,0,0,0,0,0,0)';$S;
    'VSS_P46':'(0,0,0,0,0,0,0,0,0,0,0,0,0,0,0,0,0,0,0,0,0,0,0,0,0,0,0,0,P46,0,0,~
0,0,0,0,0,0,0,0,0)';$S;
    'VSS_P47':'(0,0,0,0,0,0,0,0,0,0,0,0,0,0,0,0,0,0,0,0,0,0,0,0,0,0,0,0,P47,0,0,~
0,0,0,0,0,0,0,0,0)';$S;
    'VSS_P48':'(0,0,0,0,0,0,0,0,0,0,0,0,0,0,0,0,0,0,0,0,0,0,0,0,0,0,0,0,P48,0,0,~
0,0,0,0,0,0,0,0,0)';$S;
    'VSS_P49':'(0,0,0,0,0,0,0,0,0,0,0,0,0,0,0,0,0,0,0,0,0,0,0,0,0,0,0,0,P49,0,0,~
0,0,0,0,0,0,0,0,0)';$S;
    'VSS_P50':'(0,0,0,0,0,0,0,0,0,0,0,0,0,0,0,0,0,0,0,0,0,0,0,0,0,0,0,0,P50,0,0,~
0,0,0,0,0,0,0,0,0)';$S;
    'VSS_P51':'(0,0,0,0,0,0,0,0,0,0,0,0,0,0,0,0,0,0,0,0,0,0,0,0,0,0,0,0,P51,0,0,~
0,0,0,0,0,0,0,0,0)';$S;
    'VSS_P52':'(0,0,0,0,0,0,0,0,0,0,0,0,0,0,0,0,0,0,0,0,0,0,0,0,0,0,0,0,P52,0,0,~
0,0,0,0,0,0,0,0,0)';$S;
    'VSS_P53':'(0,0,0,0,0,0,0,0,0,0,0,0,0,0,0,0,0,0,0,0,0,0,0,0,0,0,0,0,P53,0,0,~
0,0,0,0,0,0,0,0,0)';$S;
    'VSS_P59':'(0,0,0,0,0,0,0,0,0,0,0,0,0,0,0,0,0,0,0,0,0,0,0,0,0,0,0,0,P59,0,0,~
0,0,0,0,0,0,0,0,0)';$S;
    'VSS_P61':'(0,0,0,0,0,0,0,0,0,0,0,0,0,0,0,0,0,0,0,0,0,0,0,0,0,0,0,0,P61,0,0,~
0,0,0,0,0,0,0,0,0)';$S;
    'VSS_P66':'(0,0,0,0,0,0,0,0,0,0,0,0,0,0,0,0,0,0,0,0,0,0,0,0,0,0,0,0,P66,0,0,~
0,0,0,0,0,0,0,0,0)';$S;
    'VSS_P73':'(0,0,0,0,0,0,0,0,0,0,0,0,0,0,0,0,0,0,0,0,0,0,0,0,0,0,0,0,P73,0,0,~
0,0,0,0,0,0,0,0,0)';$S;
    'VSS_R1':'(0,0,0,0,0,0,0,0,0,0,0,0,0,0,0,0,0,0,0,0,0,0,0,0,0,0,0,0,R1,0,0,0,~
0,0,0,0,0,0,0,0)';$S;
    'VSS_R4':'(0,0,0,0,0,0,0,0,0,0,0,0,0,0,0,0,0,0,0,0,0,0,0,0,0,0,0,0,R4,0,0,0,~
0,0,0,0,0,0,0,0)';$S;
    'VSS_R6':'(0,0,0,0,0,0,0,0,0,0,0,0,0,0,0,0,0,0,0,0,0,0,0,0,0,0,0,0,R6,0,0,0,~
0,0,0,0,0,0,0,0)';$S;
    'VSS_R8':'(0,0,0,0,0,0,0,0,0,0,0,0,0,0,0,0,0,0,0,0,0,0,0,0,0,0,0,0,R8,0,0,0,~
0,0,0,0,0,0,0,0)';$S;
    'VSS_R11':'(0,0,0,0,0,0,0,0,0,0,0,0,0,0,0,0,0,0,0,0,0,0,0,0,0,0,0,0,R11,0,0,~
0,0,0,0,0,0,0,0,0)';$S;
    'VSS_R13':'(0,0,0,0,0,0,0,0,0,0,0,0,0,0,0,0,0,0,0,0,0,0,0,0,0,0,0,0,R13,0,0,~
0,0,0,0,0,0,0,0,0)';$S;
    'VSS_R15':'(0,0,0,0,0,0,0,0,0,0,0,0,0,0,0,0,0,0,0,0,0,0,0,0,0,0,0,0,R15,0,0,~
0,0,0,0,0,0,0,0,0)';$S;
    'VSS_R18':'(0,0,0,0,0,0,0,0,0,0,0,0,0,0,0,0,0,0,0,0,0,0,0,0,0,0,0,0,R18,0,0,~
0,0,0,0,0,0,0,0,0)';$S;
    'VSS_R20':'(0,0,0,0,0,0,0,0,0,0,0,0,0,0,0,0,0,0,0,0,0,0,0,0,0,0,0,0,R20,0,0,~
0,0,0,0,0,0,0,0,0)';$S;
    'VSS_R22':'(0,0,0,0,0,0,0,0,0,0,0,0,0,0,0,0,0,0,0,0,0,0,0,0,0,0,0,0,R22,0,0,~
0,0,0,0,0,0,0,0,0)';$S;
    'VSS_R25':'(0,0,0,0,0,0,0,0,0,0,0,0,0,0,0,0,0,0,0,0,0,0,0,0,0,0,0,0,R25,0,0,~
0,0,0,0,0,0,0,0,0)';$S;
    'VSS_R28':'(0,0,0,0,0,0,0,0,0,0,0,0,0,0,0,0,0,0,0,0,0,0,0,0,0,0,0,0,R28,0,0,~
0,0,0,0,0,0,0,0,0)';$S;
    'VSS_R31':'(0,0,0,0,0,0,0,0,0,0,0,0,0,0,0,0,0,0,0,0,0,0,0,0,0,0,0,0,R31,0,0,~
0,0,0,0,0,0,0,0,0)';$S;
    'VSS_R34':'(0,0,0,0,0,0,0,0,0,0,0,0,0,0,0,0,0,0,0,0,0,0,0,0,0,0,0,0,R34,0,0,~
0,0,0,0,0,0,0,0,0)';$S;
    'VSS_R35':'(0,0,0,0,0,0,0,0,0,0,0,0,0,0,0,0,0,0,0,0,0,0,0,0,0,0,0,0,R35,0,0,~
0,0,0,0,0,0,0,0,0)';$S;
    'VSS_R36':'(0,0,0,0,0,0,0,0,0,0,0,0,0,0,0,0,0,0,0,0,0,0,0,0,0,0,0,0,R36,0,0,~
0,0,0,0,0,0,0,0,0)';$S;
    'VSS_R40':'(0,0,0,0,0,0,0,0,0,0,0,0,0,0,0,0,0,0,0,0,0,0,0,0,0,0,0,0,R40,0,0,~
0,0,0,0,0,0,0,0,0)';$S;
    'VSS_R41':'(0,0,0,0,0,0,0,0,0,0,0,0,0,0,0,0,0,0,0,0,0,0,0,0,0,0,0,0,R41,0,0,~
0,0,0,0,0,0,0,0,0)';$S;
    'VSS_R42':'(0,0,0,0,0,0,0,0,0,0,0,0,0,0,0,0,0,0,0,0,0,0,0,0,0,0,0,0,R42,0,0,~
0,0,0,0,0,0,0,0,0)';$S;
    'VSS_R45':'(0,0,0,0,0,0,0,0,0,0,0,0,0,0,0,0,0,0,0,0,0,0,0,0,0,0,0,0,R45,0,0,~
0,0,0,0,0,0,0,0,0)';$S;
    'VSS_AB68':'(0,0,0,0,0,0,0,0,0,0,0,0,0,0,0,0,0,0,0,0,0,0,0,0,0,0,0,0,0,AB68,~
0,0,0,0,0,0,0,0,0,0)';$S;
    'VSS_AB71':'(0,0,0,0,0,0,0,0,0,0,0,0,0,0,0,0,0,0,0,0,0,0,0,0,0,0,0,0,0,AB71,~
0,0,0,0,0,0,0,0,0,0)';$S;
    'VSS_AB73':'(0,0,0,0,0,0,0,0,0,0,0,0,0,0,0,0,0,0,0,0,0,0,0,0,0,0,0,0,0,AB73,~
0,0,0,0,0,0,0,0,0,0)';$S;
    'VSS_AC1':'(0,0,0,0,0,0,0,0,0,0,0,0,0,0,0,0,0,0,0,0,0,0,0,0,0,0,0,0,0,AC1,0,~
0,0,0,0,0,0,0,0,0)';$S;
    'VSS_AC6':'(0,0,0,0,0,0,0,0,0,0,0,0,0,0,0,0,0,0,0,0,0,0,0,0,0,0,0,0,0,AC6,0,~
0,0,0,0,0,0,0,0,0)';$S;
    'VSS_AC8':'(0,0,0,0,0,0,0,0,0,0,0,0,0,0,0,0,0,0,0,0,0,0,0,0,0,0,0,0,0,AC8,0,~
0,0,0,0,0,0,0,0,0)';$S;
    'VSS_AC13':'(0,0,0,0,0,0,0,0,0,0,0,0,0,0,0,0,0,0,0,0,0,0,0,0,0,0,0,0,0,AC13,~
0,0,0,0,0,0,0,0,0,0)';$S;
    'VSS_AC15':'(0,0,0,0,0,0,0,0,0,0,0,0,0,0,0,0,0,0,0,0,0,0,0,0,0,0,0,0,0,AC15,~
0,0,0,0,0,0,0,0,0,0)';$S;
    'VSS_AC20':'(0,0,0,0,0,0,0,0,0,0,0,0,0,0,0,0,0,0,0,0,0,0,0,0,0,0,0,0,0,AC20,~
0,0,0,0,0,0,0,0,0,0)';$S;
    'VSS_AC22':'(0,0,0,0,0,0,0,0,0,0,0,0,0,0,0,0,0,0,0,0,0,0,0,0,0,0,0,0,0,AC22,~
0,0,0,0,0,0,0,0,0,0)';$S;
    'VSS_AC25':'(0,0,0,0,0,0,0,0,0,0,0,0,0,0,0,0,0,0,0,0,0,0,0,0,0,0,0,0,0,AC25,~
0,0,0,0,0,0,0,0,0,0)';$S;
    'VSS_AC28':'(0,0,0,0,0,0,0,0,0,0,0,0,0,0,0,0,0,0,0,0,0,0,0,0,0,0,0,0,0,AC28,~
0,0,0,0,0,0,0,0,0,0)';$S;
    'VSS_AC31':'(0,0,0,0,0,0,0,0,0,0,0,0,0,0,0,0,0,0,0,0,0,0,0,0,0,0,0,0,0,AC31,~
0,0,0,0,0,0,0,0,0,0)';$S;
    'VSS_AC34':'(0,0,0,0,0,0,0,0,0,0,0,0,0,0,0,0,0,0,0,0,0,0,0,0,0,0,0,0,0,AC34,~
0,0,0,0,0,0,0,0,0,0)';$S;
    'VSS_AC42':'(0,0,0,0,0,0,0,0,0,0,0,0,0,0,0,0,0,0,0,0,0,0,0,0,0,0,0,0,0,AC42,~
0,0,0,0,0,0,0,0,0,0)';$S;
    'VSS_AC45':'(0,0,0,0,0,0,0,0,0,0,0,0,0,0,0,0,0,0,0,0,0,0,0,0,0,0,0,0,0,AC45,~
0,0,0,0,0,0,0,0,0,0)';$S;
    'VSS_AC48':'(0,0,0,0,0,0,0,0,0,0,0,0,0,0,0,0,0,0,0,0,0,0,0,0,0,0,0,0,0,AC48,~
0,0,0,0,0,0,0,0,0,0)';$S;
    'VSS_AC51':'(0,0,0,0,0,0,0,0,0,0,0,0,0,0,0,0,0,0,0,0,0,0,0,0,0,0,0,0,0,AC51,~
0,0,0,0,0,0,0,0,0,0)';$S;
    'VSS_AC54':'(0,0,0,0,0,0,0,0,0,0,0,0,0,0,0,0,0,0,0,0,0,0,0,0,0,0,0,0,0,AC54,~
0,0,0,0,0,0,0,0,0,0)';$S;
    'VSS_AC56':'(0,0,0,0,0,0,0,0,0,0,0,0,0,0,0,0,0,0,0,0,0,0,0,0,0,0,0,0,0,AC56,~
0,0,0,0,0,0,0,0,0,0)';$S;
    'VSS_AC61':'(0,0,0,0,0,0,0,0,0,0,0,0,0,0,0,0,0,0,0,0,0,0,0,0,0,0,0,0,0,AC61,~
0,0,0,0,0,0,0,0,0,0)';$S;
    'VSS_AC63':'(0,0,0,0,0,0,0,0,0,0,0,0,0,0,0,0,0,0,0,0,0,0,0,0,0,0,0,0,0,AC63,~
0,0,0,0,0,0,0,0,0,0)';$S;
    'VSS_AC68':'(0,0,0,0,0,0,0,0,0,0,0,0,0,0,0,0,0,0,0,0,0,0,0,0,0,0,0,0,0,AC68,~
0,0,0,0,0,0,0,0,0,0)';$S;
    'VSS_AC70':'(0,0,0,0,0,0,0,0,0,0,0,0,0,0,0,0,0,0,0,0,0,0,0,0,0,0,0,0,0,AC70,~
0,0,0,0,0,0,0,0,0,0)';$S;
    'VSS_AC75':'(0,0,0,0,0,0,0,0,0,0,0,0,0,0,0,0,0,0,0,0,0,0,0,0,0,0,0,0,0,AC75,~
0,0,0,0,0,0,0,0,0,0)';$S;
    'VSS_AD3':'(0,0,0,0,0,0,0,0,0,0,0,0,0,0,0,0,0,0,0,0,0,0,0,0,0,0,0,0,0,AD3,0,~
0,0,0,0,0,0,0,0,0)';$S;
    'VSS_AD5':'(0,0,0,0,0,0,0,0,0,0,0,0,0,0,0,0,0,0,0,0,0,0,0,0,0,0,0,0,0,AD5,0,~
0,0,0,0,0,0,0,0,0)';$S;
    'VSS_AD8':'(0,0,0,0,0,0,0,0,0,0,0,0,0,0,0,0,0,0,0,0,0,0,0,0,0,0,0,0,0,AD8,0,~
0,0,0,0,0,0,0,0,0)';$S;
    'VSS_AD10':'(0,0,0,0,0,0,0,0,0,0,0,0,0,0,0,0,0,0,0,0,0,0,0,0,0,0,0,0,0,AD10,~
0,0,0,0,0,0,0,0,0,0)';$S;
    'VSS_AD12':'(0,0,0,0,0,0,0,0,0,0,0,0,0,0,0,0,0,0,0,0,0,0,0,0,0,0,0,0,0,AD12,~
0,0,0,0,0,0,0,0,0,0)';$S;
    'VSS_AD15':'(0,0,0,0,0,0,0,0,0,0,0,0,0,0,0,0,0,0,0,0,0,0,0,0,0,0,0,0,0,AD15,~
0,0,0,0,0,0,0,0,0,0)';$S;
    'VSS_AD17':'(0,0,0,0,0,0,0,0,0,0,0,0,0,0,0,0,0,0,0,0,0,0,0,0,0,0,0,0,0,AD17,~
0,0,0,0,0,0,0,0,0,0)';$S;
    'VSS_AD19':'(0,0,0,0,0,0,0,0,0,0,0,0,0,0,0,0,0,0,0,0,0,0,0,0,0,0,0,0,0,AD19,~
0,0,0,0,0,0,0,0,0,0)';$S;
    'VSS_AD23':'(0,0,0,0,0,0,0,0,0,0,0,0,0,0,0,0,0,0,0,0,0,0,0,0,0,0,0,0,0,AD23,~
0,0,0,0,0,0,0,0,0,0)';$S;
    'VSS_AD24':'(0,0,0,0,0,0,0,0,0,0,0,0,0,0,0,0,0,0,0,0,0,0,0,0,0,0,0,0,0,AD24,~
0,0,0,0,0,0,0,0,0,0)';$S;
    'VSS_AD25':'(0,0,0,0,0,0,0,0,0,0,0,0,0,0,0,0,0,0,0,0,0,0,0,0,0,0,0,0,0,AD25,~
0,0,0,0,0,0,0,0,0,0)';$S;
    'VSS_AD26':'(0,0,0,0,0,0,0,0,0,0,0,0,0,0,0,0,0,0,0,0,0,0,0,0,0,0,0,0,0,AD26,~
0,0,0,0,0,0,0,0,0,0)';$S;
    'VSS_AD27':'(0,0,0,0,0,0,0,0,0,0,0,0,0,0,0,0,0,0,0,0,0,0,0,0,0,0,0,0,0,AD27,~
0,0,0,0,0,0,0,0,0,0)';$S;
    'VSS_AD28':'(0,0,0,0,0,0,0,0,0,0,0,0,0,0,0,0,0,0,0,0,0,0,0,0,0,0,0,0,0,AD28,~
0,0,0,0,0,0,0,0,0,0)';$S;
    'VSS_AD29':'(0,0,0,0,0,0,0,0,0,0,0,0,0,0,0,0,0,0,0,0,0,0,0,0,0,0,0,0,0,AD29,~
0,0,0,0,0,0,0,0,0,0)';$S;
    'VSS_AD30':'(0,0,0,0,0,0,0,0,0,0,0,0,0,0,0,0,0,0,0,0,0,0,0,0,0,0,0,0,0,AD30,~
0,0,0,0,0,0,0,0,0,0)';$S;
    'VSS_AD32':'(0,0,0,0,0,0,0,0,0,0,0,0,0,0,0,0,0,0,0,0,0,0,0,0,0,0,0,0,0,AD32,~
0,0,0,0,0,0,0,0,0,0)';$S;
    'VSS_AD33':'(0,0,0,0,0,0,0,0,0,0,0,0,0,0,0,0,0,0,0,0,0,0,0,0,0,0,0,0,0,AD33,~
0,0,0,0,0,0,0,0,0,0)';$S;
    'VSS_AD34':'(0,0,0,0,0,0,0,0,0,0,0,0,0,0,0,0,0,0,0,0,0,0,0,0,0,0,0,0,0,AD34,~
0,0,0,0,0,0,0,0,0,0)';$S;
    'VSS_AD37':'(0,0,0,0,0,0,0,0,0,0,0,0,0,0,0,0,0,0,0,0,0,0,0,0,0,0,0,0,0,AD37,~
0,0,0,0,0,0,0,0,0,0)';$S;
    'VSS_AD39':'(0,0,0,0,0,0,0,0,0,0,0,0,0,0,0,0,0,0,0,0,0,0,0,0,0,0,0,0,0,AD39,~
0,0,0,0,0,0,0,0,0,0)';$S;
    'VSS_AD42':'(0,0,0,0,0,0,0,0,0,0,0,0,0,0,0,0,0,0,0,0,0,0,0,0,0,0,0,0,0,AD42,~
0,0,0,0,0,0,0,0,0,0)';$S;
    'VSS_AD43':'(0,0,0,0,0,0,0,0,0,0,0,0,0,0,0,0,0,0,0,0,0,0,0,0,0,0,0,0,0,AD43,~
0,0,0,0,0,0,0,0,0,0)';$S;
    'VSS_AD44':'(0,0,0,0,0,0,0,0,0,0,0,0,0,0,0,0,0,0,0,0,0,0,0,0,0,0,0,0,0,AD44,~
0,0,0,0,0,0,0,0,0,0)';$S;
    'VSS_AD45':'(0,0,0,0,0,0,0,0,0,0,0,0,0,0,0,0,0,0,0,0,0,0,0,0,0,0,0,0,0,AD45,~
0,0,0,0,0,0,0,0,0,0)';$S;
    'VSS_AD46':'(0,0,0,0,0,0,0,0,0,0,0,0,0,0,0,0,0,0,0,0,0,0,0,0,0,0,0,0,0,AD46,~
0,0,0,0,0,0,0,0,0,0)';$S;
    'VSS_AD47':'(0,0,0,0,0,0,0,0,0,0,0,0,0,0,0,0,0,0,0,0,0,0,0,0,0,0,0,0,0,AD47,~
0,0,0,0,0,0,0,0,0,0)';$S;
    'VSS_AD48':'(0,0,0,0,0,0,0,0,0,0,0,0,0,0,0,0,0,0,0,0,0,0,0,0,0,0,0,0,0,AD48,~
0,0,0,0,0,0,0,0,0,0)';$S;
    'VSS_T66':'(0,0,0,0,0,0,0,0,0,0,0,0,0,0,0,0,0,0,0,0,0,0,0,0,0,0,0,0,0,T66,0,~
0,0,0,0,0,0,0,0,0)';$S;
    'VSS_T68':'(0,0,0,0,0,0,0,0,0,0,0,0,0,0,0,0,0,0,0,0,0,0,0,0,0,0,0,0,0,T68,0,~
0,0,0,0,0,0,0,0,0)';$S;
    'VSS_T71':'(0,0,0,0,0,0,0,0,0,0,0,0,0,0,0,0,0,0,0,0,0,0,0,0,0,0,0,0,0,T71,0,~
0,0,0,0,0,0,0,0,0)';$S;
    'VSS_T73':'(0,0,0,0,0,0,0,0,0,0,0,0,0,0,0,0,0,0,0,0,0,0,0,0,0,0,0,0,0,T73,0,~
0,0,0,0,0,0,0,0,0)';$S;
    'VSS_U1':'(0,0,0,0,0,0,0,0,0,0,0,0,0,0,0,0,0,0,0,0,0,0,0,0,0,0,0,0,0,U1,0,0,~
0,0,0,0,0,0,0,0)';$S;
    'VSS_U6':'(0,0,0,0,0,0,0,0,0,0,0,0,0,0,0,0,0,0,0,0,0,0,0,0,0,0,0,0,0,U6,0,0,~
0,0,0,0,0,0,0,0)';$S;
    'VSS_U8':'(0,0,0,0,0,0,0,0,0,0,0,0,0,0,0,0,0,0,0,0,0,0,0,0,0,0,0,0,0,U8,0,0,~
0,0,0,0,0,0,0,0)';$S;
    'VSS_U13':'(0,0,0,0,0,0,0,0,0,0,0,0,0,0,0,0,0,0,0,0,0,0,0,0,0,0,0,0,0,U13,0,~
0,0,0,0,0,0,0,0,0)';$S;
    'VSS_U15':'(0,0,0,0,0,0,0,0,0,0,0,0,0,0,0,0,0,0,0,0,0,0,0,0,0,0,0,0,0,U15,0,~
0,0,0,0,0,0,0,0,0)';$S;
    'VSS_U20':'(0,0,0,0,0,0,0,0,0,0,0,0,0,0,0,0,0,0,0,0,0,0,0,0,0,0,0,0,0,U20,0,~
0,0,0,0,0,0,0,0,0)';$S;
    'VSS_U22':'(0,0,0,0,0,0,0,0,0,0,0,0,0,0,0,0,0,0,0,0,0,0,0,0,0,0,0,0,0,U22,0,~
0,0,0,0,0,0,0,0,0)';$S;
    'VSS_U25':'(0,0,0,0,0,0,0,0,0,0,0,0,0,0,0,0,0,0,0,0,0,0,0,0,0,0,0,0,0,U25,0,~
0,0,0,0,0,0,0,0,0)';$S;
    'VSS_U28':'(0,0,0,0,0,0,0,0,0,0,0,0,0,0,0,0,0,0,0,0,0,0,0,0,0,0,0,0,0,U28,0,~
0,0,0,0,0,0,0,0,0)';$S;
    'VSS_U31':'(0,0,0,0,0,0,0,0,0,0,0,0,0,0,0,0,0,0,0,0,0,0,0,0,0,0,0,0,0,U31,0,~
0,0,0,0,0,0,0,0,0)';$S;
    'VSS_U34':'(0,0,0,0,0,0,0,0,0,0,0,0,0,0,0,0,0,0,0,0,0,0,0,0,0,0,0,0,0,U34,0,~
0,0,0,0,0,0,0,0,0)';$S;
    'VSS_U42':'(0,0,0,0,0,0,0,0,0,0,0,0,0,0,0,0,0,0,0,0,0,0,0,0,0,0,0,0,0,U42,0,~
0,0,0,0,0,0,0,0,0)';$S;
    'VSS_U45':'(0,0,0,0,0,0,0,0,0,0,0,0,0,0,0,0,0,0,0,0,0,0,0,0,0,0,0,0,0,U45,0,~
0,0,0,0,0,0,0,0,0)';$S;
    'VSS_U48':'(0,0,0,0,0,0,0,0,0,0,0,0,0,0,0,0,0,0,0,0,0,0,0,0,0,0,0,0,0,U48,0,~
0,0,0,0,0,0,0,0,0)';$S;
    'VSS_U51':'(0,0,0,0,0,0,0,0,0,0,0,0,0,0,0,0,0,0,0,0,0,0,0,0,0,0,0,0,0,U51,0,~
0,0,0,0,0,0,0,0,0)';$S;
    'VSS_U54':'(0,0,0,0,0,0,0,0,0,0,0,0,0,0,0,0,0,0,0,0,0,0,0,0,0,0,0,0,0,U54,0,~
0,0,0,0,0,0,0,0,0)';$S;
    'VSS_U56':'(0,0,0,0,0,0,0,0,0,0,0,0,0,0,0,0,0,0,0,0,0,0,0,0,0,0,0,0,0,U56,0,~
0,0,0,0,0,0,0,0,0)';$S;
    'VSS_U61':'(0,0,0,0,0,0,0,0,0,0,0,0,0,0,0,0,0,0,0,0,0,0,0,0,0,0,0,0,0,U61,0,~
0,0,0,0,0,0,0,0,0)';$S;
    'VSS_U63':'(0,0,0,0,0,0,0,0,0,0,0,0,0,0,0,0,0,0,0,0,0,0,0,0,0,0,0,0,0,U63,0,~
0,0,0,0,0,0,0,0,0)';$S;
    'VSS_U68':'(0,0,0,0,0,0,0,0,0,0,0,0,0,0,0,0,0,0,0,0,0,0,0,0,0,0,0,0,0,U68,0,~
0,0,0,0,0,0,0,0,0)';$S;
    'VSS_U70':'(0,0,0,0,0,0,0,0,0,0,0,0,0,0,0,0,0,0,0,0,0,0,0,0,0,0,0,0,0,U70,0,~
0,0,0,0,0,0,0,0,0)';$S;
    'VSS_U75':'(0,0,0,0,0,0,0,0,0,0,0,0,0,0,0,0,0,0,0,0,0,0,0,0,0,0,0,0,0,U75,0,~
0,0,0,0,0,0,0,0,0)';$S;
    'VSS_V3':'(0,0,0,0,0,0,0,0,0,0,0,0,0,0,0,0,0,0,0,0,0,0,0,0,0,0,0,0,0,V3,0,0,~
0,0,0,0,0,0,0,0)';$S;
    'VSS_V5':'(0,0,0,0,0,0,0,0,0,0,0,0,0,0,0,0,0,0,0,0,0,0,0,0,0,0,0,0,0,V5,0,0,~
0,0,0,0,0,0,0,0)';$S;
    'VSS_V8':'(0,0,0,0,0,0,0,0,0,0,0,0,0,0,0,0,0,0,0,0,0,0,0,0,0,0,0,0,0,V8,0,0,~
0,0,0,0,0,0,0,0)';$S;
    'VSS_V10':'(0,0,0,0,0,0,0,0,0,0,0,0,0,0,0,0,0,0,0,0,0,0,0,0,0,0,0,0,0,V10,0,~
0,0,0,0,0,0,0,0,0)';$S;
    'VSS_V12':'(0,0,0,0,0,0,0,0,0,0,0,0,0,0,0,0,0,0,0,0,0,0,0,0,0,0,0,0,0,V12,0,~
0,0,0,0,0,0,0,0,0)';$S;
    'VSS_V15':'(0,0,0,0,0,0,0,0,0,0,0,0,0,0,0,0,0,0,0,0,0,0,0,0,0,0,0,0,0,V15,0,~
0,0,0,0,0,0,0,0,0)';$S;
    'VSS_V17':'(0,0,0,0,0,0,0,0,0,0,0,0,0,0,0,0,0,0,0,0,0,0,0,0,0,0,0,0,0,V17,0,~
0,0,0,0,0,0,0,0,0)';$S;
    'VSS_V19':'(0,0,0,0,0,0,0,0,0,0,0,0,0,0,0,0,0,0,0,0,0,0,0,0,0,0,0,0,0,V19,0,~
0,0,0,0,0,0,0,0,0)';$S;
    'VSS_V23':'(0,0,0,0,0,0,0,0,0,0,0,0,0,0,0,0,0,0,0,0,0,0,0,0,0,0,0,0,0,V23,0,~
0,0,0,0,0,0,0,0,0)';$S;
    'VSS_V24':'(0,0,0,0,0,0,0,0,0,0,0,0,0,0,0,0,0,0,0,0,0,0,0,0,0,0,0,0,0,V24,0,~
0,0,0,0,0,0,0,0,0)';$S;
    'VSS_V25':'(0,0,0,0,0,0,0,0,0,0,0,0,0,0,0,0,0,0,0,0,0,0,0,0,0,0,0,0,0,V25,0,~
0,0,0,0,0,0,0,0,0)';$S;
    'VSS_V26':'(0,0,0,0,0,0,0,0,0,0,0,0,0,0,0,0,0,0,0,0,0,0,0,0,0,0,0,0,0,V26,0,~
0,0,0,0,0,0,0,0,0)';$S;
    'VSS_V28':'(0,0,0,0,0,0,0,0,0,0,0,0,0,0,0,0,0,0,0,0,0,0,0,0,0,0,0,0,0,V28,0,~
0,0,0,0,0,0,0,0,0)';$S;
    'VSS_V29':'(0,0,0,0,0,0,0,0,0,0,0,0,0,0,0,0,0,0,0,0,0,0,0,0,0,0,0,0,0,V29,0,~
0,0,0,0,0,0,0,0,0)';$S;
    'VSS_V30':'(0,0,0,0,0,0,0,0,0,0,0,0,0,0,0,0,0,0,0,0,0,0,0,0,0,0,0,0,0,V30,0,~
0,0,0,0,0,0,0,0,0)';$S;
    'VSS_V31':'(0,0,0,0,0,0,0,0,0,0,0,0,0,0,0,0,0,0,0,0,0,0,0,0,0,0,0,0,0,V31,0,~
0,0,0,0,0,0,0,0,0)';$S;
    'VSS_V32':'(0,0,0,0,0,0,0,0,0,0,0,0,0,0,0,0,0,0,0,0,0,0,0,0,0,0,0,0,0,V32,0,~
0,0,0,0,0,0,0,0,0)';$S;
    'VSS_V33':'(0,0,0,0,0,0,0,0,0,0,0,0,0,0,0,0,0,0,0,0,0,0,0,0,0,0,0,0,0,V33,0,~
0,0,0,0,0,0,0,0,0)';$S;
    'VSS_V34':'(0,0,0,0,0,0,0,0,0,0,0,0,0,0,0,0,0,0,0,0,0,0,0,0,0,0,0,0,0,V34,0,~
0,0,0,0,0,0,0,0,0)';$S;
    'VSS_V37':'(0,0,0,0,0,0,0,0,0,0,0,0,0,0,0,0,0,0,0,0,0,0,0,0,0,0,0,0,0,V37,0,~
0,0,0,0,0,0,0,0,0)';$S;
    'VSS_V39':'(0,0,0,0,0,0,0,0,0,0,0,0,0,0,0,0,0,0,0,0,0,0,0,0,0,0,0,0,0,V39,0,~
0,0,0,0,0,0,0,0,0)';$S;
    'VSS_V42':'(0,0,0,0,0,0,0,0,0,0,0,0,0,0,0,0,0,0,0,0,0,0,0,0,0,0,0,0,0,V42,0,~
0,0,0,0,0,0,0,0,0)';$S;
    'VSS_V43':'(0,0,0,0,0,0,0,0,0,0,0,0,0,0,0,0,0,0,0,0,0,0,0,0,0,0,0,0,0,V43,0,~
0,0,0,0,0,0,0,0,0)';$S;
    'VSS_V44':'(0,0,0,0,0,0,0,0,0,0,0,0,0,0,0,0,0,0,0,0,0,0,0,0,0,0,0,0,0,V44,0,~
0,0,0,0,0,0,0,0,0)';$S;
    'VSS_V45':'(0,0,0,0,0,0,0,0,0,0,0,0,0,0,0,0,0,0,0,0,0,0,0,0,0,0,0,0,0,V45,0,~
0,0,0,0,0,0,0,0,0)';$S;
    'VSS_V46':'(0,0,0,0,0,0,0,0,0,0,0,0,0,0,0,0,0,0,0,0,0,0,0,0,0,0,0,0,0,V46,0,~
0,0,0,0,0,0,0,0,0)';$S;
    'VSS_V47':'(0,0,0,0,0,0,0,0,0,0,0,0,0,0,0,0,0,0,0,0,0,0,0,0,0,0,0,0,0,V47,0,~
0,0,0,0,0,0,0,0,0)';$S;
    'VSS_V48':'(0,0,0,0,0,0,0,0,0,0,0,0,0,0,0,0,0,0,0,0,0,0,0,0,0,0,0,0,0,V48,0,~
0,0,0,0,0,0,0,0,0)';$S;
    'VSS_V49':'(0,0,0,0,0,0,0,0,0,0,0,0,0,0,0,0,0,0,0,0,0,0,0,0,0,0,0,0,0,V49,0,~
0,0,0,0,0,0,0,0,0)';$S;
    'VSS_V50':'(0,0,0,0,0,0,0,0,0,0,0,0,0,0,0,0,0,0,0,0,0,0,0,0,0,0,0,0,0,V50,0,~
0,0,0,0,0,0,0,0,0)';$S;
    'VSS_V51':'(0,0,0,0,0,0,0,0,0,0,0,0,0,0,0,0,0,0,0,0,0,0,0,0,0,0,0,0,0,V51,0,~
0,0,0,0,0,0,0,0,0)';$S;
    'VSS_V52':'(0,0,0,0,0,0,0,0,0,0,0,0,0,0,0,0,0,0,0,0,0,0,0,0,0,0,0,0,0,V52,0,~
0,0,0,0,0,0,0,0,0)';$S;
    'VSS_V53':'(0,0,0,0,0,0,0,0,0,0,0,0,0,0,0,0,0,0,0,0,0,0,0,0,0,0,0,0,0,V53,0,~
0,0,0,0,0,0,0,0,0)';$S;
    'VSS_V57':'(0,0,0,0,0,0,0,0,0,0,0,0,0,0,0,0,0,0,0,0,0,0,0,0,0,0,0,0,0,V57,0,~
0,0,0,0,0,0,0,0,0)';$S;
    'VSS_V59':'(0,0,0,0,0,0,0,0,0,0,0,0,0,0,0,0,0,0,0,0,0,0,0,0,0,0,0,0,0,V59,0,~
0,0,0,0,0,0,0,0,0)';$S;
    'VSS_V61':'(0,0,0,0,0,0,0,0,0,0,0,0,0,0,0,0,0,0,0,0,0,0,0,0,0,0,0,0,0,V61,0,~
0,0,0,0,0,0,0,0,0)';$S;
    'VSS_V64':'(0,0,0,0,0,0,0,0,0,0,0,0,0,0,0,0,0,0,0,0,0,0,0,0,0,0,0,0,0,V64,0,~
0,0,0,0,0,0,0,0,0)';$S;
    'VSS_V66':'(0,0,0,0,0,0,0,0,0,0,0,0,0,0,0,0,0,0,0,0,0,0,0,0,0,0,0,0,0,V66,0,~
0,0,0,0,0,0,0,0,0)';$S;
    'VSS_V71':'(0,0,0,0,0,0,0,0,0,0,0,0,0,0,0,0,0,0,0,0,0,0,0,0,0,0,0,0,0,V71,0,~
0,0,0,0,0,0,0,0,0)';$S;
    'VSS_V73':'(0,0,0,0,0,0,0,0,0,0,0,0,0,0,0,0,0,0,0,0,0,0,0,0,0,0,0,0,0,V73,0,~
0,0,0,0,0,0,0,0,0)';$S;
    'VSS_W1':'(0,0,0,0,0,0,0,0,0,0,0,0,0,0,0,0,0,0,0,0,0,0,0,0,0,0,0,0,0,W1,0,0,~
0,0,0,0,0,0,0,0)';$S;
    'VSS_W4':'(0,0,0,0,0,0,0,0,0,0,0,0,0,0,0,0,0,0,0,0,0,0,0,0,0,0,0,0,0,W4,0,0,~
0,0,0,0,0,0,0,0)';$S;
    'VSS_W6':'(0,0,0,0,0,0,0,0,0,0,0,0,0,0,0,0,0,0,0,0,0,0,0,0,0,0,0,0,0,W6,0,0,~
0,0,0,0,0,0,0,0)';$S;
    'VSS_W8':'(0,0,0,0,0,0,0,0,0,0,0,0,0,0,0,0,0,0,0,0,0,0,0,0,0,0,0,0,0,W8,0,0,~
0,0,0,0,0,0,0,0)';$S;
    'VSS_W11':'(0,0,0,0,0,0,0,0,0,0,0,0,0,0,0,0,0,0,0,0,0,0,0,0,0,0,0,0,0,W11,0,~
0,0,0,0,0,0,0,0,0)';$S;
    'VSS_W13':'(0,0,0,0,0,0,0,0,0,0,0,0,0,0,0,0,0,0,0,0,0,0,0,0,0,0,0,0,0,W13,0,~
0,0,0,0,0,0,0,0,0)';$S;
    'VSS_W15':'(0,0,0,0,0,0,0,0,0,0,0,0,0,0,0,0,0,0,0,0,0,0,0,0,0,0,0,0,0,W15,0,~
0,0,0,0,0,0,0,0,0)';$S;
    'VSS_W18':'(0,0,0,0,0,0,0,0,0,0,0,0,0,0,0,0,0,0,0,0,0,0,0,0,0,0,0,0,0,W18,0,~
0,0,0,0,0,0,0,0,0)';$S;
    'VSS_W20':'(0,0,0,0,0,0,0,0,0,0,0,0,0,0,0,0,0,0,0,0,0,0,0,0,0,0,0,0,0,W20,0,~
0,0,0,0,0,0,0,0,0)';$S;
    'VSS_W22':'(0,0,0,0,0,0,0,0,0,0,0,0,0,0,0,0,0,0,0,0,0,0,0,0,0,0,0,0,0,W22,0,~
0,0,0,0,0,0,0,0,0)';$S;
    'VSS_W25':'(0,0,0,0,0,0,0,0,0,0,0,0,0,0,0,0,0,0,0,0,0,0,0,0,0,0,0,0,0,W25,0,~
0,0,0,0,0,0,0,0,0)';$S;
    'VSS_W28':'(0,0,0,0,0,0,0,0,0,0,0,0,0,0,0,0,0,0,0,0,0,0,0,0,0,0,0,0,0,W28,0,~
0,0,0,0,0,0,0,0,0)';$S;
    'VSS_W34':'(0,0,0,0,0,0,0,0,0,0,0,0,0,0,0,0,0,0,0,0,0,0,0,0,0,0,0,0,0,W34,0,~
0,0,0,0,0,0,0,0,0)';$S;
    'VSS_W35':'(0,0,0,0,0,0,0,0,0,0,0,0,0,0,0,0,0,0,0,0,0,0,0,0,0,0,0,0,0,W35,0,~
0,0,0,0,0,0,0,0,0)';$S;
    'VSS_W36':'(0,0,0,0,0,0,0,0,0,0,0,0,0,0,0,0,0,0,0,0,0,0,0,0,0,0,0,0,0,W36,0,~
0,0,0,0,0,0,0,0,0)';$S;
    'VSS_W40':'(0,0,0,0,0,0,0,0,0,0,0,0,0,0,0,0,0,0,0,0,0,0,0,0,0,0,0,0,0,W40,0,~
0,0,0,0,0,0,0,0,0)';$S;
    'VSS_W41':'(0,0,0,0,0,0,0,0,0,0,0,0,0,0,0,0,0,0,0,0,0,0,0,0,0,0,0,0,0,W41,0,~
0,0,0,0,0,0,0,0,0)';$S;
    'VSS_W42':'(0,0,0,0,0,0,0,0,0,0,0,0,0,0,0,0,0,0,0,0,0,0,0,0,0,0,0,0,0,W42,0,~
0,0,0,0,0,0,0,0,0)';$S;
    'VSS_W45':'(0,0,0,0,0,0,0,0,0,0,0,0,0,0,0,0,0,0,0,0,0,0,0,0,0,0,0,0,0,W45,0,~
0,0,0,0,0,0,0,0,0)';$S;
    'VSS_W48':'(0,0,0,0,0,0,0,0,0,0,0,0,0,0,0,0,0,0,0,0,0,0,0,0,0,0,0,0,0,W48,0,~
0,0,0,0,0,0,0,0,0)';$S;
    'VSS_W51':'(0,0,0,0,0,0,0,0,0,0,0,0,0,0,0,0,0,0,0,0,0,0,0,0,0,0,0,0,0,W51,0,~
0,0,0,0,0,0,0,0,0)';$S;
    'VSS_W54':'(0,0,0,0,0,0,0,0,0,0,0,0,0,0,0,0,0,0,0,0,0,0,0,0,0,0,0,0,0,W54,0,~
0,0,0,0,0,0,0,0,0)';$S;
    'VSS_W56':'(0,0,0,0,0,0,0,0,0,0,0,0,0,0,0,0,0,0,0,0,0,0,0,0,0,0,0,0,0,W56,0,~
0,0,0,0,0,0,0,0,0)';$S;
    'VSS_W58':'(0,0,0,0,0,0,0,0,0,0,0,0,0,0,0,0,0,0,0,0,0,0,0,0,0,0,0,0,0,W58,0,~
0,0,0,0,0,0,0,0,0)';$S;
    'VSS_W61':'(0,0,0,0,0,0,0,0,0,0,0,0,0,0,0,0,0,0,0,0,0,0,0,0,0,0,0,0,0,W61,0,~
0,0,0,0,0,0,0,0,0)';$S;
    'VSS_W63':'(0,0,0,0,0,0,0,0,0,0,0,0,0,0,0,0,0,0,0,0,0,0,0,0,0,0,0,0,0,W63,0,~
0,0,0,0,0,0,0,0,0)';$S;
    'VSS_W65':'(0,0,0,0,0,0,0,0,0,0,0,0,0,0,0,0,0,0,0,0,0,0,0,0,0,0,0,0,0,W65,0,~
0,0,0,0,0,0,0,0,0)';$S;
    'VSS_W68':'(0,0,0,0,0,0,0,0,0,0,0,0,0,0,0,0,0,0,0,0,0,0,0,0,0,0,0,0,0,W68,0,~
0,0,0,0,0,0,0,0,0)';$S;
    'VSS_W70':'(0,0,0,0,0,0,0,0,0,0,0,0,0,0,0,0,0,0,0,0,0,0,0,0,0,0,0,0,0,W70,0,~
0,0,0,0,0,0,0,0,0)';$S;
    'VSS_W72':'(0,0,0,0,0,0,0,0,0,0,0,0,0,0,0,0,0,0,0,0,0,0,0,0,0,0,0,0,0,W72,0,~
0,0,0,0,0,0,0,0,0)';$S;
    'VSS_W75':'(0,0,0,0,0,0,0,0,0,0,0,0,0,0,0,0,0,0,0,0,0,0,0,0,0,0,0,0,0,W75,0,~
0,0,0,0,0,0,0,0,0)';$S;
    'VSS_Y3':'(0,0,0,0,0,0,0,0,0,0,0,0,0,0,0,0,0,0,0,0,0,0,0,0,0,0,0,0,0,Y3,0,0,~
0,0,0,0,0,0,0,0)';$S;
    'VSS_Y8':'(0,0,0,0,0,0,0,0,0,0,0,0,0,0,0,0,0,0,0,0,0,0,0,0,0,0,0,0,0,Y8,0,0,~
0,0,0,0,0,0,0,0)';$S;
    'VSS_Y10':'(0,0,0,0,0,0,0,0,0,0,0,0,0,0,0,0,0,0,0,0,0,0,0,0,0,0,0,0,0,Y10,0,~
0,0,0,0,0,0,0,0,0)';$S;
    'VSS_Y15':'(0,0,0,0,0,0,0,0,0,0,0,0,0,0,0,0,0,0,0,0,0,0,0,0,0,0,0,0,0,Y15,0,~
0,0,0,0,0,0,0,0,0)';$S;
    'VSS_Y17':'(0,0,0,0,0,0,0,0,0,0,0,0,0,0,0,0,0,0,0,0,0,0,0,0,0,0,0,0,0,Y17,0,~
0,0,0,0,0,0,0,0,0)';$S;
    'VSS_Y22':'(0,0,0,0,0,0,0,0,0,0,0,0,0,0,0,0,0,0,0,0,0,0,0,0,0,0,0,0,0,Y22,0,~
0,0,0,0,0,0,0,0,0)';$S;
    'VSS_Y23':'(0,0,0,0,0,0,0,0,0,0,0,0,0,0,0,0,0,0,0,0,0,0,0,0,0,0,0,0,0,Y23,0,~
0,0,0,0,0,0,0,0,0)';$S;
    'VSS_Y24':'(0,0,0,0,0,0,0,0,0,0,0,0,0,0,0,0,0,0,0,0,0,0,0,0,0,0,0,0,0,Y24,0,~
0,0,0,0,0,0,0,0,0)';$S;
    'VSS_Y25':'(0,0,0,0,0,0,0,0,0,0,0,0,0,0,0,0,0,0,0,0,0,0,0,0,0,0,0,0,0,Y25,0,~
0,0,0,0,0,0,0,0,0)';$S;
    'VSS_Y26':'(0,0,0,0,0,0,0,0,0,0,0,0,0,0,0,0,0,0,0,0,0,0,0,0,0,0,0,0,0,Y26,0,~
0,0,0,0,0,0,0,0,0)';$S;
    'VSS_Y27':'(0,0,0,0,0,0,0,0,0,0,0,0,0,0,0,0,0,0,0,0,0,0,0,0,0,0,0,0,0,Y27,0,~
0,0,0,0,0,0,0,0,0)';$S;
    'VSS_Y28':'(0,0,0,0,0,0,0,0,0,0,0,0,0,0,0,0,0,0,0,0,0,0,0,0,0,0,0,0,0,Y28,0,~
0,0,0,0,0,0,0,0,0)';$S;
    'VSS_Y31':'(0,0,0,0,0,0,0,0,0,0,0,0,0,0,0,0,0,0,0,0,0,0,0,0,0,0,0,0,0,Y31,0,~
0,0,0,0,0,0,0,0,0)';$S;
    'VSS_Y32':'(0,0,0,0,0,0,0,0,0,0,0,0,0,0,0,0,0,0,0,0,0,0,0,0,0,0,0,0,0,Y32,0,~
0,0,0,0,0,0,0,0,0)';$S;
    'VSS_Y33':'(0,0,0,0,0,0,0,0,0,0,0,0,0,0,0,0,0,0,0,0,0,0,0,0,0,0,0,0,0,Y33,0,~
0,0,0,0,0,0,0,0,0)';$S;
    'VSS_Y34':'(0,0,0,0,0,0,0,0,0,0,0,0,0,0,0,0,0,0,0,0,0,0,0,0,0,0,0,0,0,Y34,0,~
0,0,0,0,0,0,0,0,0)';$S;
    'VSS_Y37':'(0,0,0,0,0,0,0,0,0,0,0,0,0,0,0,0,0,0,0,0,0,0,0,0,0,0,0,0,0,Y37,0,~
0,0,0,0,0,0,0,0,0)';$S;
    'VSS_Y39':'(0,0,0,0,0,0,0,0,0,0,0,0,0,0,0,0,0,0,0,0,0,0,0,0,0,0,0,0,0,Y39,0,~
0,0,0,0,0,0,0,0,0)';$S;
    'VSS_Y42':'(0,0,0,0,0,0,0,0,0,0,0,0,0,0,0,0,0,0,0,0,0,0,0,0,0,0,0,0,0,Y42,0,~
0,0,0,0,0,0,0,0,0)';$S;
    'VSS_Y43':'(0,0,0,0,0,0,0,0,0,0,0,0,0,0,0,0,0,0,0,0,0,0,0,0,0,0,0,0,0,Y43,0,~
0,0,0,0,0,0,0,0,0)';$S;
    'VSS_Y44':'(0,0,0,0,0,0,0,0,0,0,0,0,0,0,0,0,0,0,0,0,0,0,0,0,0,0,0,0,0,Y44,0,~
0,0,0,0,0,0,0,0,0)';$S;
    'VSS_Y45':'(0,0,0,0,0,0,0,0,0,0,0,0,0,0,0,0,0,0,0,0,0,0,0,0,0,0,0,0,0,Y45,0,~
0,0,0,0,0,0,0,0,0)';$S;
    'VSS_Y48':'(0,0,0,0,0,0,0,0,0,0,0,0,0,0,0,0,0,0,0,0,0,0,0,0,0,0,0,0,0,Y48,0,~
0,0,0,0,0,0,0,0,0)';$S;
    'VSS_Y49':'(0,0,0,0,0,0,0,0,0,0,0,0,0,0,0,0,0,0,0,0,0,0,0,0,0,0,0,0,0,Y49,0,~
0,0,0,0,0,0,0,0,0)';$S;
    'VSS_Y50':'(0,0,0,0,0,0,0,0,0,0,0,0,0,0,0,0,0,0,0,0,0,0,0,0,0,0,0,0,0,Y50,0,~
0,0,0,0,0,0,0,0,0)';$S;
    'VSS_Y51':'(0,0,0,0,0,0,0,0,0,0,0,0,0,0,0,0,0,0,0,0,0,0,0,0,0,0,0,0,0,Y51,0,~
0,0,0,0,0,0,0,0,0)';$S;
    'VSS_Y52':'(0,0,0,0,0,0,0,0,0,0,0,0,0,0,0,0,0,0,0,0,0,0,0,0,0,0,0,0,0,Y52,0,~
0,0,0,0,0,0,0,0,0)';$S;
    'VSS_Y53':'(0,0,0,0,0,0,0,0,0,0,0,0,0,0,0,0,0,0,0,0,0,0,0,0,0,0,0,0,0,Y53,0,~
0,0,0,0,0,0,0,0,0)';$S;
    'VSS_Y54':'(0,0,0,0,0,0,0,0,0,0,0,0,0,0,0,0,0,0,0,0,0,0,0,0,0,0,0,0,0,Y54,0,~
0,0,0,0,0,0,0,0,0)';$S;
    'VSS_Y59':'(0,0,0,0,0,0,0,0,0,0,0,0,0,0,0,0,0,0,0,0,0,0,0,0,0,0,0,0,0,Y59,0,~
0,0,0,0,0,0,0,0,0)';$S;
    'VSS_Y61':'(0,0,0,0,0,0,0,0,0,0,0,0,0,0,0,0,0,0,0,0,0,0,0,0,0,0,0,0,0,Y61,0,~
0,0,0,0,0,0,0,0,0)';$S;
    'VSS_Y66':'(0,0,0,0,0,0,0,0,0,0,0,0,0,0,0,0,0,0,0,0,0,0,0,0,0,0,0,0,0,Y66,0,~
0,0,0,0,0,0,0,0,0)';$S;
    'VSS_Y68':'(0,0,0,0,0,0,0,0,0,0,0,0,0,0,0,0,0,0,0,0,0,0,0,0,0,0,0,0,0,Y68,0,~
0,0,0,0,0,0,0,0,0)';$S;
    'VSS_Y73':'(0,0,0,0,0,0,0,0,0,0,0,0,0,0,0,0,0,0,0,0,0,0,0,0,0,0,0,0,0,Y73,0,~
0,0,0,0,0,0,0,0,0)';$S;
    'VSS_AA1':'(0,0,0,0,0,0,0,0,0,0,0,0,0,0,0,0,0,0,0,0,0,0,0,0,0,0,0,0,0,AA1,0,~
0,0,0,0,0,0,0,0,0)';$S;
    'VSS_AA4':'(0,0,0,0,0,0,0,0,0,0,0,0,0,0,0,0,0,0,0,0,0,0,0,0,0,0,0,0,0,AA4,0,~
0,0,0,0,0,0,0,0,0)';$S;
    'VSS_AA6':'(0,0,0,0,0,0,0,0,0,0,0,0,0,0,0,0,0,0,0,0,0,0,0,0,0,0,0,0,0,AA6,0,~
0,0,0,0,0,0,0,0,0)';$S;
    'VSS_AA8':'(0,0,0,0,0,0,0,0,0,0,0,0,0,0,0,0,0,0,0,0,0,0,0,0,0,0,0,0,0,AA8,0,~
0,0,0,0,0,0,0,0,0)';$S;
    'VSS_AA11':'(0,0,0,0,0,0,0,0,0,0,0,0,0,0,0,0,0,0,0,0,0,0,0,0,0,0,0,0,0,AA11,~
0,0,0,0,0,0,0,0,0,0)';$S;
    'VSS_AA13':'(0,0,0,0,0,0,0,0,0,0,0,0,0,0,0,0,0,0,0,0,0,0,0,0,0,0,0,0,0,AA13,~
0,0,0,0,0,0,0,0,0,0)';$S;
    'VSS_AA15':'(0,0,0,0,0,0,0,0,0,0,0,0,0,0,0,0,0,0,0,0,0,0,0,0,0,0,0,0,0,AA15,~
0,0,0,0,0,0,0,0,0,0)';$S;
    'VSS_AA18':'(0,0,0,0,0,0,0,0,0,0,0,0,0,0,0,0,0,0,0,0,0,0,0,0,0,0,0,0,0,AA18,~
0,0,0,0,0,0,0,0,0,0)';$S;
    'VSS_AA20':'(0,0,0,0,0,0,0,0,0,0,0,0,0,0,0,0,0,0,0,0,0,0,0,0,0,0,0,0,0,AA20,~
0,0,0,0,0,0,0,0,0,0)';$S;
    'VSS_AA31':'(0,0,0,0,0,0,0,0,0,0,0,0,0,0,0,0,0,0,0,0,0,0,0,0,0,0,0,0,0,AA31,~
0,0,0,0,0,0,0,0,0,0)';$S;
    'VSS_AA34':'(0,0,0,0,0,0,0,0,0,0,0,0,0,0,0,0,0,0,0,0,0,0,0,0,0,0,0,0,0,AA34,~
0,0,0,0,0,0,0,0,0,0)';$S;
    'VSS_AA35':'(0,0,0,0,0,0,0,0,0,0,0,0,0,0,0,0,0,0,0,0,0,0,0,0,0,0,0,0,0,AA35,~
0,0,0,0,0,0,0,0,0,0)';$S;
    'VSS_AA36':'(0,0,0,0,0,0,0,0,0,0,0,0,0,0,0,0,0,0,0,0,0,0,0,0,0,0,0,0,0,AA36,~
0,0,0,0,0,0,0,0,0,0)';$S;
    'VSS_AA40':'(0,0,0,0,0,0,0,0,0,0,0,0,0,0,0,0,0,0,0,0,0,0,0,0,0,0,0,0,0,AA40,~
0,0,0,0,0,0,0,0,0,0)';$S;
    'VSS_AA41':'(0,0,0,0,0,0,0,0,0,0,0,0,0,0,0,0,0,0,0,0,0,0,0,0,0,0,0,0,0,AA41,~
0,0,0,0,0,0,0,0,0,0)';$S;
    'VSS_AA45':'(0,0,0,0,0,0,0,0,0,0,0,0,0,0,0,0,0,0,0,0,0,0,0,0,0,0,0,0,0,AA45,~
0,0,0,0,0,0,0,0,0,0)';$S;
    'VSS_AA56':'(0,0,0,0,0,0,0,0,0,0,0,0,0,0,0,0,0,0,0,0,0,0,0,0,0,0,0,0,0,AA56,~
0,0,0,0,0,0,0,0,0,0)';$S;
    'VSS_AA58':'(0,0,0,0,0,0,0,0,0,0,0,0,0,0,0,0,0,0,0,0,0,0,0,0,0,0,0,0,0,AA58,~
0,0,0,0,0,0,0,0,0,0)';$S;
    'VSS_AA61':'(0,0,0,0,0,0,0,0,0,0,0,0,0,0,0,0,0,0,0,0,0,0,0,0,0,0,0,0,0,AA61,~
0,0,0,0,0,0,0,0,0,0)';$S;
    'VSS_AA63':'(0,0,0,0,0,0,0,0,0,0,0,0,0,0,0,0,0,0,0,0,0,0,0,0,0,0,0,0,0,AA63,~
0,0,0,0,0,0,0,0,0,0)';$S;
    'VSS_AA65':'(0,0,0,0,0,0,0,0,0,0,0,0,0,0,0,0,0,0,0,0,0,0,0,0,0,0,0,0,0,AA65,~
0,0,0,0,0,0,0,0,0,0)';$S;
    'VSS_AA68':'(0,0,0,0,0,0,0,0,0,0,0,0,0,0,0,0,0,0,0,0,0,0,0,0,0,0,0,0,0,AA68,~
0,0,0,0,0,0,0,0,0,0)';$S;
    'VSS_AA70':'(0,0,0,0,0,0,0,0,0,0,0,0,0,0,0,0,0,0,0,0,0,0,0,0,0,0,0,0,0,AA70,~
0,0,0,0,0,0,0,0,0,0)';$S;
    'VSS_AA75':'(0,0,0,0,0,0,0,0,0,0,0,0,0,0,0,0,0,0,0,0,0,0,0,0,0,0,0,0,0,AA75,~
0,0,0,0,0,0,0,0,0,0)';$S;
    'VSS_AB3':'(0,0,0,0,0,0,0,0,0,0,0,0,0,0,0,0,0,0,0,0,0,0,0,0,0,0,0,0,0,AB3,0,~
0,0,0,0,0,0,0,0,0)';$S;
    'VSS_AB5':'(0,0,0,0,0,0,0,0,0,0,0,0,0,0,0,0,0,0,0,0,0,0,0,0,0,0,0,0,0,AB5,0,~
0,0,0,0,0,0,0,0,0)';$S;
    'VSS_AB8':'(0,0,0,0,0,0,0,0,0,0,0,0,0,0,0,0,0,0,0,0,0,0,0,0,0,0,0,0,0,AB8,0,~
0,0,0,0,0,0,0,0,0)';$S;
    'VSS_AB10':'(0,0,0,0,0,0,0,0,0,0,0,0,0,0,0,0,0,0,0,0,0,0,0,0,0,0,0,0,0,AB10,~
0,0,0,0,0,0,0,0,0,0)';$S;
    'VSS_AB12':'(0,0,0,0,0,0,0,0,0,0,0,0,0,0,0,0,0,0,0,0,0,0,0,0,0,0,0,0,0,AB12,~
0,0,0,0,0,0,0,0,0,0)';$S;
    'VSS_AB15':'(0,0,0,0,0,0,0,0,0,0,0,0,0,0,0,0,0,0,0,0,0,0,0,0,0,0,0,0,0,AB15,~
0,0,0,0,0,0,0,0,0,0)';$S;
    'VSS_AB17':'(0,0,0,0,0,0,0,0,0,0,0,0,0,0,0,0,0,0,0,0,0,0,0,0,0,0,0,0,0,AB17,~
0,0,0,0,0,0,0,0,0,0)';$S;
    'VSS_AB19':'(0,0,0,0,0,0,0,0,0,0,0,0,0,0,0,0,0,0,0,0,0,0,0,0,0,0,0,0,0,AB19,~
0,0,0,0,0,0,0,0,0,0)';$S;
    'VSS_AB22':'(0,0,0,0,0,0,0,0,0,0,0,0,0,0,0,0,0,0,0,0,0,0,0,0,0,0,0,0,0,AB22,~
0,0,0,0,0,0,0,0,0,0)';$S;
    'VSS_AB25':'(0,0,0,0,0,0,0,0,0,0,0,0,0,0,0,0,0,0,0,0,0,0,0,0,0,0,0,0,0,AB25,~
0,0,0,0,0,0,0,0,0,0)';$S;
    'VSS_AB28':'(0,0,0,0,0,0,0,0,0,0,0,0,0,0,0,0,0,0,0,0,0,0,0,0,0,0,0,0,0,AB28,~
0,0,0,0,0,0,0,0,0,0)';$S;
    'VSS_AB31':'(0,0,0,0,0,0,0,0,0,0,0,0,0,0,0,0,0,0,0,0,0,0,0,0,0,0,0,0,0,AB31,~
0,0,0,0,0,0,0,0,0,0)';$S;
    'VSS_AB34':'(0,0,0,0,0,0,0,0,0,0,0,0,0,0,0,0,0,0,0,0,0,0,0,0,0,0,0,0,0,AB34,~
0,0,0,0,0,0,0,0,0,0)';$S;
    'VSS_AB37':'(0,0,0,0,0,0,0,0,0,0,0,0,0,0,0,0,0,0,0,0,0,0,0,0,0,0,0,0,0,AB37,~
0,0,0,0,0,0,0,0,0,0)';$S;
    'VSS_AB39':'(0,0,0,0,0,0,0,0,0,0,0,0,0,0,0,0,0,0,0,0,0,0,0,0,0,0,0,0,0,AB39,~
0,0,0,0,0,0,0,0,0,0)';$S;
    'VSS_AB42':'(0,0,0,0,0,0,0,0,0,0,0,0,0,0,0,0,0,0,0,0,0,0,0,0,0,0,0,0,0,AB42,~
0,0,0,0,0,0,0,0,0,0)';$S;
    'VSS_AB45':'(0,0,0,0,0,0,0,0,0,0,0,0,0,0,0,0,0,0,0,0,0,0,0,0,0,0,0,0,0,AB45,~
0,0,0,0,0,0,0,0,0,0)';$S;
    'VSS_AB48':'(0,0,0,0,0,0,0,0,0,0,0,0,0,0,0,0,0,0,0,0,0,0,0,0,0,0,0,0,0,AB48,~
0,0,0,0,0,0,0,0,0,0)';$S;
    'VSS_AB51':'(0,0,0,0,0,0,0,0,0,0,0,0,0,0,0,0,0,0,0,0,0,0,0,0,0,0,0,0,0,AB51,~
0,0,0,0,0,0,0,0,0,0)';$S;
    'VSS_AB54':'(0,0,0,0,0,0,0,0,0,0,0,0,0,0,0,0,0,0,0,0,0,0,0,0,0,0,0,0,0,AB54,~
0,0,0,0,0,0,0,0,0,0)';$S;
    'VSS_AB57':'(0,0,0,0,0,0,0,0,0,0,0,0,0,0,0,0,0,0,0,0,0,0,0,0,0,0,0,0,0,AB57,~
0,0,0,0,0,0,0,0,0,0)';$S;
    'VSS_AB59':'(0,0,0,0,0,0,0,0,0,0,0,0,0,0,0,0,0,0,0,0,0,0,0,0,0,0,0,0,0,AB59,~
0,0,0,0,0,0,0,0,0,0)';$S;
    'VSS_AB61':'(0,0,0,0,0,0,0,0,0,0,0,0,0,0,0,0,0,0,0,0,0,0,0,0,0,0,0,0,0,AB61,~
0,0,0,0,0,0,0,0,0,0)';$S;
    'VSS_AB64':'(0,0,0,0,0,0,0,0,0,0,0,0,0,0,0,0,0,0,0,0,0,0,0,0,0,0,0,0,0,AB64,~
0,0,0,0,0,0,0,0,0,0)';$S;
    'VSS_AB66':'(0,0,0,0,0,0,0,0,0,0,0,0,0,0,0,0,0,0,0,0,0,0,0,0,0,0,0,0,0,AB66,~
0,0,0,0,0,0,0,0,0,0)';$S;
    'VSS_AK10':'(0,0,0,0,0,0,0,0,0,0,0,0,0,0,0,0,0,0,0,0,0,0,0,0,0,0,0,0,0,0,AK1~
0,0,0,0,0,0,0,0,0,0)';$S;
    'VSS_AK12':'(0,0,0,0,0,0,0,0,0,0,0,0,0,0,0,0,0,0,0,0,0,0,0,0,0,0,0,0,0,0,AK1~
2,0,0,0,0,0,0,0,0,0)';$S;
    'VSS_AK15':'(0,0,0,0,0,0,0,0,0,0,0,0,0,0,0,0,0,0,0,0,0,0,0,0,0,0,0,0,0,0,AK1~
5,0,0,0,0,0,0,0,0,0)';$S;
    'VSS_AK17':'(0,0,0,0,0,0,0,0,0,0,0,0,0,0,0,0,0,0,0,0,0,0,0,0,0,0,0,0,0,0,AK1~
7,0,0,0,0,0,0,0,0,0)';$S;
    'VSS_AK19':'(0,0,0,0,0,0,0,0,0,0,0,0,0,0,0,0,0,0,0,0,0,0,0,0,0,0,0,0,0,0,AK1~
9,0,0,0,0,0,0,0,0,0)';$S;
    'VSS_AK22':'(0,0,0,0,0,0,0,0,0,0,0,0,0,0,0,0,0,0,0,0,0,0,0,0,0,0,0,0,0,0,AK2~
2,0,0,0,0,0,0,0,0,0)';$S;
    'VSS_AK25':'(0,0,0,0,0,0,0,0,0,0,0,0,0,0,0,0,0,0,0,0,0,0,0,0,0,0,0,0,0,0,AK2~
5,0,0,0,0,0,0,0,0,0)';$S;
    'VSS_AK28':'(0,0,0,0,0,0,0,0,0,0,0,0,0,0,0,0,0,0,0,0,0,0,0,0,0,0,0,0,0,0,AK2~
8,0,0,0,0,0,0,0,0,0)';$S;
    'VSS_AK31':'(0,0,0,0,0,0,0,0,0,0,0,0,0,0,0,0,0,0,0,0,0,0,0,0,0,0,0,0,0,0,AK3~
1,0,0,0,0,0,0,0,0,0)';$S;
    'VSS_AK34':'(0,0,0,0,0,0,0,0,0,0,0,0,0,0,0,0,0,0,0,0,0,0,0,0,0,0,0,0,0,0,AK3~
4,0,0,0,0,0,0,0,0,0)';$S;
    'VSS_AK37':'(0,0,0,0,0,0,0,0,0,0,0,0,0,0,0,0,0,0,0,0,0,0,0,0,0,0,0,0,0,0,AK3~
7,0,0,0,0,0,0,0,0,0)';$S;
    'VSS_AK39':'(0,0,0,0,0,0,0,0,0,0,0,0,0,0,0,0,0,0,0,0,0,0,0,0,0,0,0,0,0,0,AK3~
9,0,0,0,0,0,0,0,0,0)';$S;
    'VSS_AK42':'(0,0,0,0,0,0,0,0,0,0,0,0,0,0,0,0,0,0,0,0,0,0,0,0,0,0,0,0,0,0,AK4~
2,0,0,0,0,0,0,0,0,0)';$S;
    'VSS_AK45':'(0,0,0,0,0,0,0,0,0,0,0,0,0,0,0,0,0,0,0,0,0,0,0,0,0,0,0,0,0,0,AK4~
5,0,0,0,0,0,0,0,0,0)';$S;
    'VSS_AK48':'(0,0,0,0,0,0,0,0,0,0,0,0,0,0,0,0,0,0,0,0,0,0,0,0,0,0,0,0,0,0,AK4~
8,0,0,0,0,0,0,0,0,0)';$S;
    'VSS_AK51':'(0,0,0,0,0,0,0,0,0,0,0,0,0,0,0,0,0,0,0,0,0,0,0,0,0,0,0,0,0,0,AK5~
1,0,0,0,0,0,0,0,0,0)';$S;
    'VSS_AK54':'(0,0,0,0,0,0,0,0,0,0,0,0,0,0,0,0,0,0,0,0,0,0,0,0,0,0,0,0,0,0,AK5~
4,0,0,0,0,0,0,0,0,0)';$S;
    'VSS_AK57':'(0,0,0,0,0,0,0,0,0,0,0,0,0,0,0,0,0,0,0,0,0,0,0,0,0,0,0,0,0,0,AK5~
7,0,0,0,0,0,0,0,0,0)';$S;
    'VSS_AK59':'(0,0,0,0,0,0,0,0,0,0,0,0,0,0,0,0,0,0,0,0,0,0,0,0,0,0,0,0,0,0,AK5~
9,0,0,0,0,0,0,0,0,0)';$S;
    'VSS_AK61':'(0,0,0,0,0,0,0,0,0,0,0,0,0,0,0,0,0,0,0,0,0,0,0,0,0,0,0,0,0,0,AK6~
1,0,0,0,0,0,0,0,0,0)';$S;
    'VSS_AK64':'(0,0,0,0,0,0,0,0,0,0,0,0,0,0,0,0,0,0,0,0,0,0,0,0,0,0,0,0,0,0,AK6~
4,0,0,0,0,0,0,0,0,0)';$S;
    'VSS_AK66':'(0,0,0,0,0,0,0,0,0,0,0,0,0,0,0,0,0,0,0,0,0,0,0,0,0,0,0,0,0,0,AK6~
6,0,0,0,0,0,0,0,0,0)';$S;
    'VSS_AK68':'(0,0,0,0,0,0,0,0,0,0,0,0,0,0,0,0,0,0,0,0,0,0,0,0,0,0,0,0,0,0,AK6~
8,0,0,0,0,0,0,0,0,0)';$S;
    'VSS_AK71':'(0,0,0,0,0,0,0,0,0,0,0,0,0,0,0,0,0,0,0,0,0,0,0,0,0,0,0,0,0,0,AK7~
1,0,0,0,0,0,0,0,0,0)';$S;
    'VSS_AK73':'(0,0,0,0,0,0,0,0,0,0,0,0,0,0,0,0,0,0,0,0,0,0,0,0,0,0,0,0,0,0,AK7~
3,0,0,0,0,0,0,0,0,0)';$S;
    'VSS_AL1':'(0,0,0,0,0,0,0,0,0,0,0,0,0,0,0,0,0,0,0,0,0,0,0,0,0,0,0,0,0,0,AL1,~
0,0,0,0,0,0,0,0,0)';$S;
    'VSS_AL4':'(0,0,0,0,0,0,0,0,0,0,0,0,0,0,0,0,0,0,0,0,0,0,0,0,0,0,0,0,0,0,AL4,~
0,0,0,0,0,0,0,0,0)';$S;
    'VSS_AL6':'(0,0,0,0,0,0,0,0,0,0,0,0,0,0,0,0,0,0,0,0,0,0,0,0,0,0,0,0,0,0,AL6,~
0,0,0,0,0,0,0,0,0)';$S;
    'VSS_AL8':'(0,0,0,0,0,0,0,0,0,0,0,0,0,0,0,0,0,0,0,0,0,0,0,0,0,0,0,0,0,0,AL8,~
0,0,0,0,0,0,0,0,0)';$S;
    'VSS_AL11':'(0,0,0,0,0,0,0,0,0,0,0,0,0,0,0,0,0,0,0,0,0,0,0,0,0,0,0,0,0,0,AL1~
1,0,0,0,0,0,0,0,0,0)';$S;
    'VSS_AL13':'(0,0,0,0,0,0,0,0,0,0,0,0,0,0,0,0,0,0,0,0,0,0,0,0,0,0,0,0,0,0,AL1~
3,0,0,0,0,0,0,0,0,0)';$S;
    'VSS_AL15':'(0,0,0,0,0,0,0,0,0,0,0,0,0,0,0,0,0,0,0,0,0,0,0,0,0,0,0,0,0,0,AL1~
5,0,0,0,0,0,0,0,0,0)';$S;
    'VSS_AL18':'(0,0,0,0,0,0,0,0,0,0,0,0,0,0,0,0,0,0,0,0,0,0,0,0,0,0,0,0,0,0,AL1~
8,0,0,0,0,0,0,0,0,0)';$S;
    'VSS_AL20':'(0,0,0,0,0,0,0,0,0,0,0,0,0,0,0,0,0,0,0,0,0,0,0,0,0,0,0,0,0,0,AL2~
0,0,0,0,0,0,0,0,0,0)';$S;
    'VSS_AL22':'(0,0,0,0,0,0,0,0,0,0,0,0,0,0,0,0,0,0,0,0,0,0,0,0,0,0,0,0,0,0,AL2~
2,0,0,0,0,0,0,0,0,0)';$S;
    'VSS_AL25':'(0,0,0,0,0,0,0,0,0,0,0,0,0,0,0,0,0,0,0,0,0,0,0,0,0,0,0,0,0,0,AL2~
5,0,0,0,0,0,0,0,0,0)';$S;
    'VSS_AL28':'(0,0,0,0,0,0,0,0,0,0,0,0,0,0,0,0,0,0,0,0,0,0,0,0,0,0,0,0,0,0,AL2~
8,0,0,0,0,0,0,0,0,0)';$S;
    'VSS_AL31':'(0,0,0,0,0,0,0,0,0,0,0,0,0,0,0,0,0,0,0,0,0,0,0,0,0,0,0,0,0,0,AL3~
1,0,0,0,0,0,0,0,0,0)';$S;
    'VSS_AL34':'(0,0,0,0,0,0,0,0,0,0,0,0,0,0,0,0,0,0,0,0,0,0,0,0,0,0,0,0,0,0,AL3~
4,0,0,0,0,0,0,0,0,0)';$S;
    'VSS_AL42':'(0,0,0,0,0,0,0,0,0,0,0,0,0,0,0,0,0,0,0,0,0,0,0,0,0,0,0,0,0,0,AL4~
2,0,0,0,0,0,0,0,0,0)';$S;
    'VSS_AL45':'(0,0,0,0,0,0,0,0,0,0,0,0,0,0,0,0,0,0,0,0,0,0,0,0,0,0,0,0,0,0,AL4~
5,0,0,0,0,0,0,0,0,0)';$S;
    'VSS_AL48':'(0,0,0,0,0,0,0,0,0,0,0,0,0,0,0,0,0,0,0,0,0,0,0,0,0,0,0,0,0,0,AL4~
8,0,0,0,0,0,0,0,0,0)';$S;
    'VSS_AL51':'(0,0,0,0,0,0,0,0,0,0,0,0,0,0,0,0,0,0,0,0,0,0,0,0,0,0,0,0,0,0,AL5~
1,0,0,0,0,0,0,0,0,0)';$S;
    'VSS_AL54':'(0,0,0,0,0,0,0,0,0,0,0,0,0,0,0,0,0,0,0,0,0,0,0,0,0,0,0,0,0,0,AL5~
4,0,0,0,0,0,0,0,0,0)';$S;
    'VSS_AL56':'(0,0,0,0,0,0,0,0,0,0,0,0,0,0,0,0,0,0,0,0,0,0,0,0,0,0,0,0,0,0,AL5~
6,0,0,0,0,0,0,0,0,0)';$S;
    'VSS_AL58':'(0,0,0,0,0,0,0,0,0,0,0,0,0,0,0,0,0,0,0,0,0,0,0,0,0,0,0,0,0,0,AL5~
8,0,0,0,0,0,0,0,0,0)';$S;
    'VSS_AL61':'(0,0,0,0,0,0,0,0,0,0,0,0,0,0,0,0,0,0,0,0,0,0,0,0,0,0,0,0,0,0,AL6~
1,0,0,0,0,0,0,0,0,0)';$S;
    'VSS_AL63':'(0,0,0,0,0,0,0,0,0,0,0,0,0,0,0,0,0,0,0,0,0,0,0,0,0,0,0,0,0,0,AL6~
3,0,0,0,0,0,0,0,0,0)';$S;
    'VSS_AL65':'(0,0,0,0,0,0,0,0,0,0,0,0,0,0,0,0,0,0,0,0,0,0,0,0,0,0,0,0,0,0,AL6~
5,0,0,0,0,0,0,0,0,0)';$S;
    'VSS_AL68':'(0,0,0,0,0,0,0,0,0,0,0,0,0,0,0,0,0,0,0,0,0,0,0,0,0,0,0,0,0,0,AL6~
8,0,0,0,0,0,0,0,0,0)';$S;
    'VSS_AL70':'(0,0,0,0,0,0,0,0,0,0,0,0,0,0,0,0,0,0,0,0,0,0,0,0,0,0,0,0,0,0,AL7~
0,0,0,0,0,0,0,0,0,0)';$S;
    'VSS_AL72':'(0,0,0,0,0,0,0,0,0,0,0,0,0,0,0,0,0,0,0,0,0,0,0,0,0,0,0,0,0,0,AL7~
2,0,0,0,0,0,0,0,0,0)';$S;
    'VSS_AL75':'(0,0,0,0,0,0,0,0,0,0,0,0,0,0,0,0,0,0,0,0,0,0,0,0,0,0,0,0,0,0,AL7~
5,0,0,0,0,0,0,0,0,0)';$S;
    'VSS_AM3':'(0,0,0,0,0,0,0,0,0,0,0,0,0,0,0,0,0,0,0,0,0,0,0,0,0,0,0,0,0,0,AM3,~
0,0,0,0,0,0,0,0,0)';$S;
    'VSS_AM8':'(0,0,0,0,0,0,0,0,0,0,0,0,0,0,0,0,0,0,0,0,0,0,0,0,0,0,0,0,0,0,AM8,~
0,0,0,0,0,0,0,0,0)';$S;
    'VSS_AM10':'(0,0,0,0,0,0,0,0,0,0,0,0,0,0,0,0,0,0,0,0,0,0,0,0,0,0,0,0,0,0,AM1~
0,0,0,0,0,0,0,0,0,0)';$S;
    'VSS_AM15':'(0,0,0,0,0,0,0,0,0,0,0,0,0,0,0,0,0,0,0,0,0,0,0,0,0,0,0,0,0,0,AM1~
5,0,0,0,0,0,0,0,0,0)';$S;
    'VSS_AM17':'(0,0,0,0,0,0,0,0,0,0,0,0,0,0,0,0,0,0,0,0,0,0,0,0,0,0,0,0,0,0,AM1~
7,0,0,0,0,0,0,0,0,0)';$S;
    'VSS_AM23':'(0,0,0,0,0,0,0,0,0,0,0,0,0,0,0,0,0,0,0,0,0,0,0,0,0,0,0,0,0,0,AM2~
3,0,0,0,0,0,0,0,0,0)';$S;
    'VSS_AM24':'(0,0,0,0,0,0,0,0,0,0,0,0,0,0,0,0,0,0,0,0,0,0,0,0,0,0,0,0,0,0,AM2~
4,0,0,0,0,0,0,0,0,0)';$S;
    'VSS_AM25':'(0,0,0,0,0,0,0,0,0,0,0,0,0,0,0,0,0,0,0,0,0,0,0,0,0,0,0,0,0,0,AM2~
5,0,0,0,0,0,0,0,0,0)';$S;
    'VSS_AM26':'(0,0,0,0,0,0,0,0,0,0,0,0,0,0,0,0,0,0,0,0,0,0,0,0,0,0,0,0,0,0,AM2~
6,0,0,0,0,0,0,0,0,0)';$S;
    'VSS_AM27':'(0,0,0,0,0,0,0,0,0,0,0,0,0,0,0,0,0,0,0,0,0,0,0,0,0,0,0,0,0,0,AM2~
7,0,0,0,0,0,0,0,0,0)';$S;
    'VSS_AM28':'(0,0,0,0,0,0,0,0,0,0,0,0,0,0,0,0,0,0,0,0,0,0,0,0,0,0,0,0,0,0,AM2~
8,0,0,0,0,0,0,0,0,0)';$S;
    'VSS_AM29':'(0,0,0,0,0,0,0,0,0,0,0,0,0,0,0,0,0,0,0,0,0,0,0,0,0,0,0,0,0,0,AM2~
9,0,0,0,0,0,0,0,0,0)';$S;
    'VSS_AM30':'(0,0,0,0,0,0,0,0,0,0,0,0,0,0,0,0,0,0,0,0,0,0,0,0,0,0,0,0,0,0,AM3~
0,0,0,0,0,0,0,0,0,0)';$S;
    'VSS_AM31':'(0,0,0,0,0,0,0,0,0,0,0,0,0,0,0,0,0,0,0,0,0,0,0,0,0,0,0,0,0,0,AM3~
1,0,0,0,0,0,0,0,0,0)';$S;
    'VSS_AM32':'(0,0,0,0,0,0,0,0,0,0,0,0,0,0,0,0,0,0,0,0,0,0,0,0,0,0,0,0,0,0,AM3~
2,0,0,0,0,0,0,0,0,0)';$S;
    'VSS_AM33':'(0,0,0,0,0,0,0,0,0,0,0,0,0,0,0,0,0,0,0,0,0,0,0,0,0,0,0,0,0,0,AM3~
3,0,0,0,0,0,0,0,0,0)';$S;
    'VSS_AM34':'(0,0,0,0,0,0,0,0,0,0,0,0,0,0,0,0,0,0,0,0,0,0,0,0,0,0,0,0,0,0,AM3~
4,0,0,0,0,0,0,0,0,0)';$S;
    'VSS_AM39':'(0,0,0,0,0,0,0,0,0,0,0,0,0,0,0,0,0,0,0,0,0,0,0,0,0,0,0,0,0,0,AM3~
9,0,0,0,0,0,0,0,0,0)';$S;
    'VSS_AD49':'(0,0,0,0,0,0,0,0,0,0,0,0,0,0,0,0,0,0,0,0,0,0,0,0,0,0,0,0,0,0,AD4~
9,0,0,0,0,0,0,0,0,0)';$S;
    'VSS_AD50':'(0,0,0,0,0,0,0,0,0,0,0,0,0,0,0,0,0,0,0,0,0,0,0,0,0,0,0,0,0,0,AD5~
0,0,0,0,0,0,0,0,0,0)';$S;
    'VSS_AD51':'(0,0,0,0,0,0,0,0,0,0,0,0,0,0,0,0,0,0,0,0,0,0,0,0,0,0,0,0,0,0,AD5~
1,0,0,0,0,0,0,0,0,0)';$S;
    'VSS_AD52':'(0,0,0,0,0,0,0,0,0,0,0,0,0,0,0,0,0,0,0,0,0,0,0,0,0,0,0,0,0,0,AD5~
2,0,0,0,0,0,0,0,0,0)';$S;
    'VSS_AD53':'(0,0,0,0,0,0,0,0,0,0,0,0,0,0,0,0,0,0,0,0,0,0,0,0,0,0,0,0,0,0,AD5~
3,0,0,0,0,0,0,0,0,0)';$S;
    'VSS_AD57':'(0,0,0,0,0,0,0,0,0,0,0,0,0,0,0,0,0,0,0,0,0,0,0,0,0,0,0,0,0,0,AD5~
7,0,0,0,0,0,0,0,0,0)';$S;
    'VSS_AD59':'(0,0,0,0,0,0,0,0,0,0,0,0,0,0,0,0,0,0,0,0,0,0,0,0,0,0,0,0,0,0,AD5~
9,0,0,0,0,0,0,0,0,0)';$S;
    'VSS_AD61':'(0,0,0,0,0,0,0,0,0,0,0,0,0,0,0,0,0,0,0,0,0,0,0,0,0,0,0,0,0,0,AD6~
1,0,0,0,0,0,0,0,0,0)';$S;
    'VSS_AD64':'(0,0,0,0,0,0,0,0,0,0,0,0,0,0,0,0,0,0,0,0,0,0,0,0,0,0,0,0,0,0,AD6~
4,0,0,0,0,0,0,0,0,0)';$S;
    'VSS_AD66':'(0,0,0,0,0,0,0,0,0,0,0,0,0,0,0,0,0,0,0,0,0,0,0,0,0,0,0,0,0,0,AD6~
6,0,0,0,0,0,0,0,0,0)';$S;
    'VSS_AD68':'(0,0,0,0,0,0,0,0,0,0,0,0,0,0,0,0,0,0,0,0,0,0,0,0,0,0,0,0,0,0,AD6~
8,0,0,0,0,0,0,0,0,0)';$S;
    'VSS_AD71':'(0,0,0,0,0,0,0,0,0,0,0,0,0,0,0,0,0,0,0,0,0,0,0,0,0,0,0,0,0,0,AD7~
1,0,0,0,0,0,0,0,0,0)';$S;
    'VSS_AD73':'(0,0,0,0,0,0,0,0,0,0,0,0,0,0,0,0,0,0,0,0,0,0,0,0,0,0,0,0,0,0,AD7~
3,0,0,0,0,0,0,0,0,0)';$S;
    'VSS_AE1':'(0,0,0,0,0,0,0,0,0,0,0,0,0,0,0,0,0,0,0,0,0,0,0,0,0,0,0,0,0,0,AE1,~
0,0,0,0,0,0,0,0,0)';$S;
    'VSS_AE6':'(0,0,0,0,0,0,0,0,0,0,0,0,0,0,0,0,0,0,0,0,0,0,0,0,0,0,0,0,0,0,AE6,~
0,0,0,0,0,0,0,0,0)';$S;
    'VSS_AE8':'(0,0,0,0,0,0,0,0,0,0,0,0,0,0,0,0,0,0,0,0,0,0,0,0,0,0,0,0,0,0,AE8,~
0,0,0,0,0,0,0,0,0)';$S;
    'VSS_AE11':'(0,0,0,0,0,0,0,0,0,0,0,0,0,0,0,0,0,0,0,0,0,0,0,0,0,0,0,0,0,0,AE1~
1,0,0,0,0,0,0,0,0,0)';$S;
    'VSS_AE13':'(0,0,0,0,0,0,0,0,0,0,0,0,0,0,0,0,0,0,0,0,0,0,0,0,0,0,0,0,0,0,AE1~
3,0,0,0,0,0,0,0,0,0)';$S;
    'VSS_AE15':'(0,0,0,0,0,0,0,0,0,0,0,0,0,0,0,0,0,0,0,0,0,0,0,0,0,0,0,0,0,0,AE1~
5,0,0,0,0,0,0,0,0,0)';$S;
    'VSS_AE18':'(0,0,0,0,0,0,0,0,0,0,0,0,0,0,0,0,0,0,0,0,0,0,0,0,0,0,0,0,0,0,AE1~
8,0,0,0,0,0,0,0,0,0)';$S;
    'VSS_AE20':'(0,0,0,0,0,0,0,0,0,0,0,0,0,0,0,0,0,0,0,0,0,0,0,0,0,0,0,0,0,0,AE2~
0,0,0,0,0,0,0,0,0,0)';$S;
    'VSS_AE22':'(0,0,0,0,0,0,0,0,0,0,0,0,0,0,0,0,0,0,0,0,0,0,0,0,0,0,0,0,0,0,AE2~
2,0,0,0,0,0,0,0,0,0)';$S;
    'VSS_AE25':'(0,0,0,0,0,0,0,0,0,0,0,0,0,0,0,0,0,0,0,0,0,0,0,0,0,0,0,0,0,0,AE2~
5,0,0,0,0,0,0,0,0,0)';$S;
    'VSS_AE28':'(0,0,0,0,0,0,0,0,0,0,0,0,0,0,0,0,0,0,0,0,0,0,0,0,0,0,0,0,0,0,AE2~
8,0,0,0,0,0,0,0,0,0)';$S;
    'VSS_AE31':'(0,0,0,0,0,0,0,0,0,0,0,0,0,0,0,0,0,0,0,0,0,0,0,0,0,0,0,0,0,0,AE3~
1,0,0,0,0,0,0,0,0,0)';$S;
    'VSS_AE34':'(0,0,0,0,0,0,0,0,0,0,0,0,0,0,0,0,0,0,0,0,0,0,0,0,0,0,0,0,0,0,AE3~
4,0,0,0,0,0,0,0,0,0)';$S;
    'VSS_AE35':'(0,0,0,0,0,0,0,0,0,0,0,0,0,0,0,0,0,0,0,0,0,0,0,0,0,0,0,0,0,0,AE3~
5,0,0,0,0,0,0,0,0,0)';$S;
    'VSS_AE36':'(0,0,0,0,0,0,0,0,0,0,0,0,0,0,0,0,0,0,0,0,0,0,0,0,0,0,0,0,0,0,AE3~
6,0,0,0,0,0,0,0,0,0)';$S;
    'VSS_AE40':'(0,0,0,0,0,0,0,0,0,0,0,0,0,0,0,0,0,0,0,0,0,0,0,0,0,0,0,0,0,0,AE4~
0,0,0,0,0,0,0,0,0,0)';$S;
    'VSS_AE41':'(0,0,0,0,0,0,0,0,0,0,0,0,0,0,0,0,0,0,0,0,0,0,0,0,0,0,0,0,0,0,AE4~
1,0,0,0,0,0,0,0,0,0)';$S;
    'VSS_AE42':'(0,0,0,0,0,0,0,0,0,0,0,0,0,0,0,0,0,0,0,0,0,0,0,0,0,0,0,0,0,0,AE4~
2,0,0,0,0,0,0,0,0,0)';$S;
    'VSS_AE45':'(0,0,0,0,0,0,0,0,0,0,0,0,0,0,0,0,0,0,0,0,0,0,0,0,0,0,0,0,0,0,AE4~
5,0,0,0,0,0,0,0,0,0)';$S;
    'VSS_AE48':'(0,0,0,0,0,0,0,0,0,0,0,0,0,0,0,0,0,0,0,0,0,0,0,0,0,0,0,0,0,0,AE4~
8,0,0,0,0,0,0,0,0,0)';$S;
    'VSS_AE51':'(0,0,0,0,0,0,0,0,0,0,0,0,0,0,0,0,0,0,0,0,0,0,0,0,0,0,0,0,0,0,AE5~
1,0,0,0,0,0,0,0,0,0)';$S;
    'VSS_AE54':'(0,0,0,0,0,0,0,0,0,0,0,0,0,0,0,0,0,0,0,0,0,0,0,0,0,0,0,0,0,0,AE5~
4,0,0,0,0,0,0,0,0,0)';$S;
    'VSS_AE56':'(0,0,0,0,0,0,0,0,0,0,0,0,0,0,0,0,0,0,0,0,0,0,0,0,0,0,0,0,0,0,AE5~
6,0,0,0,0,0,0,0,0,0)';$S;
    'VSS_AE58':'(0,0,0,0,0,0,0,0,0,0,0,0,0,0,0,0,0,0,0,0,0,0,0,0,0,0,0,0,0,0,AE5~
8,0,0,0,0,0,0,0,0,0)';$S;
    'VSS_AE61':'(0,0,0,0,0,0,0,0,0,0,0,0,0,0,0,0,0,0,0,0,0,0,0,0,0,0,0,0,0,0,AE6~
1,0,0,0,0,0,0,0,0,0)';$S;
    'VSS_AE63':'(0,0,0,0,0,0,0,0,0,0,0,0,0,0,0,0,0,0,0,0,0,0,0,0,0,0,0,0,0,0,AE6~
3,0,0,0,0,0,0,0,0,0)';$S;
    'VSS_AE65':'(0,0,0,0,0,0,0,0,0,0,0,0,0,0,0,0,0,0,0,0,0,0,0,0,0,0,0,0,0,0,AE6~
5,0,0,0,0,0,0,0,0,0)';$S;
    'VSS_AE68':'(0,0,0,0,0,0,0,0,0,0,0,0,0,0,0,0,0,0,0,0,0,0,0,0,0,0,0,0,0,0,AE6~
8,0,0,0,0,0,0,0,0,0)';$S;
    'VSS_AE70':'(0,0,0,0,0,0,0,0,0,0,0,0,0,0,0,0,0,0,0,0,0,0,0,0,0,0,0,0,0,0,AE7~
0,0,0,0,0,0,0,0,0,0)';$S;
    'VSS_AE72':'(0,0,0,0,0,0,0,0,0,0,0,0,0,0,0,0,0,0,0,0,0,0,0,0,0,0,0,0,0,0,AE7~
2,0,0,0,0,0,0,0,0,0)';$S;
    'VSS_AE75':'(0,0,0,0,0,0,0,0,0,0,0,0,0,0,0,0,0,0,0,0,0,0,0,0,0,0,0,0,0,0,AE7~
5,0,0,0,0,0,0,0,0,0)';$S;
    'VSS_AF3':'(0,0,0,0,0,0,0,0,0,0,0,0,0,0,0,0,0,0,0,0,0,0,0,0,0,0,0,0,0,0,AF3,~
0,0,0,0,0,0,0,0,0)';$S;
    'VSS_AF8':'(0,0,0,0,0,0,0,0,0,0,0,0,0,0,0,0,0,0,0,0,0,0,0,0,0,0,0,0,0,0,AF8,~
0,0,0,0,0,0,0,0,0)';$S;
    'VSS_AF10':'(0,0,0,0,0,0,0,0,0,0,0,0,0,0,0,0,0,0,0,0,0,0,0,0,0,0,0,0,0,0,AF1~
0,0,0,0,0,0,0,0,0,0)';$S;
    'VSS_AF15':'(0,0,0,0,0,0,0,0,0,0,0,0,0,0,0,0,0,0,0,0,0,0,0,0,0,0,0,0,0,0,AF1~
5,0,0,0,0,0,0,0,0,0)';$S;
    'VSS_AF17':'(0,0,0,0,0,0,0,0,0,0,0,0,0,0,0,0,0,0,0,0,0,0,0,0,0,0,0,0,0,0,AF1~
7,0,0,0,0,0,0,0,0,0)';$S;
    'VSS_AF22':'(0,0,0,0,0,0,0,0,0,0,0,0,0,0,0,0,0,0,0,0,0,0,0,0,0,0,0,0,0,0,AF2~
2,0,0,0,0,0,0,0,0,0)';$S;
    'VSS_AF25':'(0,0,0,0,0,0,0,0,0,0,0,0,0,0,0,0,0,0,0,0,0,0,0,0,0,0,0,0,0,0,AF2~
5,0,0,0,0,0,0,0,0,0)';$S;
    'VSS_AF28':'(0,0,0,0,0,0,0,0,0,0,0,0,0,0,0,0,0,0,0,0,0,0,0,0,0,0,0,0,0,0,AF2~
8,0,0,0,0,0,0,0,0,0)';$S;
    'VSS_AF31':'(0,0,0,0,0,0,0,0,0,0,0,0,0,0,0,0,0,0,0,0,0,0,0,0,0,0,0,0,0,0,AF3~
1,0,0,0,0,0,0,0,0,0)';$S;
    'VSS_AF34':'(0,0,0,0,0,0,0,0,0,0,0,0,0,0,0,0,0,0,0,0,0,0,0,0,0,0,0,0,0,0,AF3~
4,0,0,0,0,0,0,0,0,0)';$S;
    'VSS_AF37':'(0,0,0,0,0,0,0,0,0,0,0,0,0,0,0,0,0,0,0,0,0,0,0,0,0,0,0,0,0,0,AF3~
7,0,0,0,0,0,0,0,0,0)';$S;
    'VSS_AF39':'(0,0,0,0,0,0,0,0,0,0,0,0,0,0,0,0,0,0,0,0,0,0,0,0,0,0,0,0,0,0,AF3~
9,0,0,0,0,0,0,0,0,0)';$S;
    'VSS_AF42':'(0,0,0,0,0,0,0,0,0,0,0,0,0,0,0,0,0,0,0,0,0,0,0,0,0,0,0,0,0,0,AF4~
2,0,0,0,0,0,0,0,0,0)';$S;
    'VSS_AF45':'(0,0,0,0,0,0,0,0,0,0,0,0,0,0,0,0,0,0,0,0,0,0,0,0,0,0,0,0,0,0,AF4~
5,0,0,0,0,0,0,0,0,0)';$S;
    'VSS_AF48':'(0,0,0,0,0,0,0,0,0,0,0,0,0,0,0,0,0,0,0,0,0,0,0,0,0,0,0,0,0,0,AF4~
8,0,0,0,0,0,0,0,0,0)';$S;
    'VSS_AF51':'(0,0,0,0,0,0,0,0,0,0,0,0,0,0,0,0,0,0,0,0,0,0,0,0,0,0,0,0,0,0,AF5~
1,0,0,0,0,0,0,0,0,0)';$S;
    'VSS_AF54':'(0,0,0,0,0,0,0,0,0,0,0,0,0,0,0,0,0,0,0,0,0,0,0,0,0,0,0,0,0,0,AF5~
4,0,0,0,0,0,0,0,0,0)';$S;
    'VSS_AF59':'(0,0,0,0,0,0,0,0,0,0,0,0,0,0,0,0,0,0,0,0,0,0,0,0,0,0,0,0,0,0,AF5~
9,0,0,0,0,0,0,0,0,0)';$S;
    'VSS_AF61':'(0,0,0,0,0,0,0,0,0,0,0,0,0,0,0,0,0,0,0,0,0,0,0,0,0,0,0,0,0,0,AF6~
1,0,0,0,0,0,0,0,0,0)';$S;
    'VSS_AF66':'(0,0,0,0,0,0,0,0,0,0,0,0,0,0,0,0,0,0,0,0,0,0,0,0,0,0,0,0,0,0,AF6~
6,0,0,0,0,0,0,0,0,0)';$S;
    'VSS_AF68':'(0,0,0,0,0,0,0,0,0,0,0,0,0,0,0,0,0,0,0,0,0,0,0,0,0,0,0,0,0,0,AF6~
8,0,0,0,0,0,0,0,0,0)';$S;
    'VSS_AF73':'(0,0,0,0,0,0,0,0,0,0,0,0,0,0,0,0,0,0,0,0,0,0,0,0,0,0,0,0,0,0,AF7~
3,0,0,0,0,0,0,0,0,0)';$S;
    'VSS_AG1':'(0,0,0,0,0,0,0,0,0,0,0,0,0,0,0,0,0,0,0,0,0,0,0,0,0,0,0,0,0,0,AG1,~
0,0,0,0,0,0,0,0,0)';$S;
    'VSS_AG4':'(0,0,0,0,0,0,0,0,0,0,0,0,0,0,0,0,0,0,0,0,0,0,0,0,0,0,0,0,0,0,AG4,~
0,0,0,0,0,0,0,0,0)';$S;
    'VSS_AG6':'(0,0,0,0,0,0,0,0,0,0,0,0,0,0,0,0,0,0,0,0,0,0,0,0,0,0,0,0,0,0,AG6,~
0,0,0,0,0,0,0,0,0)';$S;
    'VSS_AG8':'(0,0,0,0,0,0,0,0,0,0,0,0,0,0,0,0,0,0,0,0,0,0,0,0,0,0,0,0,0,0,AG8,~
0,0,0,0,0,0,0,0,0)';$S;
    'VSS_AG11':'(0,0,0,0,0,0,0,0,0,0,0,0,0,0,0,0,0,0,0,0,0,0,0,0,0,0,0,0,0,0,AG1~
1,0,0,0,0,0,0,0,0,0)';$S;
    'VSS_AG13':'(0,0,0,0,0,0,0,0,0,0,0,0,0,0,0,0,0,0,0,0,0,0,0,0,0,0,0,0,0,0,AG1~
3,0,0,0,0,0,0,0,0,0)';$S;
    'VSS_AG15':'(0,0,0,0,0,0,0,0,0,0,0,0,0,0,0,0,0,0,0,0,0,0,0,0,0,0,0,0,0,0,AG1~
5,0,0,0,0,0,0,0,0,0)';$S;
    'VSS_AG18':'(0,0,0,0,0,0,0,0,0,0,0,0,0,0,0,0,0,0,0,0,0,0,0,0,0,0,0,0,0,0,AG1~
8,0,0,0,0,0,0,0,0,0)';$S;
    'VSS_AG20':'(0,0,0,0,0,0,0,0,0,0,0,0,0,0,0,0,0,0,0,0,0,0,0,0,0,0,0,0,0,0,AG2~
0,0,0,0,0,0,0,0,0,0)';$S;
    'VSS_AG22':'(0,0,0,0,0,0,0,0,0,0,0,0,0,0,0,0,0,0,0,0,0,0,0,0,0,0,0,0,0,0,AG2~
2,0,0,0,0,0,0,0,0,0)';$S;
    'VSS_AG25':'(0,0,0,0,0,0,0,0,0,0,0,0,0,0,0,0,0,0,0,0,0,0,0,0,0,0,0,0,0,0,AG2~
5,0,0,0,0,0,0,0,0,0)';$S;
    'VSS_AG28':'(0,0,0,0,0,0,0,0,0,0,0,0,0,0,0,0,0,0,0,0,0,0,0,0,0,0,0,0,0,0,AG2~
8,0,0,0,0,0,0,0,0,0)';$S;
    'VSS_AG31':'(0,0,0,0,0,0,0,0,0,0,0,0,0,0,0,0,0,0,0,0,0,0,0,0,0,0,0,0,0,0,AG3~
1,0,0,0,0,0,0,0,0,0)';$S;
    'VSS_AG34':'(0,0,0,0,0,0,0,0,0,0,0,0,0,0,0,0,0,0,0,0,0,0,0,0,0,0,0,0,0,0,AG3~
4,0,0,0,0,0,0,0,0,0)';$S;
    'VSS_AG42':'(0,0,0,0,0,0,0,0,0,0,0,0,0,0,0,0,0,0,0,0,0,0,0,0,0,0,0,0,0,0,AG4~
2,0,0,0,0,0,0,0,0,0)';$S;
    'VSS_AG45':'(0,0,0,0,0,0,0,0,0,0,0,0,0,0,0,0,0,0,0,0,0,0,0,0,0,0,0,0,0,0,AG4~
5,0,0,0,0,0,0,0,0,0)';$S;
    'VSS_AG48':'(0,0,0,0,0,0,0,0,0,0,0,0,0,0,0,0,0,0,0,0,0,0,0,0,0,0,0,0,0,0,AG4~
8,0,0,0,0,0,0,0,0,0)';$S;
    'VSS_AG51':'(0,0,0,0,0,0,0,0,0,0,0,0,0,0,0,0,0,0,0,0,0,0,0,0,0,0,0,0,0,0,AG5~
1,0,0,0,0,0,0,0,0,0)';$S;
    'VSS_AG54':'(0,0,0,0,0,0,0,0,0,0,0,0,0,0,0,0,0,0,0,0,0,0,0,0,0,0,0,0,0,0,AG5~
4,0,0,0,0,0,0,0,0,0)';$S;
    'VSS_AG56':'(0,0,0,0,0,0,0,0,0,0,0,0,0,0,0,0,0,0,0,0,0,0,0,0,0,0,0,0,0,0,AG5~
6,0,0,0,0,0,0,0,0,0)';$S;
    'VSS_AG58':'(0,0,0,0,0,0,0,0,0,0,0,0,0,0,0,0,0,0,0,0,0,0,0,0,0,0,0,0,0,0,AG5~
8,0,0,0,0,0,0,0,0,0)';$S;
    'VSS_AG61':'(0,0,0,0,0,0,0,0,0,0,0,0,0,0,0,0,0,0,0,0,0,0,0,0,0,0,0,0,0,0,AG6~
1,0,0,0,0,0,0,0,0,0)';$S;
    'VSS_AG63':'(0,0,0,0,0,0,0,0,0,0,0,0,0,0,0,0,0,0,0,0,0,0,0,0,0,0,0,0,0,0,AG6~
3,0,0,0,0,0,0,0,0,0)';$S;
    'VSS_AG65':'(0,0,0,0,0,0,0,0,0,0,0,0,0,0,0,0,0,0,0,0,0,0,0,0,0,0,0,0,0,0,AG6~
5,0,0,0,0,0,0,0,0,0)';$S;
    'VSS_AG68':'(0,0,0,0,0,0,0,0,0,0,0,0,0,0,0,0,0,0,0,0,0,0,0,0,0,0,0,0,0,0,AG6~
8,0,0,0,0,0,0,0,0,0)';$S;
    'VSS_AG70':'(0,0,0,0,0,0,0,0,0,0,0,0,0,0,0,0,0,0,0,0,0,0,0,0,0,0,0,0,0,0,AG7~
0,0,0,0,0,0,0,0,0,0)';$S;
    'VSS_AG72':'(0,0,0,0,0,0,0,0,0,0,0,0,0,0,0,0,0,0,0,0,0,0,0,0,0,0,0,0,0,0,AG7~
2,0,0,0,0,0,0,0,0,0)';$S;
    'VSS_AG75':'(0,0,0,0,0,0,0,0,0,0,0,0,0,0,0,0,0,0,0,0,0,0,0,0,0,0,0,0,0,0,AG7~
5,0,0,0,0,0,0,0,0,0)';$S;
    'VSS_AH3':'(0,0,0,0,0,0,0,0,0,0,0,0,0,0,0,0,0,0,0,0,0,0,0,0,0,0,0,0,0,0,AH3,~
0,0,0,0,0,0,0,0,0)';$S;
    'VSS_AH5':'(0,0,0,0,0,0,0,0,0,0,0,0,0,0,0,0,0,0,0,0,0,0,0,0,0,0,0,0,0,0,AH5,~
0,0,0,0,0,0,0,0,0)';$S;
    'VSS_AH8':'(0,0,0,0,0,0,0,0,0,0,0,0,0,0,0,0,0,0,0,0,0,0,0,0,0,0,0,0,0,0,AH8,~
0,0,0,0,0,0,0,0,0)';$S;
    'VSS_AH10':'(0,0,0,0,0,0,0,0,0,0,0,0,0,0,0,0,0,0,0,0,0,0,0,0,0,0,0,0,0,0,AH1~
0,0,0,0,0,0,0,0,0,0)';$S;
    'VSS_AH12':'(0,0,0,0,0,0,0,0,0,0,0,0,0,0,0,0,0,0,0,0,0,0,0,0,0,0,0,0,0,0,AH1~
2,0,0,0,0,0,0,0,0,0)';$S;
    'VSS_AH15':'(0,0,0,0,0,0,0,0,0,0,0,0,0,0,0,0,0,0,0,0,0,0,0,0,0,0,0,0,0,0,AH1~
5,0,0,0,0,0,0,0,0,0)';$S;
    'VSS_AH17':'(0,0,0,0,0,0,0,0,0,0,0,0,0,0,0,0,0,0,0,0,0,0,0,0,0,0,0,0,0,0,AH1~
7,0,0,0,0,0,0,0,0,0)';$S;
    'VSS_AH19':'(0,0,0,0,0,0,0,0,0,0,0,0,0,0,0,0,0,0,0,0,0,0,0,0,0,0,0,0,0,0,AH1~
9,0,0,0,0,0,0,0,0,0)';$S;
    'VSS_AH23':'(0,0,0,0,0,0,0,0,0,0,0,0,0,0,0,0,0,0,0,0,0,0,0,0,0,0,0,0,0,0,AH2~
3,0,0,0,0,0,0,0,0,0)';$S;
    'VSS_AH24':'(0,0,0,0,0,0,0,0,0,0,0,0,0,0,0,0,0,0,0,0,0,0,0,0,0,0,0,0,0,0,AH2~
4,0,0,0,0,0,0,0,0,0)';$S;
    'VSS_AH25':'(0,0,0,0,0,0,0,0,0,0,0,0,0,0,0,0,0,0,0,0,0,0,0,0,0,0,0,0,0,0,AH2~
5,0,0,0,0,0,0,0,0,0)';$S;
    'VSS_AH26':'(0,0,0,0,0,0,0,0,0,0,0,0,0,0,0,0,0,0,0,0,0,0,0,0,0,0,0,0,0,0,AH2~
6,0,0,0,0,0,0,0,0,0)';$S;
    'VSS_AH27':'(0,0,0,0,0,0,0,0,0,0,0,0,0,0,0,0,0,0,0,0,0,0,0,0,0,0,0,0,0,0,AH2~
7,0,0,0,0,0,0,0,0,0)';$S;
    'VSS_AH28':'(0,0,0,0,0,0,0,0,0,0,0,0,0,0,0,0,0,0,0,0,0,0,0,0,0,0,0,0,0,0,AH2~
8,0,0,0,0,0,0,0,0,0)';$S;
    'VSS_AH29':'(0,0,0,0,0,0,0,0,0,0,0,0,0,0,0,0,0,0,0,0,0,0,0,0,0,0,0,0,0,0,AH2~
9,0,0,0,0,0,0,0,0,0)';$S;
    'VSS_AH30':'(0,0,0,0,0,0,0,0,0,0,0,0,0,0,0,0,0,0,0,0,0,0,0,0,0,0,0,0,0,0,AH3~
0,0,0,0,0,0,0,0,0,0)';$S;
    'VSS_AH31':'(0,0,0,0,0,0,0,0,0,0,0,0,0,0,0,0,0,0,0,0,0,0,0,0,0,0,0,0,0,0,AH3~
1,0,0,0,0,0,0,0,0,0)';$S;
    'VSS_AH32':'(0,0,0,0,0,0,0,0,0,0,0,0,0,0,0,0,0,0,0,0,0,0,0,0,0,0,0,0,0,0,AH3~
2,0,0,0,0,0,0,0,0,0)';$S;
    'VSS_AH34':'(0,0,0,0,0,0,0,0,0,0,0,0,0,0,0,0,0,0,0,0,0,0,0,0,0,0,0,0,0,0,AH3~
4,0,0,0,0,0,0,0,0,0)';$S;
    'VSS_AH37':'(0,0,0,0,0,0,0,0,0,0,0,0,0,0,0,0,0,0,0,0,0,0,0,0,0,0,0,0,0,0,AH3~
7,0,0,0,0,0,0,0,0,0)';$S;
    'VSS_AH39':'(0,0,0,0,0,0,0,0,0,0,0,0,0,0,0,0,0,0,0,0,0,0,0,0,0,0,0,0,0,0,AH3~
9,0,0,0,0,0,0,0,0,0)';$S;
    'VSS_AH42':'(0,0,0,0,0,0,0,0,0,0,0,0,0,0,0,0,0,0,0,0,0,0,0,0,0,0,0,0,0,0,AH4~
2,0,0,0,0,0,0,0,0,0)';$S;
    'VSS_AH43':'(0,0,0,0,0,0,0,0,0,0,0,0,0,0,0,0,0,0,0,0,0,0,0,0,0,0,0,0,0,0,AH4~
3,0,0,0,0,0,0,0,0,0)';$S;
    'VSS_AH44':'(0,0,0,0,0,0,0,0,0,0,0,0,0,0,0,0,0,0,0,0,0,0,0,0,0,0,0,0,0,0,AH4~
4,0,0,0,0,0,0,0,0,0)';$S;
    'VSS_AH45':'(0,0,0,0,0,0,0,0,0,0,0,0,0,0,0,0,0,0,0,0,0,0,0,0,0,0,0,0,0,0,AH4~
5,0,0,0,0,0,0,0,0,0)';$S;
    'VSS_AH46':'(0,0,0,0,0,0,0,0,0,0,0,0,0,0,0,0,0,0,0,0,0,0,0,0,0,0,0,0,0,0,AH4~
6,0,0,0,0,0,0,0,0,0)';$S;
    'VSS_AH47':'(0,0,0,0,0,0,0,0,0,0,0,0,0,0,0,0,0,0,0,0,0,0,0,0,0,0,0,0,0,0,AH4~
7,0,0,0,0,0,0,0,0,0)';$S;
    'VSS_AH48':'(0,0,0,0,0,0,0,0,0,0,0,0,0,0,0,0,0,0,0,0,0,0,0,0,0,0,0,0,0,0,AH4~
8,0,0,0,0,0,0,0,0,0)';$S;
    'VSS_AH49':'(0,0,0,0,0,0,0,0,0,0,0,0,0,0,0,0,0,0,0,0,0,0,0,0,0,0,0,0,0,0,AH4~
9,0,0,0,0,0,0,0,0,0)';$S;
    'VSS_AH50':'(0,0,0,0,0,0,0,0,0,0,0,0,0,0,0,0,0,0,0,0,0,0,0,0,0,0,0,0,0,0,AH5~
0,0,0,0,0,0,0,0,0,0)';$S;
    'VSS_AH51':'(0,0,0,0,0,0,0,0,0,0,0,0,0,0,0,0,0,0,0,0,0,0,0,0,0,0,0,0,0,0,AH5~
1,0,0,0,0,0,0,0,0,0)';$S;
    'VSS_AH52':'(0,0,0,0,0,0,0,0,0,0,0,0,0,0,0,0,0,0,0,0,0,0,0,0,0,0,0,0,0,0,AH5~
2,0,0,0,0,0,0,0,0,0)';$S;
    'VSS_AH53':'(0,0,0,0,0,0,0,0,0,0,0,0,0,0,0,0,0,0,0,0,0,0,0,0,0,0,0,0,0,0,AH5~
3,0,0,0,0,0,0,0,0,0)';$S;
    'VSS_AH57':'(0,0,0,0,0,0,0,0,0,0,0,0,0,0,0,0,0,0,0,0,0,0,0,0,0,0,0,0,0,0,AH5~
7,0,0,0,0,0,0,0,0,0)';$S;
    'VSS_AH59':'(0,0,0,0,0,0,0,0,0,0,0,0,0,0,0,0,0,0,0,0,0,0,0,0,0,0,0,0,0,0,AH5~
9,0,0,0,0,0,0,0,0,0)';$S;
    'VSS_AH61':'(0,0,0,0,0,0,0,0,0,0,0,0,0,0,0,0,0,0,0,0,0,0,0,0,0,0,0,0,0,0,AH6~
1,0,0,0,0,0,0,0,0,0)';$S;
    'VSS_AH64':'(0,0,0,0,0,0,0,0,0,0,0,0,0,0,0,0,0,0,0,0,0,0,0,0,0,0,0,0,0,0,AH6~
4,0,0,0,0,0,0,0,0,0)';$S;
    'VSS_AH66':'(0,0,0,0,0,0,0,0,0,0,0,0,0,0,0,0,0,0,0,0,0,0,0,0,0,0,0,0,0,0,AH6~
6,0,0,0,0,0,0,0,0,0)';$S;
    'VSS_AH68':'(0,0,0,0,0,0,0,0,0,0,0,0,0,0,0,0,0,0,0,0,0,0,0,0,0,0,0,0,0,0,AH6~
8,0,0,0,0,0,0,0,0,0)';$S;
    'VSS_AH71':'(0,0,0,0,0,0,0,0,0,0,0,0,0,0,0,0,0,0,0,0,0,0,0,0,0,0,0,0,0,0,AH7~
1,0,0,0,0,0,0,0,0,0)';$S;
    'VSS_AH73':'(0,0,0,0,0,0,0,0,0,0,0,0,0,0,0,0,0,0,0,0,0,0,0,0,0,0,0,0,0,0,AH7~
3,0,0,0,0,0,0,0,0,0)';$S;
    'VSS_AJ1':'(0,0,0,0,0,0,0,0,0,0,0,0,0,0,0,0,0,0,0,0,0,0,0,0,0,0,0,0,0,0,AJ1,~
0,0,0,0,0,0,0,0,0)';$S;
    'VSS_AJ6':'(0,0,0,0,0,0,0,0,0,0,0,0,0,0,0,0,0,0,0,0,0,0,0,0,0,0,0,0,0,0,AJ6,~
0,0,0,0,0,0,0,0,0)';$S;
    'VSS_AJ8':'(0,0,0,0,0,0,0,0,0,0,0,0,0,0,0,0,0,0,0,0,0,0,0,0,0,0,0,0,0,0,AJ8,~
0,0,0,0,0,0,0,0,0)';$S;
    'VSS_AJ15':'(0,0,0,0,0,0,0,0,0,0,0,0,0,0,0,0,0,0,0,0,0,0,0,0,0,0,0,0,0,0,AJ1~
5,0,0,0,0,0,0,0,0,0)';$S;
    'VSS_AJ20':'(0,0,0,0,0,0,0,0,0,0,0,0,0,0,0,0,0,0,0,0,0,0,0,0,0,0,0,0,0,0,AJ2~
0,0,0,0,0,0,0,0,0,0)';$S;
    'VSS_AJ22':'(0,0,0,0,0,0,0,0,0,0,0,0,0,0,0,0,0,0,0,0,0,0,0,0,0,0,0,0,0,0,AJ2~
2,0,0,0,0,0,0,0,0,0)';$S;
    'VSS_AJ25':'(0,0,0,0,0,0,0,0,0,0,0,0,0,0,0,0,0,0,0,0,0,0,0,0,0,0,0,0,0,0,AJ2~
5,0,0,0,0,0,0,0,0,0)';$S;
    'VSS_AJ28':'(0,0,0,0,0,0,0,0,0,0,0,0,0,0,0,0,0,0,0,0,0,0,0,0,0,0,0,0,0,0,AJ2~
8,0,0,0,0,0,0,0,0,0)';$S;
    'VSS_AJ31':'(0,0,0,0,0,0,0,0,0,0,0,0,0,0,0,0,0,0,0,0,0,0,0,0,0,0,0,0,0,0,AJ3~
1,0,0,0,0,0,0,0,0,0)';$S;
    'VSS_AJ34':'(0,0,0,0,0,0,0,0,0,0,0,0,0,0,0,0,0,0,0,0,0,0,0,0,0,0,0,0,0,0,AJ3~
4,0,0,0,0,0,0,0,0,0)';$S;
    'VSS_AJ35':'(0,0,0,0,0,0,0,0,0,0,0,0,0,0,0,0,0,0,0,0,0,0,0,0,0,0,0,0,0,0,AJ3~
5,0,0,0,0,0,0,0,0,0)';$S;
    'VSS_AJ36':'(0,0,0,0,0,0,0,0,0,0,0,0,0,0,0,0,0,0,0,0,0,0,0,0,0,0,0,0,0,0,AJ3~
6,0,0,0,0,0,0,0,0,0)';$S;
    'VSS_AJ40':'(0,0,0,0,0,0,0,0,0,0,0,0,0,0,0,0,0,0,0,0,0,0,0,0,0,0,0,0,0,0,AJ4~
0,0,0,0,0,0,0,0,0,0)';$S;
    'VSS_AJ41':'(0,0,0,0,0,0,0,0,0,0,0,0,0,0,0,0,0,0,0,0,0,0,0,0,0,0,0,0,0,0,AJ4~
1,0,0,0,0,0,0,0,0,0)';$S;
    'VSS_AJ42':'(0,0,0,0,0,0,0,0,0,0,0,0,0,0,0,0,0,0,0,0,0,0,0,0,0,0,0,0,0,0,AJ4~
2,0,0,0,0,0,0,0,0,0)';$S;
    'VSS_AJ45':'(0,0,0,0,0,0,0,0,0,0,0,0,0,0,0,0,0,0,0,0,0,0,0,0,0,0,0,0,0,0,AJ4~
5,0,0,0,0,0,0,0,0,0)';$S;
    'VSS_AJ48':'(0,0,0,0,0,0,0,0,0,0,0,0,0,0,0,0,0,0,0,0,0,0,0,0,0,0,0,0,0,0,AJ4~
8,0,0,0,0,0,0,0,0,0)';$S;
    'VSS_AJ51':'(0,0,0,0,0,0,0,0,0,0,0,0,0,0,0,0,0,0,0,0,0,0,0,0,0,0,0,0,0,0,AJ5~
1,0,0,0,0,0,0,0,0,0)';$S;
    'VSS_AJ54':'(0,0,0,0,0,0,0,0,0,0,0,0,0,0,0,0,0,0,0,0,0,0,0,0,0,0,0,0,0,0,AJ5~
4,0,0,0,0,0,0,0,0,0)';$S;
    'VSS_AJ56':'(0,0,0,0,0,0,0,0,0,0,0,0,0,0,0,0,0,0,0,0,0,0,0,0,0,0,0,0,0,0,AJ5~
6,0,0,0,0,0,0,0,0,0)';$S;
    'VSS_AJ61':'(0,0,0,0,0,0,0,0,0,0,0,0,0,0,0,0,0,0,0,0,0,0,0,0,0,0,0,0,0,0,AJ6~
1,0,0,0,0,0,0,0,0,0)';$S;
    'VSS_AJ63':'(0,0,0,0,0,0,0,0,0,0,0,0,0,0,0,0,0,0,0,0,0,0,0,0,0,0,0,0,0,0,AJ6~
3,0,0,0,0,0,0,0,0,0)';$S;
    'VSS_AJ68':'(0,0,0,0,0,0,0,0,0,0,0,0,0,0,0,0,0,0,0,0,0,0,0,0,0,0,0,0,0,0,AJ6~
8,0,0,0,0,0,0,0,0,0)';$S;
    'VSS_AJ70':'(0,0,0,0,0,0,0,0,0,0,0,0,0,0,0,0,0,0,0,0,0,0,0,0,0,0,0,0,0,0,AJ7~
0,0,0,0,0,0,0,0,0,0)';$S;
    'VSS_AJ75':'(0,0,0,0,0,0,0,0,0,0,0,0,0,0,0,0,0,0,0,0,0,0,0,0,0,0,0,0,0,0,AJ7~
5,0,0,0,0,0,0,0,0,0)';$S;
    'VSS_AK3':'(0,0,0,0,0,0,0,0,0,0,0,0,0,0,0,0,0,0,0,0,0,0,0,0,0,0,0,0,0,0,AK3,~
0,0,0,0,0,0,0,0,0)';$S;
    'VSS_AK5':'(0,0,0,0,0,0,0,0,0,0,0,0,0,0,0,0,0,0,0,0,0,0,0,0,0,0,0,0,0,0,AK5,~
0,0,0,0,0,0,0,0,0)';$S;
    'VSS_AK8':'(0,0,0,0,0,0,0,0,0,0,0,0,0,0,0,0,0,0,0,0,0,0,0,0,0,0,0,0,0,0,AK8,~
0,0,0,0,0,0,0,0,0)';$S;
    'VSS_AM42':'(0,0,0,0,0,0,0,0,0,0,0,0,0,0,0,0,0,0,0,0,0,0,0,0,0,0,0,0,0,0,0,A~
M42,0,0,0,0,0,0,0,0)';$S;
    'VSS_AM43':'(0,0,0,0,0,0,0,0,0,0,0,0,0,0,0,0,0,0,0,0,0,0,0,0,0,0,0,0,0,0,0,A~
M43,0,0,0,0,0,0,0,0)';$S;
    'VSS_AM44':'(0,0,0,0,0,0,0,0,0,0,0,0,0,0,0,0,0,0,0,0,0,0,0,0,0,0,0,0,0,0,0,A~
M44,0,0,0,0,0,0,0,0)';$S;
    'VSS_AM45':'(0,0,0,0,0,0,0,0,0,0,0,0,0,0,0,0,0,0,0,0,0,0,0,0,0,0,0,0,0,0,0,A~
M45,0,0,0,0,0,0,0,0)';$S;
    'VSS_AM46':'(0,0,0,0,0,0,0,0,0,0,0,0,0,0,0,0,0,0,0,0,0,0,0,0,0,0,0,0,0,0,0,A~
M46,0,0,0,0,0,0,0,0)';$S;
    'VSS_AM47':'(0,0,0,0,0,0,0,0,0,0,0,0,0,0,0,0,0,0,0,0,0,0,0,0,0,0,0,0,0,0,0,A~
M47,0,0,0,0,0,0,0,0)';$S;
    'VSS_AM48':'(0,0,0,0,0,0,0,0,0,0,0,0,0,0,0,0,0,0,0,0,0,0,0,0,0,0,0,0,0,0,0,A~
M48,0,0,0,0,0,0,0,0)';$S;
    'VSS_AM49':'(0,0,0,0,0,0,0,0,0,0,0,0,0,0,0,0,0,0,0,0,0,0,0,0,0,0,0,0,0,0,0,A~
M49,0,0,0,0,0,0,0,0)';$S;
    'VSS_AM50':'(0,0,0,0,0,0,0,0,0,0,0,0,0,0,0,0,0,0,0,0,0,0,0,0,0,0,0,0,0,0,0,A~
M50,0,0,0,0,0,0,0,0)';$S;
    'VSS_AM51':'(0,0,0,0,0,0,0,0,0,0,0,0,0,0,0,0,0,0,0,0,0,0,0,0,0,0,0,0,0,0,0,A~
M51,0,0,0,0,0,0,0,0)';$S;
    'VSS_AM52':'(0,0,0,0,0,0,0,0,0,0,0,0,0,0,0,0,0,0,0,0,0,0,0,0,0,0,0,0,0,0,0,A~
M52,0,0,0,0,0,0,0,0)';$S;
    'VSS_AM53':'(0,0,0,0,0,0,0,0,0,0,0,0,0,0,0,0,0,0,0,0,0,0,0,0,0,0,0,0,0,0,0,A~
M53,0,0,0,0,0,0,0,0)';$S;
    'VSS_AM59':'(0,0,0,0,0,0,0,0,0,0,0,0,0,0,0,0,0,0,0,0,0,0,0,0,0,0,0,0,0,0,0,A~
M59,0,0,0,0,0,0,0,0)';$S;
    'VSS_AM61':'(0,0,0,0,0,0,0,0,0,0,0,0,0,0,0,0,0,0,0,0,0,0,0,0,0,0,0,0,0,0,0,A~
M61,0,0,0,0,0,0,0,0)';$S;
    'VSS_AM66':'(0,0,0,0,0,0,0,0,0,0,0,0,0,0,0,0,0,0,0,0,0,0,0,0,0,0,0,0,0,0,0,A~
M66,0,0,0,0,0,0,0,0)';$S;
    'VSS_AM68':'(0,0,0,0,0,0,0,0,0,0,0,0,0,0,0,0,0,0,0,0,0,0,0,0,0,0,0,0,0,0,0,A~
M68,0,0,0,0,0,0,0,0)';$S;
    'VSS_AM73':'(0,0,0,0,0,0,0,0,0,0,0,0,0,0,0,0,0,0,0,0,0,0,0,0,0,0,0,0,0,0,0,A~
M73,0,0,0,0,0,0,0,0)';$S;
    'VSS_AN1':'(0,0,0,0,0,0,0,0,0,0,0,0,0,0,0,0,0,0,0,0,0,0,0,0,0,0,0,0,0,0,0,AN~
1,0,0,0,0,0,0,0,0)';$S;
    'VSS_AN4':'(0,0,0,0,0,0,0,0,0,0,0,0,0,0,0,0,0,0,0,0,0,0,0,0,0,0,0,0,0,0,0,AN~
4,0,0,0,0,0,0,0,0)';$S;
    'VSS_AN6':'(0,0,0,0,0,0,0,0,0,0,0,0,0,0,0,0,0,0,0,0,0,0,0,0,0,0,0,0,0,0,0,AN~
6,0,0,0,0,0,0,0,0)';$S;
    'VSS_AN8':'(0,0,0,0,0,0,0,0,0,0,0,0,0,0,0,0,0,0,0,0,0,0,0,0,0,0,0,0,0,0,0,AN~
8,0,0,0,0,0,0,0,0)';$S;
    'VSS_AN11':'(0,0,0,0,0,0,0,0,0,0,0,0,0,0,0,0,0,0,0,0,0,0,0,0,0,0,0,0,0,0,0,A~
N11,0,0,0,0,0,0,0,0)';$S;
    'VSS_AN13':'(0,0,0,0,0,0,0,0,0,0,0,0,0,0,0,0,0,0,0,0,0,0,0,0,0,0,0,0,0,0,0,A~
N13,0,0,0,0,0,0,0,0)';$S;
    'VSS_AN15':'(0,0,0,0,0,0,0,0,0,0,0,0,0,0,0,0,0,0,0,0,0,0,0,0,0,0,0,0,0,0,0,A~
N15,0,0,0,0,0,0,0,0)';$S;
    'VSS_AN18':'(0,0,0,0,0,0,0,0,0,0,0,0,0,0,0,0,0,0,0,0,0,0,0,0,0,0,0,0,0,0,0,A~
N18,0,0,0,0,0,0,0,0)';$S;
    'VSS_AN22':'(0,0,0,0,0,0,0,0,0,0,0,0,0,0,0,0,0,0,0,0,0,0,0,0,0,0,0,0,0,0,0,A~
N22,0,0,0,0,0,0,0,0)';$S;
    'VSS_AN25':'(0,0,0,0,0,0,0,0,0,0,0,0,0,0,0,0,0,0,0,0,0,0,0,0,0,0,0,0,0,0,0,A~
N25,0,0,0,0,0,0,0,0)';$S;
    'VSS_AN28':'(0,0,0,0,0,0,0,0,0,0,0,0,0,0,0,0,0,0,0,0,0,0,0,0,0,0,0,0,0,0,0,A~
N28,0,0,0,0,0,0,0,0)';$S;
    'VSS_AN31':'(0,0,0,0,0,0,0,0,0,0,0,0,0,0,0,0,0,0,0,0,0,0,0,0,0,0,0,0,0,0,0,A~
N31,0,0,0,0,0,0,0,0)';$S;
    'VSS_AN34':'(0,0,0,0,0,0,0,0,0,0,0,0,0,0,0,0,0,0,0,0,0,0,0,0,0,0,0,0,0,0,0,A~
N34,0,0,0,0,0,0,0,0)';$S;
    'VSS_AN35':'(0,0,0,0,0,0,0,0,0,0,0,0,0,0,0,0,0,0,0,0,0,0,0,0,0,0,0,0,0,0,0,A~
N35,0,0,0,0,0,0,0,0)';$S;
    'VSS_AN36':'(0,0,0,0,0,0,0,0,0,0,0,0,0,0,0,0,0,0,0,0,0,0,0,0,0,0,0,0,0,0,0,A~
N36,0,0,0,0,0,0,0,0)';$S;
    'VSS_AN40':'(0,0,0,0,0,0,0,0,0,0,0,0,0,0,0,0,0,0,0,0,0,0,0,0,0,0,0,0,0,0,0,A~
N40,0,0,0,0,0,0,0,0)';$S;
    'VSS_AN41':'(0,0,0,0,0,0,0,0,0,0,0,0,0,0,0,0,0,0,0,0,0,0,0,0,0,0,0,0,0,0,0,A~
N41,0,0,0,0,0,0,0,0)';$S;
    'VSS_AN42':'(0,0,0,0,0,0,0,0,0,0,0,0,0,0,0,0,0,0,0,0,0,0,0,0,0,0,0,0,0,0,0,A~
N42,0,0,0,0,0,0,0,0)';$S;
    'VSS_AN45':'(0,0,0,0,0,0,0,0,0,0,0,0,0,0,0,0,0,0,0,0,0,0,0,0,0,0,0,0,0,0,0,A~
N45,0,0,0,0,0,0,0,0)';$S;
    'VSS_AN48':'(0,0,0,0,0,0,0,0,0,0,0,0,0,0,0,0,0,0,0,0,0,0,0,0,0,0,0,0,0,0,0,A~
N48,0,0,0,0,0,0,0,0)';$S;
    'VSS_AN51':'(0,0,0,0,0,0,0,0,0,0,0,0,0,0,0,0,0,0,0,0,0,0,0,0,0,0,0,0,0,0,0,A~
N51,0,0,0,0,0,0,0,0)';$S;
    'VSS_AN54':'(0,0,0,0,0,0,0,0,0,0,0,0,0,0,0,0,0,0,0,0,0,0,0,0,0,0,0,0,0,0,0,A~
N54,0,0,0,0,0,0,0,0)';$S;
    'VSS_AN56':'(0,0,0,0,0,0,0,0,0,0,0,0,0,0,0,0,0,0,0,0,0,0,0,0,0,0,0,0,0,0,0,A~
N56,0,0,0,0,0,0,0,0)';$S;
    'VSS_AN58':'(0,0,0,0,0,0,0,0,0,0,0,0,0,0,0,0,0,0,0,0,0,0,0,0,0,0,0,0,0,0,0,A~
N58,0,0,0,0,0,0,0,0)';$S;
    'VSS_AN61':'(0,0,0,0,0,0,0,0,0,0,0,0,0,0,0,0,0,0,0,0,0,0,0,0,0,0,0,0,0,0,0,A~
N61,0,0,0,0,0,0,0,0)';$S;
    'VSS_AN63':'(0,0,0,0,0,0,0,0,0,0,0,0,0,0,0,0,0,0,0,0,0,0,0,0,0,0,0,0,0,0,0,A~
N63,0,0,0,0,0,0,0,0)';$S;
    'VSS_AN65':'(0,0,0,0,0,0,0,0,0,0,0,0,0,0,0,0,0,0,0,0,0,0,0,0,0,0,0,0,0,0,0,A~
N65,0,0,0,0,0,0,0,0)';$S;
    'VSS_AN68':'(0,0,0,0,0,0,0,0,0,0,0,0,0,0,0,0,0,0,0,0,0,0,0,0,0,0,0,0,0,0,0,A~
N68,0,0,0,0,0,0,0,0)';$S;
    'VSS_AN70':'(0,0,0,0,0,0,0,0,0,0,0,0,0,0,0,0,0,0,0,0,0,0,0,0,0,0,0,0,0,0,0,A~
N70,0,0,0,0,0,0,0,0)';$S;
    'VSS_AN72':'(0,0,0,0,0,0,0,0,0,0,0,0,0,0,0,0,0,0,0,0,0,0,0,0,0,0,0,0,0,0,0,A~
N72,0,0,0,0,0,0,0,0)';$S;
    'VSS_AN75':'(0,0,0,0,0,0,0,0,0,0,0,0,0,0,0,0,0,0,0,0,0,0,0,0,0,0,0,0,0,0,0,A~
N75,0,0,0,0,0,0,0,0)';$S;
    'VSS_AP3':'(0,0,0,0,0,0,0,0,0,0,0,0,0,0,0,0,0,0,0,0,0,0,0,0,0,0,0,0,0,0,0,AP~
3,0,0,0,0,0,0,0,0)';$S;
    'VSS_AP5':'(0,0,0,0,0,0,0,0,0,0,0,0,0,0,0,0,0,0,0,0,0,0,0,0,0,0,0,0,0,0,0,AP~
5,0,0,0,0,0,0,0,0)';$S;
    'VSS_AP8':'(0,0,0,0,0,0,0,0,0,0,0,0,0,0,0,0,0,0,0,0,0,0,0,0,0,0,0,0,0,0,0,AP~
8,0,0,0,0,0,0,0,0)';$S;
    'VSS_AP10':'(0,0,0,0,0,0,0,0,0,0,0,0,0,0,0,0,0,0,0,0,0,0,0,0,0,0,0,0,0,0,0,A~
P10,0,0,0,0,0,0,0,0)';$S;
    'VSS_AP12':'(0,0,0,0,0,0,0,0,0,0,0,0,0,0,0,0,0,0,0,0,0,0,0,0,0,0,0,0,0,0,0,A~
P12,0,0,0,0,0,0,0,0)';$S;
    'VSS_AP15':'(0,0,0,0,0,0,0,0,0,0,0,0,0,0,0,0,0,0,0,0,0,0,0,0,0,0,0,0,0,0,0,A~
P15,0,0,0,0,0,0,0,0)';$S;
    'VSS_AP17':'(0,0,0,0,0,0,0,0,0,0,0,0,0,0,0,0,0,0,0,0,0,0,0,0,0,0,0,0,0,0,0,A~
P17,0,0,0,0,0,0,0,0)';$S;
    'VSS_AP19':'(0,0,0,0,0,0,0,0,0,0,0,0,0,0,0,0,0,0,0,0,0,0,0,0,0,0,0,0,0,0,0,A~
P19,0,0,0,0,0,0,0,0)';$S;
    'VSS_AP22':'(0,0,0,0,0,0,0,0,0,0,0,0,0,0,0,0,0,0,0,0,0,0,0,0,0,0,0,0,0,0,0,A~
P22,0,0,0,0,0,0,0,0)';$S;
    'VSS_AP25':'(0,0,0,0,0,0,0,0,0,0,0,0,0,0,0,0,0,0,0,0,0,0,0,0,0,0,0,0,0,0,0,A~
P25,0,0,0,0,0,0,0,0)';$S;
    'VSS_AP28':'(0,0,0,0,0,0,0,0,0,0,0,0,0,0,0,0,0,0,0,0,0,0,0,0,0,0,0,0,0,0,0,A~
P28,0,0,0,0,0,0,0,0)';$S;
    'VSS_AP31':'(0,0,0,0,0,0,0,0,0,0,0,0,0,0,0,0,0,0,0,0,0,0,0,0,0,0,0,0,0,0,0,A~
P31,0,0,0,0,0,0,0,0)';$S;
    'VSS_AP34':'(0,0,0,0,0,0,0,0,0,0,0,0,0,0,0,0,0,0,0,0,0,0,0,0,0,0,0,0,0,0,0,A~
P34,0,0,0,0,0,0,0,0)';$S;
    'VSS_AP37':'(0,0,0,0,0,0,0,0,0,0,0,0,0,0,0,0,0,0,0,0,0,0,0,0,0,0,0,0,0,0,0,A~
P37,0,0,0,0,0,0,0,0)';$S;
    'VSS_AP39':'(0,0,0,0,0,0,0,0,0,0,0,0,0,0,0,0,0,0,0,0,0,0,0,0,0,0,0,0,0,0,0,A~
P39,0,0,0,0,0,0,0,0)';$S;
    'VSS_AP42':'(0,0,0,0,0,0,0,0,0,0,0,0,0,0,0,0,0,0,0,0,0,0,0,0,0,0,0,0,0,0,0,A~
P42,0,0,0,0,0,0,0,0)';$S;
    'VSS_AP45':'(0,0,0,0,0,0,0,0,0,0,0,0,0,0,0,0,0,0,0,0,0,0,0,0,0,0,0,0,0,0,0,A~
P45,0,0,0,0,0,0,0,0)';$S;
    'VSS_AP48':'(0,0,0,0,0,0,0,0,0,0,0,0,0,0,0,0,0,0,0,0,0,0,0,0,0,0,0,0,0,0,0,A~
P48,0,0,0,0,0,0,0,0)';$S;
    'VSS_AP51':'(0,0,0,0,0,0,0,0,0,0,0,0,0,0,0,0,0,0,0,0,0,0,0,0,0,0,0,0,0,0,0,A~
P51,0,0,0,0,0,0,0,0)';$S;
    'VSS_AP54':'(0,0,0,0,0,0,0,0,0,0,0,0,0,0,0,0,0,0,0,0,0,0,0,0,0,0,0,0,0,0,0,A~
P54,0,0,0,0,0,0,0,0)';$S;
    'VSS_AP57':'(0,0,0,0,0,0,0,0,0,0,0,0,0,0,0,0,0,0,0,0,0,0,0,0,0,0,0,0,0,0,0,A~
P57,0,0,0,0,0,0,0,0)';$S;
    'VSS_AP59':'(0,0,0,0,0,0,0,0,0,0,0,0,0,0,0,0,0,0,0,0,0,0,0,0,0,0,0,0,0,0,0,A~
P59,0,0,0,0,0,0,0,0)';$S;
    'VSS_AP61':'(0,0,0,0,0,0,0,0,0,0,0,0,0,0,0,0,0,0,0,0,0,0,0,0,0,0,0,0,0,0,0,A~
P61,0,0,0,0,0,0,0,0)';$S;
    'VSS_AP64':'(0,0,0,0,0,0,0,0,0,0,0,0,0,0,0,0,0,0,0,0,0,0,0,0,0,0,0,0,0,0,0,A~
P64,0,0,0,0,0,0,0,0)';$S;
    'VSS_AP66':'(0,0,0,0,0,0,0,0,0,0,0,0,0,0,0,0,0,0,0,0,0,0,0,0,0,0,0,0,0,0,0,A~
P66,0,0,0,0,0,0,0,0)';$S;
    'VSS_AP68':'(0,0,0,0,0,0,0,0,0,0,0,0,0,0,0,0,0,0,0,0,0,0,0,0,0,0,0,0,0,0,0,A~
P68,0,0,0,0,0,0,0,0)';$S;
    'VSS_AP71':'(0,0,0,0,0,0,0,0,0,0,0,0,0,0,0,0,0,0,0,0,0,0,0,0,0,0,0,0,0,0,0,A~
P71,0,0,0,0,0,0,0,0)';$S;
    'VSS_AP73':'(0,0,0,0,0,0,0,0,0,0,0,0,0,0,0,0,0,0,0,0,0,0,0,0,0,0,0,0,0,0,0,A~
P73,0,0,0,0,0,0,0,0)';$S;
    'VSS_AR1':'(0,0,0,0,0,0,0,0,0,0,0,0,0,0,0,0,0,0,0,0,0,0,0,0,0,0,0,0,0,0,0,AR~
1,0,0,0,0,0,0,0,0)';$S;
    'VSS_AR5':'(0,0,0,0,0,0,0,0,0,0,0,0,0,0,0,0,0,0,0,0,0,0,0,0,0,0,0,0,0,0,0,AR~
5,0,0,0,0,0,0,0,0)';$S;
    'VSS_AR6':'(0,0,0,0,0,0,0,0,0,0,0,0,0,0,0,0,0,0,0,0,0,0,0,0,0,0,0,0,0,0,0,AR~
6,0,0,0,0,0,0,0,0)';$S;
    'VSS_AR8':'(0,0,0,0,0,0,0,0,0,0,0,0,0,0,0,0,0,0,0,0,0,0,0,0,0,0,0,0,0,0,0,AR~
8,0,0,0,0,0,0,0,0)';$S;
    'VSS_AR9':'(0,0,0,0,0,0,0,0,0,0,0,0,0,0,0,0,0,0,0,0,0,0,0,0,0,0,0,0,0,0,0,AR~
9,0,0,0,0,0,0,0,0)';$S;
    'VSS_AR12':'(0,0,0,0,0,0,0,0,0,0,0,0,0,0,0,0,0,0,0,0,0,0,0,0,0,0,0,0,0,0,0,A~
R12,0,0,0,0,0,0,0,0)';$S;
    'VSS_AR13':'(0,0,0,0,0,0,0,0,0,0,0,0,0,0,0,0,0,0,0,0,0,0,0,0,0,0,0,0,0,0,0,A~
R13,0,0,0,0,0,0,0,0)';$S;
    'VSS_AR15':'(0,0,0,0,0,0,0,0,0,0,0,0,0,0,0,0,0,0,0,0,0,0,0,0,0,0,0,0,0,0,0,A~
R15,0,0,0,0,0,0,0,0)';$S;
    'VSS_AR16':'(0,0,0,0,0,0,0,0,0,0,0,0,0,0,0,0,0,0,0,0,0,0,0,0,0,0,0,0,0,0,0,A~
R16,0,0,0,0,0,0,0,0)';$S;
    'VSS_AR19':'(0,0,0,0,0,0,0,0,0,0,0,0,0,0,0,0,0,0,0,0,0,0,0,0,0,0,0,0,0,0,0,A~
R19,0,0,0,0,0,0,0,0)';$S;
    'VSS_AR20':'(0,0,0,0,0,0,0,0,0,0,0,0,0,0,0,0,0,0,0,0,0,0,0,0,0,0,0,0,0,0,0,A~
R20,0,0,0,0,0,0,0,0)';$S;
    'VSS_AR22':'(0,0,0,0,0,0,0,0,0,0,0,0,0,0,0,0,0,0,0,0,0,0,0,0,0,0,0,0,0,0,0,A~
R22,0,0,0,0,0,0,0,0)';$S;
    'VSS_AR24':'(0,0,0,0,0,0,0,0,0,0,0,0,0,0,0,0,0,0,0,0,0,0,0,0,0,0,0,0,0,0,0,A~
R24,0,0,0,0,0,0,0,0)';$S;
    'VSS_AR26':'(0,0,0,0,0,0,0,0,0,0,0,0,0,0,0,0,0,0,0,0,0,0,0,0,0,0,0,0,0,0,0,A~
R26,0,0,0,0,0,0,0,0)';$S;
    'VSS_AR28':'(0,0,0,0,0,0,0,0,0,0,0,0,0,0,0,0,0,0,0,0,0,0,0,0,0,0,0,0,0,0,0,A~
R28,0,0,0,0,0,0,0,0)';$S;
    'VSS_AR30':'(0,0,0,0,0,0,0,0,0,0,0,0,0,0,0,0,0,0,0,0,0,0,0,0,0,0,0,0,0,0,0,A~
R30,0,0,0,0,0,0,0,0)';$S;
    'VSS_AR32':'(0,0,0,0,0,0,0,0,0,0,0,0,0,0,0,0,0,0,0,0,0,0,0,0,0,0,0,0,0,0,0,A~
R32,0,0,0,0,0,0,0,0)';$S;
    'VSS_AR34':'(0,0,0,0,0,0,0,0,0,0,0,0,0,0,0,0,0,0,0,0,0,0,0,0,0,0,0,0,0,0,0,A~
R34,0,0,0,0,0,0,0,0)';$S;
    'VSS_AR36':'(0,0,0,0,0,0,0,0,0,0,0,0,0,0,0,0,0,0,0,0,0,0,0,0,0,0,0,0,0,0,0,A~
R36,0,0,0,0,0,0,0,0)';$S;
    'VSS_AR41':'(0,0,0,0,0,0,0,0,0,0,0,0,0,0,0,0,0,0,0,0,0,0,0,0,0,0,0,0,0,0,0,A~
R41,0,0,0,0,0,0,0,0)';$S;
    'VSS_AR43':'(0,0,0,0,0,0,0,0,0,0,0,0,0,0,0,0,0,0,0,0,0,0,0,0,0,0,0,0,0,0,0,A~
R43,0,0,0,0,0,0,0,0)';$S;
    'VSS_AR45':'(0,0,0,0,0,0,0,0,0,0,0,0,0,0,0,0,0,0,0,0,0,0,0,0,0,0,0,0,0,0,0,A~
R45,0,0,0,0,0,0,0,0)';$S;
    'VSS_AR47':'(0,0,0,0,0,0,0,0,0,0,0,0,0,0,0,0,0,0,0,0,0,0,0,0,0,0,0,0,0,0,0,A~
R47,0,0,0,0,0,0,0,0)';$S;
    'VSS_AR49':'(0,0,0,0,0,0,0,0,0,0,0,0,0,0,0,0,0,0,0,0,0,0,0,0,0,0,0,0,0,0,0,A~
R49,0,0,0,0,0,0,0,0)';$S;
    'VSS_AR51':'(0,0,0,0,0,0,0,0,0,0,0,0,0,0,0,0,0,0,0,0,0,0,0,0,0,0,0,0,0,0,0,A~
R51,0,0,0,0,0,0,0,0)';$S;
    'VSS_AR53':'(0,0,0,0,0,0,0,0,0,0,0,0,0,0,0,0,0,0,0,0,0,0,0,0,0,0,0,0,0,0,0,A~
R53,0,0,0,0,0,0,0,0)';$S;
    'VSS_AR56':'(0,0,0,0,0,0,0,0,0,0,0,0,0,0,0,0,0,0,0,0,0,0,0,0,0,0,0,0,0,0,0,A~
R56,0,0,0,0,0,0,0,0)';$S;
    'VSS_AR57':'(0,0,0,0,0,0,0,0,0,0,0,0,0,0,0,0,0,0,0,0,0,0,0,0,0,0,0,0,0,0,0,A~
R57,0,0,0,0,0,0,0,0)';$S;
    'VSS_AR60':'(0,0,0,0,0,0,0,0,0,0,0,0,0,0,0,0,0,0,0,0,0,0,0,0,0,0,0,0,0,0,0,A~
R60,0,0,0,0,0,0,0,0)';$S;
    'VSS_AR61':'(0,0,0,0,0,0,0,0,0,0,0,0,0,0,0,0,0,0,0,0,0,0,0,0,0,0,0,0,0,0,0,A~
R61,0,0,0,0,0,0,0,0)';$S;
    'VSS_AR63':'(0,0,0,0,0,0,0,0,0,0,0,0,0,0,0,0,0,0,0,0,0,0,0,0,0,0,0,0,0,0,0,A~
R63,0,0,0,0,0,0,0,0)';$S;
    'VSS_AR64':'(0,0,0,0,0,0,0,0,0,0,0,0,0,0,0,0,0,0,0,0,0,0,0,0,0,0,0,0,0,0,0,A~
R64,0,0,0,0,0,0,0,0)';$S;
    'VSS_AR67':'(0,0,0,0,0,0,0,0,0,0,0,0,0,0,0,0,0,0,0,0,0,0,0,0,0,0,0,0,0,0,0,A~
R67,0,0,0,0,0,0,0,0)';$S;
    'VSS_AR68':'(0,0,0,0,0,0,0,0,0,0,0,0,0,0,0,0,0,0,0,0,0,0,0,0,0,0,0,0,0,0,0,A~
R68,0,0,0,0,0,0,0,0)';$S;
    'VSS_AR70':'(0,0,0,0,0,0,0,0,0,0,0,0,0,0,0,0,0,0,0,0,0,0,0,0,0,0,0,0,0,0,0,A~
R70,0,0,0,0,0,0,0,0)';$S;
    'VSS_AR71':'(0,0,0,0,0,0,0,0,0,0,0,0,0,0,0,0,0,0,0,0,0,0,0,0,0,0,0,0,0,0,0,A~
R71,0,0,0,0,0,0,0,0)';$S;
    'VSS_AR75':'(0,0,0,0,0,0,0,0,0,0,0,0,0,0,0,0,0,0,0,0,0,0,0,0,0,0,0,0,0,0,0,A~
R75,0,0,0,0,0,0,0,0)';$S;
    'VSS_AT3':'(0,0,0,0,0,0,0,0,0,0,0,0,0,0,0,0,0,0,0,0,0,0,0,0,0,0,0,0,0,0,0,AT~
3,0,0,0,0,0,0,0,0)';$S;
    'VSS_AT4':'(0,0,0,0,0,0,0,0,0,0,0,0,0,0,0,0,0,0,0,0,0,0,0,0,0,0,0,0,0,0,0,AT~
4,0,0,0,0,0,0,0,0)';$S;
    'VSS_AT5':'(0,0,0,0,0,0,0,0,0,0,0,0,0,0,0,0,0,0,0,0,0,0,0,0,0,0,0,0,0,0,0,AT~
5,0,0,0,0,0,0,0,0)';$S;
    'VSS_AT6':'(0,0,0,0,0,0,0,0,0,0,0,0,0,0,0,0,0,0,0,0,0,0,0,0,0,0,0,0,0,0,0,AT~
6,0,0,0,0,0,0,0,0)';$S;
    'VSS_AT8':'(0,0,0,0,0,0,0,0,0,0,0,0,0,0,0,0,0,0,0,0,0,0,0,0,0,0,0,0,0,0,0,AT~
8,0,0,0,0,0,0,0,0)';$S;
    'VSS_AT9':'(0,0,0,0,0,0,0,0,0,0,0,0,0,0,0,0,0,0,0,0,0,0,0,0,0,0,0,0,0,0,0,AT~
9,0,0,0,0,0,0,0,0)';$S;
    'VSS_AT10':'(0,0,0,0,0,0,0,0,0,0,0,0,0,0,0,0,0,0,0,0,0,0,0,0,0,0,0,0,0,0,0,A~
T10,0,0,0,0,0,0,0,0)';$S;
    'VSS_AT12':'(0,0,0,0,0,0,0,0,0,0,0,0,0,0,0,0,0,0,0,0,0,0,0,0,0,0,0,0,0,0,0,A~
T12,0,0,0,0,0,0,0,0)';$S;
    'VSS_AT13':'(0,0,0,0,0,0,0,0,0,0,0,0,0,0,0,0,0,0,0,0,0,0,0,0,0,0,0,0,0,0,0,A~
T13,0,0,0,0,0,0,0,0)';$S;
    'VSS_AT15':'(0,0,0,0,0,0,0,0,0,0,0,0,0,0,0,0,0,0,0,0,0,0,0,0,0,0,0,0,0,0,0,A~
T15,0,0,0,0,0,0,0,0)';$S;
    'VSS_AT16':'(0,0,0,0,0,0,0,0,0,0,0,0,0,0,0,0,0,0,0,0,0,0,0,0,0,0,0,0,0,0,0,A~
T16,0,0,0,0,0,0,0,0)';$S;
    'VSS_AT17':'(0,0,0,0,0,0,0,0,0,0,0,0,0,0,0,0,0,0,0,0,0,0,0,0,0,0,0,0,0,0,0,A~
T17,0,0,0,0,0,0,0,0)';$S;
    'VSS_AT19':'(0,0,0,0,0,0,0,0,0,0,0,0,0,0,0,0,0,0,0,0,0,0,0,0,0,0,0,0,0,0,0,A~
T19,0,0,0,0,0,0,0,0)';$S;
    'VSS_AT20':'(0,0,0,0,0,0,0,0,0,0,0,0,0,0,0,0,0,0,0,0,0,0,0,0,0,0,0,0,0,0,0,A~
T20,0,0,0,0,0,0,0,0)';$S;
    'VSS_AT23':'(0,0,0,0,0,0,0,0,0,0,0,0,0,0,0,0,0,0,0,0,0,0,0,0,0,0,0,0,0,0,0,A~
T23,0,0,0,0,0,0,0,0)';$S;
    'VSS_AT25':'(0,0,0,0,0,0,0,0,0,0,0,0,0,0,0,0,0,0,0,0,0,0,0,0,0,0,0,0,0,0,0,A~
T25,0,0,0,0,0,0,0,0)';$S;
    'VSS_AT27':'(0,0,0,0,0,0,0,0,0,0,0,0,0,0,0,0,0,0,0,0,0,0,0,0,0,0,0,0,0,0,0,A~
T27,0,0,0,0,0,0,0,0)';$S;
    'VSS_AT29':'(0,0,0,0,0,0,0,0,0,0,0,0,0,0,0,0,0,0,0,0,0,0,0,0,0,0,0,0,0,0,0,A~
T29,0,0,0,0,0,0,0,0)';$S;
    'VSS_AT31':'(0,0,0,0,0,0,0,0,0,0,0,0,0,0,0,0,0,0,0,0,0,0,0,0,0,0,0,0,0,0,0,A~
T31,0,0,0,0,0,0,0,0)';$S;
    'VSS_AT33':'(0,0,0,0,0,0,0,0,0,0,0,0,0,0,0,0,0,0,0,0,0,0,0,0,0,0,0,0,0,0,0,A~
T33,0,0,0,0,0,0,0,0)';$S;
    'VSS_AT35':'(0,0,0,0,0,0,0,0,0,0,0,0,0,0,0,0,0,0,0,0,0,0,0,0,0,0,0,0,0,0,0,A~
T35,0,0,0,0,0,0,0,0)';$S;
    'VSS_AT37':'(0,0,0,0,0,0,0,0,0,0,0,0,0,0,0,0,0,0,0,0,0,0,0,0,0,0,0,0,0,0,0,A~
T37,0,0,0,0,0,0,0,0)';$S;
    'VSS_AT40':'(0,0,0,0,0,0,0,0,0,0,0,0,0,0,0,0,0,0,0,0,0,0,0,0,0,0,0,0,0,0,0,A~
T40,0,0,0,0,0,0,0,0)';$S;
    'VSS_AT42':'(0,0,0,0,0,0,0,0,0,0,0,0,0,0,0,0,0,0,0,0,0,0,0,0,0,0,0,0,0,0,0,A~
T42,0,0,0,0,0,0,0,0)';$S;
    'VSS_AT44':'(0,0,0,0,0,0,0,0,0,0,0,0,0,0,0,0,0,0,0,0,0,0,0,0,0,0,0,0,0,0,0,A~
T44,0,0,0,0,0,0,0,0)';$S;
    'VSS_AT46':'(0,0,0,0,0,0,0,0,0,0,0,0,0,0,0,0,0,0,0,0,0,0,0,0,0,0,0,0,0,0,0,A~
T46,0,0,0,0,0,0,0,0)';$S;
    'VSS_AT48':'(0,0,0,0,0,0,0,0,0,0,0,0,0,0,0,0,0,0,0,0,0,0,0,0,0,0,0,0,0,0,0,A~
T48,0,0,0,0,0,0,0,0)';$S;
    'VSS_AT50':'(0,0,0,0,0,0,0,0,0,0,0,0,0,0,0,0,0,0,0,0,0,0,0,0,0,0,0,0,0,0,0,A~
T50,0,0,0,0,0,0,0,0)';$S;
    'VSS_AT52':'(0,0,0,0,0,0,0,0,0,0,0,0,0,0,0,0,0,0,0,0,0,0,0,0,0,0,0,0,0,0,0,A~
T52,0,0,0,0,0,0,0,0)';$S;
    'VSS_AT54':'(0,0,0,0,0,0,0,0,0,0,0,0,0,0,0,0,0,0,0,0,0,0,0,0,0,0,0,0,0,0,0,A~
T54,0,0,0,0,0,0,0,0)';$S;
    'VSS_AT56':'(0,0,0,0,0,0,0,0,0,0,0,0,0,0,0,0,0,0,0,0,0,0,0,0,0,0,0,0,0,0,0,A~
T56,0,0,0,0,0,0,0,0)';$S;
    'VSS_AT57':'(0,0,0,0,0,0,0,0,0,0,0,0,0,0,0,0,0,0,0,0,0,0,0,0,0,0,0,0,0,0,0,A~
T57,0,0,0,0,0,0,0,0)';$S;
    'VSS_AT59':'(0,0,0,0,0,0,0,0,0,0,0,0,0,0,0,0,0,0,0,0,0,0,0,0,0,0,0,0,0,0,0,A~
T59,0,0,0,0,0,0,0,0)';$S;
    'VSS_AT60':'(0,0,0,0,0,0,0,0,0,0,0,0,0,0,0,0,0,0,0,0,0,0,0,0,0,0,0,0,0,0,0,A~
T60,0,0,0,0,0,0,0,0)';$S;
    'VSS_AT61':'(0,0,0,0,0,0,0,0,0,0,0,0,0,0,0,0,0,0,0,0,0,0,0,0,0,0,0,0,0,0,0,A~
T61,0,0,0,0,0,0,0,0)';$S;
    'VSS_AT63':'(0,0,0,0,0,0,0,0,0,0,0,0,0,0,0,0,0,0,0,0,0,0,0,0,0,0,0,0,0,0,0,A~
T63,0,0,0,0,0,0,0,0)';$S;
    'VSS_AT64':'(0,0,0,0,0,0,0,0,0,0,0,0,0,0,0,0,0,0,0,0,0,0,0,0,0,0,0,0,0,0,0,A~
T64,0,0,0,0,0,0,0,0)';$S;
    'VSS_AT66':'(0,0,0,0,0,0,0,0,0,0,0,0,0,0,0,0,0,0,0,0,0,0,0,0,0,0,0,0,0,0,0,A~
T66,0,0,0,0,0,0,0,0)';$S;
    'VSS_AT67':'(0,0,0,0,0,0,0,0,0,0,0,0,0,0,0,0,0,0,0,0,0,0,0,0,0,0,0,0,0,0,0,A~
T67,0,0,0,0,0,0,0,0)';$S;
    'VSS_AT68':'(0,0,0,0,0,0,0,0,0,0,0,0,0,0,0,0,0,0,0,0,0,0,0,0,0,0,0,0,0,0,0,A~
T68,0,0,0,0,0,0,0,0)';$S;
    'VSS_AT70':'(0,0,0,0,0,0,0,0,0,0,0,0,0,0,0,0,0,0,0,0,0,0,0,0,0,0,0,0,0,0,0,A~
T70,0,0,0,0,0,0,0,0)';$S;
    'VSS_AT71':'(0,0,0,0,0,0,0,0,0,0,0,0,0,0,0,0,0,0,0,0,0,0,0,0,0,0,0,0,0,0,0,A~
T71,0,0,0,0,0,0,0,0)';$S;
    'VSS_AT72':'(0,0,0,0,0,0,0,0,0,0,0,0,0,0,0,0,0,0,0,0,0,0,0,0,0,0,0,0,0,0,0,A~
T72,0,0,0,0,0,0,0,0)';$S;
    'VSS_AT73':'(0,0,0,0,0,0,0,0,0,0,0,0,0,0,0,0,0,0,0,0,0,0,0,0,0,0,0,0,0,0,0,A~
T73,0,0,0,0,0,0,0,0)';$S;
    'VSS_AU1':'(0,0,0,0,0,0,0,0,0,0,0,0,0,0,0,0,0,0,0,0,0,0,0,0,0,0,0,0,0,0,0,AU~
1,0,0,0,0,0,0,0,0)';$S;
    'VSS_AU3':'(0,0,0,0,0,0,0,0,0,0,0,0,0,0,0,0,0,0,0,0,0,0,0,0,0,0,0,0,0,0,0,AU~
3,0,0,0,0,0,0,0,0)';$S;
    'VSS_AU4':'(0,0,0,0,0,0,0,0,0,0,0,0,0,0,0,0,0,0,0,0,0,0,0,0,0,0,0,0,0,0,0,AU~
4,0,0,0,0,0,0,0,0)';$S;
    'VSS_AU6':'(0,0,0,0,0,0,0,0,0,0,0,0,0,0,0,0,0,0,0,0,0,0,0,0,0,0,0,0,0,0,0,AU~
6,0,0,0,0,0,0,0,0)';$S;
    'VSS_AU8':'(0,0,0,0,0,0,0,0,0,0,0,0,0,0,0,0,0,0,0,0,0,0,0,0,0,0,0,0,0,0,0,AU~
8,0,0,0,0,0,0,0,0)';$S;
    'VSS_AU11':'(0,0,0,0,0,0,0,0,0,0,0,0,0,0,0,0,0,0,0,0,0,0,0,0,0,0,0,0,0,0,0,A~
U11,0,0,0,0,0,0,0,0)';$S;
    'VSS_AU13':'(0,0,0,0,0,0,0,0,0,0,0,0,0,0,0,0,0,0,0,0,0,0,0,0,0,0,0,0,0,0,0,A~
U13,0,0,0,0,0,0,0,0)';$S;
    'VSS_AU15':'(0,0,0,0,0,0,0,0,0,0,0,0,0,0,0,0,0,0,0,0,0,0,0,0,0,0,0,0,0,0,0,A~
U15,0,0,0,0,0,0,0,0)';$S;
    'VSS_AU18':'(0,0,0,0,0,0,0,0,0,0,0,0,0,0,0,0,0,0,0,0,0,0,0,0,0,0,0,0,0,0,0,A~
U18,0,0,0,0,0,0,0,0)';$S;
    'VSS_AU20':'(0,0,0,0,0,0,0,0,0,0,0,0,0,0,0,0,0,0,0,0,0,0,0,0,0,0,0,0,0,0,0,A~
U20,0,0,0,0,0,0,0,0)';$S;
    'VSS_AU22':'(0,0,0,0,0,0,0,0,0,0,0,0,0,0,0,0,0,0,0,0,0,0,0,0,0,0,0,0,0,0,0,A~
U22,0,0,0,0,0,0,0,0)';$S;
    'VSS_AU24':'(0,0,0,0,0,0,0,0,0,0,0,0,0,0,0,0,0,0,0,0,0,0,0,0,0,0,0,0,0,0,0,A~
U24,0,0,0,0,0,0,0,0)';$S;
    'VSS_AU26':'(0,0,0,0,0,0,0,0,0,0,0,0,0,0,0,0,0,0,0,0,0,0,0,0,0,0,0,0,0,0,0,A~
U26,0,0,0,0,0,0,0,0)';$S;
    'VSS_AU28':'(0,0,0,0,0,0,0,0,0,0,0,0,0,0,0,0,0,0,0,0,0,0,0,0,0,0,0,0,0,0,0,A~
U28,0,0,0,0,0,0,0,0)';$S;
    'VSS_AU30':'(0,0,0,0,0,0,0,0,0,0,0,0,0,0,0,0,0,0,0,0,0,0,0,0,0,0,0,0,0,0,0,A~
U30,0,0,0,0,0,0,0,0)';$S;
    'VSS_AU32':'(0,0,0,0,0,0,0,0,0,0,0,0,0,0,0,0,0,0,0,0,0,0,0,0,0,0,0,0,0,0,0,A~
U32,0,0,0,0,0,0,0,0)';$S;
    'VSS_AU34':'(0,0,0,0,0,0,0,0,0,0,0,0,0,0,0,0,0,0,0,0,0,0,0,0,0,0,0,0,0,0,0,A~
U34,0,0,0,0,0,0,0,0)';$S;
    'VSS_AU36':'(0,0,0,0,0,0,0,0,0,0,0,0,0,0,0,0,0,0,0,0,0,0,0,0,0,0,0,0,0,0,0,A~
U36,0,0,0,0,0,0,0,0)';$S;
    'VSS_AU41':'(0,0,0,0,0,0,0,0,0,0,0,0,0,0,0,0,0,0,0,0,0,0,0,0,0,0,0,0,0,0,0,A~
U41,0,0,0,0,0,0,0,0)';$S;
    'VSS_AU43':'(0,0,0,0,0,0,0,0,0,0,0,0,0,0,0,0,0,0,0,0,0,0,0,0,0,0,0,0,0,0,0,A~
U43,0,0,0,0,0,0,0,0)';$S;
    'VSS_AU45':'(0,0,0,0,0,0,0,0,0,0,0,0,0,0,0,0,0,0,0,0,0,0,0,0,0,0,0,0,0,0,0,A~
U45,0,0,0,0,0,0,0,0)';$S;
    'VSS_AU47':'(0,0,0,0,0,0,0,0,0,0,0,0,0,0,0,0,0,0,0,0,0,0,0,0,0,0,0,0,0,0,0,A~
U47,0,0,0,0,0,0,0,0)';$S;
    'VSS_AU49':'(0,0,0,0,0,0,0,0,0,0,0,0,0,0,0,0,0,0,0,0,0,0,0,0,0,0,0,0,0,0,0,A~
U49,0,0,0,0,0,0,0,0)';$S;
    'VSS_AU51':'(0,0,0,0,0,0,0,0,0,0,0,0,0,0,0,0,0,0,0,0,0,0,0,0,0,0,0,0,0,0,0,A~
U51,0,0,0,0,0,0,0,0)';$S;
    'VSS_AU53':'(0,0,0,0,0,0,0,0,0,0,0,0,0,0,0,0,0,0,0,0,0,0,0,0,0,0,0,0,0,0,0,A~
U53,0,0,0,0,0,0,0,0)';$S;
    'VSS_AU56':'(0,0,0,0,0,0,0,0,0,0,0,0,0,0,0,0,0,0,0,0,0,0,0,0,0,0,0,0,0,0,0,A~
U56,0,0,0,0,0,0,0,0)';$S;
    'VSS_AU58':'(0,0,0,0,0,0,0,0,0,0,0,0,0,0,0,0,0,0,0,0,0,0,0,0,0,0,0,0,0,0,0,A~
U58,0,0,0,0,0,0,0,0)';$S;
    'VSS_AU61':'(0,0,0,0,0,0,0,0,0,0,0,0,0,0,0,0,0,0,0,0,0,0,0,0,0,0,0,0,0,0,0,A~
U61,0,0,0,0,0,0,0,0)';$S;
    'VSS_AU63':'(0,0,0,0,0,0,0,0,0,0,0,0,0,0,0,0,0,0,0,0,0,0,0,0,0,0,0,0,0,0,0,A~
U63,0,0,0,0,0,0,0,0)';$S;
    'VSS_AU65':'(0,0,0,0,0,0,0,0,0,0,0,0,0,0,0,0,0,0,0,0,0,0,0,0,0,0,0,0,0,0,0,A~
U65,0,0,0,0,0,0,0,0)';$S;
    'VSS_AU68':'(0,0,0,0,0,0,0,0,0,0,0,0,0,0,0,0,0,0,0,0,0,0,0,0,0,0,0,0,0,0,0,A~
U68,0,0,0,0,0,0,0,0)';$S;
    'VSS_AU70':'(0,0,0,0,0,0,0,0,0,0,0,0,0,0,0,0,0,0,0,0,0,0,0,0,0,0,0,0,0,0,0,A~
U70,0,0,0,0,0,0,0,0)';$S;
    'VSS_AU72':'(0,0,0,0,0,0,0,0,0,0,0,0,0,0,0,0,0,0,0,0,0,0,0,0,0,0,0,0,0,0,0,A~
U72,0,0,0,0,0,0,0,0)';$S;
    'VSS_AU73':'(0,0,0,0,0,0,0,0,0,0,0,0,0,0,0,0,0,0,0,0,0,0,0,0,0,0,0,0,0,0,0,A~
U73,0,0,0,0,0,0,0,0)';$S;
    'VSS_AU75':'(0,0,0,0,0,0,0,0,0,0,0,0,0,0,0,0,0,0,0,0,0,0,0,0,0,0,0,0,0,0,0,A~
U75,0,0,0,0,0,0,0,0)';$S;
    'VSS_AV3':'(0,0,0,0,0,0,0,0,0,0,0,0,0,0,0,0,0,0,0,0,0,0,0,0,0,0,0,0,0,0,0,AV~
3,0,0,0,0,0,0,0,0)';$S;
    'VSS_AV8':'(0,0,0,0,0,0,0,0,0,0,0,0,0,0,0,0,0,0,0,0,0,0,0,0,0,0,0,0,0,0,0,AV~
8,0,0,0,0,0,0,0,0)';$S;
    'VSS_AV10':'(0,0,0,0,0,0,0,0,0,0,0,0,0,0,0,0,0,0,0,0,0,0,0,0,0,0,0,0,0,0,0,A~
V10,0,0,0,0,0,0,0,0)';$S;
    'VSS_AV15':'(0,0,0,0,0,0,0,0,0,0,0,0,0,0,0,0,0,0,0,0,0,0,0,0,0,0,0,0,0,0,0,A~
V15,0,0,0,0,0,0,0,0)';$S;
    'VSS_AV17':'(0,0,0,0,0,0,0,0,0,0,0,0,0,0,0,0,0,0,0,0,0,0,0,0,0,0,0,0,0,0,0,A~
V17,0,0,0,0,0,0,0,0)';$S;
    'VSS_AV23':'(0,0,0,0,0,0,0,0,0,0,0,0,0,0,0,0,0,0,0,0,0,0,0,0,0,0,0,0,0,0,0,A~
V23,0,0,0,0,0,0,0,0)';$S;
    'VSS_AV25':'(0,0,0,0,0,0,0,0,0,0,0,0,0,0,0,0,0,0,0,0,0,0,0,0,0,0,0,0,0,0,0,A~
V25,0,0,0,0,0,0,0,0)';$S;
    'VSS_AV27':'(0,0,0,0,0,0,0,0,0,0,0,0,0,0,0,0,0,0,0,0,0,0,0,0,0,0,0,0,0,0,0,A~
V27,0,0,0,0,0,0,0,0)';$S;
    'VSS_AV29':'(0,0,0,0,0,0,0,0,0,0,0,0,0,0,0,0,0,0,0,0,0,0,0,0,0,0,0,0,0,0,0,A~
V29,0,0,0,0,0,0,0,0)';$S;
    'VSS_AV31':'(0,0,0,0,0,0,0,0,0,0,0,0,0,0,0,0,0,0,0,0,0,0,0,0,0,0,0,0,0,0,0,A~
V31,0,0,0,0,0,0,0,0)';$S;
    'VSS_AV33':'(0,0,0,0,0,0,0,0,0,0,0,0,0,0,0,0,0,0,0,0,0,0,0,0,0,0,0,0,0,0,0,A~
V33,0,0,0,0,0,0,0,0)';$S;
    'VSS_AV35':'(0,0,0,0,0,0,0,0,0,0,0,0,0,0,0,0,0,0,0,0,0,0,0,0,0,0,0,0,0,0,0,A~
V35,0,0,0,0,0,0,0,0)';$S;
    'VSS_AV37':'(0,0,0,0,0,0,0,0,0,0,0,0,0,0,0,0,0,0,0,0,0,0,0,0,0,0,0,0,0,0,0,A~
V37,0,0,0,0,0,0,0,0)';$S;
    'VSS_AV40':'(0,0,0,0,0,0,0,0,0,0,0,0,0,0,0,0,0,0,0,0,0,0,0,0,0,0,0,0,0,0,0,A~
V40,0,0,0,0,0,0,0,0)';$S;
    'VSS_AV42':'(0,0,0,0,0,0,0,0,0,0,0,0,0,0,0,0,0,0,0,0,0,0,0,0,0,0,0,0,0,0,0,A~
V42,0,0,0,0,0,0,0,0)';$S;
    'VSS_AV44':'(0,0,0,0,0,0,0,0,0,0,0,0,0,0,0,0,0,0,0,0,0,0,0,0,0,0,0,0,0,0,0,A~
V44,0,0,0,0,0,0,0,0)';$S;
    'VSS_AV46':'(0,0,0,0,0,0,0,0,0,0,0,0,0,0,0,0,0,0,0,0,0,0,0,0,0,0,0,0,0,0,0,A~
V46,0,0,0,0,0,0,0,0)';$S;
    'VSS_AV48':'(0,0,0,0,0,0,0,0,0,0,0,0,0,0,0,0,0,0,0,0,0,0,0,0,0,0,0,0,0,0,0,A~
V48,0,0,0,0,0,0,0,0)';$S;
    'VSS_AV50':'(0,0,0,0,0,0,0,0,0,0,0,0,0,0,0,0,0,0,0,0,0,0,0,0,0,0,0,0,0,0,0,A~
V50,0,0,0,0,0,0,0,0)';$S;
    'VSS_AV52':'(0,0,0,0,0,0,0,0,0,0,0,0,0,0,0,0,0,0,0,0,0,0,0,0,0,0,0,0,0,0,0,A~
V52,0,0,0,0,0,0,0,0)';$S;
    'VSS_AV54':'(0,0,0,0,0,0,0,0,0,0,0,0,0,0,0,0,0,0,0,0,0,0,0,0,0,0,0,0,0,0,0,A~
V54,0,0,0,0,0,0,0,0)';$S;
    'VSS_AV59':'(0,0,0,0,0,0,0,0,0,0,0,0,0,0,0,0,0,0,0,0,0,0,0,0,0,0,0,0,0,0,0,A~
V59,0,0,0,0,0,0,0,0)';$S;
    'VSS_AV61':'(0,0,0,0,0,0,0,0,0,0,0,0,0,0,0,0,0,0,0,0,0,0,0,0,0,0,0,0,0,0,0,A~
V61,0,0,0,0,0,0,0,0)';$S;
    'VSS_AV66':'(0,0,0,0,0,0,0,0,0,0,0,0,0,0,0,0,0,0,0,0,0,0,0,0,0,0,0,0,0,0,0,A~
V66,0,0,0,0,0,0,0,0)';$S;
    'VSS_AV68':'(0,0,0,0,0,0,0,0,0,0,0,0,0,0,0,0,0,0,0,0,0,0,0,0,0,0,0,0,0,0,0,A~
V68,0,0,0,0,0,0,0,0)';$S;
    'VSS_AV73':'(0,0,0,0,0,0,0,0,0,0,0,0,0,0,0,0,0,0,0,0,0,0,0,0,0,0,0,0,0,0,0,A~
V73,0,0,0,0,0,0,0,0)';$S;
    'VSS_AW1':'(0,0,0,0,0,0,0,0,0,0,0,0,0,0,0,0,0,0,0,0,0,0,0,0,0,0,0,0,0,0,0,AW~
1,0,0,0,0,0,0,0,0)';$S;
    'VSS_AW4':'(0,0,0,0,0,0,0,0,0,0,0,0,0,0,0,0,0,0,0,0,0,0,0,0,0,0,0,0,0,0,0,AW~
4,0,0,0,0,0,0,0,0)';$S;
    'VSS_AW6':'(0,0,0,0,0,0,0,0,0,0,0,0,0,0,0,0,0,0,0,0,0,0,0,0,0,0,0,0,0,0,0,AW~
6,0,0,0,0,0,0,0,0)';$S;
    'VSS_AW8':'(0,0,0,0,0,0,0,0,0,0,0,0,0,0,0,0,0,0,0,0,0,0,0,0,0,0,0,0,0,0,0,AW~
8,0,0,0,0,0,0,0,0)';$S;
    'VSS_AW11':'(0,0,0,0,0,0,0,0,0,0,0,0,0,0,0,0,0,0,0,0,0,0,0,0,0,0,0,0,0,0,0,A~
W11,0,0,0,0,0,0,0,0)';$S;
    'VSS_AW13':'(0,0,0,0,0,0,0,0,0,0,0,0,0,0,0,0,0,0,0,0,0,0,0,0,0,0,0,0,0,0,0,A~
W13,0,0,0,0,0,0,0,0)';$S;
    'VSS_AW15':'(0,0,0,0,0,0,0,0,0,0,0,0,0,0,0,0,0,0,0,0,0,0,0,0,0,0,0,0,0,0,0,A~
W15,0,0,0,0,0,0,0,0)';$S;
    'VSS_AW18':'(0,0,0,0,0,0,0,0,0,0,0,0,0,0,0,0,0,0,0,0,0,0,0,0,0,0,0,0,0,0,0,A~
W18,0,0,0,0,0,0,0,0)';$S;
    'VSS_AW20':'(0,0,0,0,0,0,0,0,0,0,0,0,0,0,0,0,0,0,0,0,0,0,0,0,0,0,0,0,0,0,0,A~
W20,0,0,0,0,0,0,0,0)';$S;
    'VSS_AW22':'(0,0,0,0,0,0,0,0,0,0,0,0,0,0,0,0,0,0,0,0,0,0,0,0,0,0,0,0,0,0,0,A~
W22,0,0,0,0,0,0,0,0)';$S;
    'VSS_AW24':'(0,0,0,0,0,0,0,0,0,0,0,0,0,0,0,0,0,0,0,0,0,0,0,0,0,0,0,0,0,0,0,A~
W24,0,0,0,0,0,0,0,0)';$S;
    'VSS_AW26':'(0,0,0,0,0,0,0,0,0,0,0,0,0,0,0,0,0,0,0,0,0,0,0,0,0,0,0,0,0,0,0,A~
W26,0,0,0,0,0,0,0,0)';$S;
    'VSS_AW28':'(0,0,0,0,0,0,0,0,0,0,0,0,0,0,0,0,0,0,0,0,0,0,0,0,0,0,0,0,0,0,0,A~
W28,0,0,0,0,0,0,0,0)';$S;
    'VSS_AW49':'(0,0,0,0,0,0,0,0,0,0,0,0,0,0,0,0,0,0,0,0,0,0,0,0,0,0,0,0,0,0,0,A~
W49,0,0,0,0,0,0,0,0)';$S;
    'VSS_AW51':'(0,0,0,0,0,0,0,0,0,0,0,0,0,0,0,0,0,0,0,0,0,0,0,0,0,0,0,0,0,0,0,A~
W51,0,0,0,0,0,0,0,0)';$S;
    'VSS_AW53':'(0,0,0,0,0,0,0,0,0,0,0,0,0,0,0,0,0,0,0,0,0,0,0,0,0,0,0,0,0,0,0,A~
W53,0,0,0,0,0,0,0,0)';$S;
    'VSS_AW56':'(0,0,0,0,0,0,0,0,0,0,0,0,0,0,0,0,0,0,0,0,0,0,0,0,0,0,0,0,0,0,0,A~
W56,0,0,0,0,0,0,0,0)';$S;
    'VSS_AW58':'(0,0,0,0,0,0,0,0,0,0,0,0,0,0,0,0,0,0,0,0,0,0,0,0,0,0,0,0,0,0,0,A~
W58,0,0,0,0,0,0,0,0)';$S;
    'VSS_AW61':'(0,0,0,0,0,0,0,0,0,0,0,0,0,0,0,0,0,0,0,0,0,0,0,0,0,0,0,0,0,0,0,A~
W61,0,0,0,0,0,0,0,0)';$S;
    'VSS_AW63':'(0,0,0,0,0,0,0,0,0,0,0,0,0,0,0,0,0,0,0,0,0,0,0,0,0,0,0,0,0,0,0,0~
,AW63,0,0,0,0,0,0,0)';$S;
    'VSS_AW65':'(0,0,0,0,0,0,0,0,0,0,0,0,0,0,0,0,0,0,0,0,0,0,0,0,0,0,0,0,0,0,0,0~
,AW65,0,0,0,0,0,0,0)';$S;
    'VSS_AW68':'(0,0,0,0,0,0,0,0,0,0,0,0,0,0,0,0,0,0,0,0,0,0,0,0,0,0,0,0,0,0,0,0~
,AW68,0,0,0,0,0,0,0)';$S;
    'VSS_AW70':'(0,0,0,0,0,0,0,0,0,0,0,0,0,0,0,0,0,0,0,0,0,0,0,0,0,0,0,0,0,0,0,0~
,AW70,0,0,0,0,0,0,0)';$S;
    'VSS_AW72':'(0,0,0,0,0,0,0,0,0,0,0,0,0,0,0,0,0,0,0,0,0,0,0,0,0,0,0,0,0,0,0,0~
,AW72,0,0,0,0,0,0,0)';$S;
    'VSS_AW75':'(0,0,0,0,0,0,0,0,0,0,0,0,0,0,0,0,0,0,0,0,0,0,0,0,0,0,0,0,0,0,0,0~
,AW75,0,0,0,0,0,0,0)';$S;
    'VSS_AY3':'(0,0,0,0,0,0,0,0,0,0,0,0,0,0,0,0,0,0,0,0,0,0,0,0,0,0,0,0,0,0,0,0,~
AY3,0,0,0,0,0,0,0)';$S;
    'VSS_AY5':'(0,0,0,0,0,0,0,0,0,0,0,0,0,0,0,0,0,0,0,0,0,0,0,0,0,0,0,0,0,0,0,0,~
AY5,0,0,0,0,0,0,0)';$S;
    'VSS_AY8':'(0,0,0,0,0,0,0,0,0,0,0,0,0,0,0,0,0,0,0,0,0,0,0,0,0,0,0,0,0,0,0,0,~
AY8,0,0,0,0,0,0,0)';$S;
    'VSS_AY10':'(0,0,0,0,0,0,0,0,0,0,0,0,0,0,0,0,0,0,0,0,0,0,0,0,0,0,0,0,0,0,0,0~
,AY10,0,0,0,0,0,0,0)';$S;
    'VSS_AY12':'(0,0,0,0,0,0,0,0,0,0,0,0,0,0,0,0,0,0,0,0,0,0,0,0,0,0,0,0,0,0,0,0~
,AY12,0,0,0,0,0,0,0)';$S;
    'VSS_AY15':'(0,0,0,0,0,0,0,0,0,0,0,0,0,0,0,0,0,0,0,0,0,0,0,0,0,0,0,0,0,0,0,0~
,AY15,0,0,0,0,0,0,0)';$S;
    'VSS_AY17':'(0,0,0,0,0,0,0,0,0,0,0,0,0,0,0,0,0,0,0,0,0,0,0,0,0,0,0,0,0,0,0,0~
,AY17,0,0,0,0,0,0,0)';$S;
    'VSS_AY19':'(0,0,0,0,0,0,0,0,0,0,0,0,0,0,0,0,0,0,0,0,0,0,0,0,0,0,0,0,0,0,0,0~
,AY19,0,0,0,0,0,0,0)';$S;
    'VSS_AY23':'(0,0,0,0,0,0,0,0,0,0,0,0,0,0,0,0,0,0,0,0,0,0,0,0,0,0,0,0,0,0,0,0~
,AY23,0,0,0,0,0,0,0)';$S;
    'VSS_AY25':'(0,0,0,0,0,0,0,0,0,0,0,0,0,0,0,0,0,0,0,0,0,0,0,0,0,0,0,0,0,0,0,0~
,AY25,0,0,0,0,0,0,0)';$S;
    'VSS_AY27':'(0,0,0,0,0,0,0,0,0,0,0,0,0,0,0,0,0,0,0,0,0,0,0,0,0,0,0,0,0,0,0,0~
,AY27,0,0,0,0,0,0,0)';$S;
    'VSS_AY48':'(0,0,0,0,0,0,0,0,0,0,0,0,0,0,0,0,0,0,0,0,0,0,0,0,0,0,0,0,0,0,0,0~
,AY48,0,0,0,0,0,0,0)';$S;
    'VSS_AY50':'(0,0,0,0,0,0,0,0,0,0,0,0,0,0,0,0,0,0,0,0,0,0,0,0,0,0,0,0,0,0,0,0~
,AY50,0,0,0,0,0,0,0)';$S;
    'VSS_AY52':'(0,0,0,0,0,0,0,0,0,0,0,0,0,0,0,0,0,0,0,0,0,0,0,0,0,0,0,0,0,0,0,0~
,AY52,0,0,0,0,0,0,0)';$S;
    'VSS_AY54':'(0,0,0,0,0,0,0,0,0,0,0,0,0,0,0,0,0,0,0,0,0,0,0,0,0,0,0,0,0,0,0,0~
,AY54,0,0,0,0,0,0,0)';$S;
    'VSS_AY57':'(0,0,0,0,0,0,0,0,0,0,0,0,0,0,0,0,0,0,0,0,0,0,0,0,0,0,0,0,0,0,0,0~
,AY57,0,0,0,0,0,0,0)';$S;
    'VSS_AY59':'(0,0,0,0,0,0,0,0,0,0,0,0,0,0,0,0,0,0,0,0,0,0,0,0,0,0,0,0,0,0,0,0~
,AY59,0,0,0,0,0,0,0)';$S;
    'VSS_AY61':'(0,0,0,0,0,0,0,0,0,0,0,0,0,0,0,0,0,0,0,0,0,0,0,0,0,0,0,0,0,0,0,0~
,AY61,0,0,0,0,0,0,0)';$S;
    'VSS_AY64':'(0,0,0,0,0,0,0,0,0,0,0,0,0,0,0,0,0,0,0,0,0,0,0,0,0,0,0,0,0,0,0,0~
,AY64,0,0,0,0,0,0,0)';$S;
    'VSS_AY66':'(0,0,0,0,0,0,0,0,0,0,0,0,0,0,0,0,0,0,0,0,0,0,0,0,0,0,0,0,0,0,0,0~
,AY66,0,0,0,0,0,0,0)';$S;
    'VSS_AY68':'(0,0,0,0,0,0,0,0,0,0,0,0,0,0,0,0,0,0,0,0,0,0,0,0,0,0,0,0,0,0,0,0~
,AY68,0,0,0,0,0,0,0)';$S;
    'VSS_AY71':'(0,0,0,0,0,0,0,0,0,0,0,0,0,0,0,0,0,0,0,0,0,0,0,0,0,0,0,0,0,0,0,0~
,AY71,0,0,0,0,0,0,0)';$S;
    'VSS_AY73':'(0,0,0,0,0,0,0,0,0,0,0,0,0,0,0,0,0,0,0,0,0,0,0,0,0,0,0,0,0,0,0,0~
,AY73,0,0,0,0,0,0,0)';$S;
    'VSS_BA1':'(0,0,0,0,0,0,0,0,0,0,0,0,0,0,0,0,0,0,0,0,0,0,0,0,0,0,0,0,0,0,0,0,~
BA1,0,0,0,0,0,0,0)';$S;
    'VSS_BA6':'(0,0,0,0,0,0,0,0,0,0,0,0,0,0,0,0,0,0,0,0,0,0,0,0,0,0,0,0,0,0,0,0,~
BA6,0,0,0,0,0,0,0)';$S;
    'VSS_BA8':'(0,0,0,0,0,0,0,0,0,0,0,0,0,0,0,0,0,0,0,0,0,0,0,0,0,0,0,0,0,0,0,0,~
BA8,0,0,0,0,0,0,0)';$S;
    'VSS_BA13':'(0,0,0,0,0,0,0,0,0,0,0,0,0,0,0,0,0,0,0,0,0,0,0,0,0,0,0,0,0,0,0,0~
,BA13,0,0,0,0,0,0,0)';$S;
    'VSS_BA15':'(0,0,0,0,0,0,0,0,0,0,0,0,0,0,0,0,0,0,0,0,0,0,0,0,0,0,0,0,0,0,0,0~
,BA15,0,0,0,0,0,0,0)';$S;
    'VSS_BA20':'(0,0,0,0,0,0,0,0,0,0,0,0,0,0,0,0,0,0,0,0,0,0,0,0,0,0,0,0,0,0,0,0~
,BA20,0,0,0,0,0,0,0)';$S;
    'VSS_BA22':'(0,0,0,0,0,0,0,0,0,0,0,0,0,0,0,0,0,0,0,0,0,0,0,0,0,0,0,0,0,0,0,0~
,BA22,0,0,0,0,0,0,0)';$S;
    'VSS_BA24':'(0,0,0,0,0,0,0,0,0,0,0,0,0,0,0,0,0,0,0,0,0,0,0,0,0,0,0,0,0,0,0,0~
,BA24,0,0,0,0,0,0,0)';$S;
    'VSS_BA26':'(0,0,0,0,0,0,0,0,0,0,0,0,0,0,0,0,0,0,0,0,0,0,0,0,0,0,0,0,0,0,0,0~
,BA26,0,0,0,0,0,0,0)';$S;
    'VSS_BA28':'(0,0,0,0,0,0,0,0,0,0,0,0,0,0,0,0,0,0,0,0,0,0,0,0,0,0,0,0,0,0,0,0~
,BA28,0,0,0,0,0,0,0)';$S;
    'VSS_BA49':'(0,0,0,0,0,0,0,0,0,0,0,0,0,0,0,0,0,0,0,0,0,0,0,0,0,0,0,0,0,0,0,0~
,BA49,0,0,0,0,0,0,0)';$S;
    'VSS_BA51':'(0,0,0,0,0,0,0,0,0,0,0,0,0,0,0,0,0,0,0,0,0,0,0,0,0,0,0,0,0,0,0,0~
,BA51,0,0,0,0,0,0,0)';$S;
    'VSS_BA53':'(0,0,0,0,0,0,0,0,0,0,0,0,0,0,0,0,0,0,0,0,0,0,0,0,0,0,0,0,0,0,0,0~
,BA53,0,0,0,0,0,0,0)';$S;
    'VSS_BA56':'(0,0,0,0,0,0,0,0,0,0,0,0,0,0,0,0,0,0,0,0,0,0,0,0,0,0,0,0,0,0,0,0~
,BA56,0,0,0,0,0,0,0)';$S;
    'VSS_BA61':'(0,0,0,0,0,0,0,0,0,0,0,0,0,0,0,0,0,0,0,0,0,0,0,0,0,0,0,0,0,0,0,0~
,BA61,0,0,0,0,0,0,0)';$S;
    'VSS_BA63':'(0,0,0,0,0,0,0,0,0,0,0,0,0,0,0,0,0,0,0,0,0,0,0,0,0,0,0,0,0,0,0,0~
,BA63,0,0,0,0,0,0,0)';$S;
    'VSS_BA68':'(0,0,0,0,0,0,0,0,0,0,0,0,0,0,0,0,0,0,0,0,0,0,0,0,0,0,0,0,0,0,0,0~
,BA68,0,0,0,0,0,0,0)';$S;
    'VSS_BA70':'(0,0,0,0,0,0,0,0,0,0,0,0,0,0,0,0,0,0,0,0,0,0,0,0,0,0,0,0,0,0,0,0~
,BA70,0,0,0,0,0,0,0)';$S;
    'VSS_BA75':'(0,0,0,0,0,0,0,0,0,0,0,0,0,0,0,0,0,0,0,0,0,0,0,0,0,0,0,0,0,0,0,0~
,BA75,0,0,0,0,0,0,0)';$S;
    'VSS_BB3':'(0,0,0,0,0,0,0,0,0,0,0,0,0,0,0,0,0,0,0,0,0,0,0,0,0,0,0,0,0,0,0,0,~
BB3,0,0,0,0,0,0,0)';$S;
    'VSS_BB5':'(0,0,0,0,0,0,0,0,0,0,0,0,0,0,0,0,0,0,0,0,0,0,0,0,0,0,0,0,0,0,0,0,~
BB5,0,0,0,0,0,0,0)';$S;
    'VSS_BB8':'(0,0,0,0,0,0,0,0,0,0,0,0,0,0,0,0,0,0,0,0,0,0,0,0,0,0,0,0,0,0,0,0,~
BB8,0,0,0,0,0,0,0)';$S;
    'VSS_BB10':'(0,0,0,0,0,0,0,0,0,0,0,0,0,0,0,0,0,0,0,0,0,0,0,0,0,0,0,0,0,0,0,0~
,BB10,0,0,0,0,0,0,0)';$S;
    'VSS_BB12':'(0,0,0,0,0,0,0,0,0,0,0,0,0,0,0,0,0,0,0,0,0,0,0,0,0,0,0,0,0,0,0,0~
,BB12,0,0,0,0,0,0,0)';$S;
    'VSS_BB15':'(0,0,0,0,0,0,0,0,0,0,0,0,0,0,0,0,0,0,0,0,0,0,0,0,0,0,0,0,0,0,0,0~
,BB15,0,0,0,0,0,0,0)';$S;
    'VSS_BB17':'(0,0,0,0,0,0,0,0,0,0,0,0,0,0,0,0,0,0,0,0,0,0,0,0,0,0,0,0,0,0,0,0~
,BB17,0,0,0,0,0,0,0)';$S;
    'VSS_BB19':'(0,0,0,0,0,0,0,0,0,0,0,0,0,0,0,0,0,0,0,0,0,0,0,0,0,0,0,0,0,0,0,0~
,BB19,0,0,0,0,0,0,0)';$S;
    'VSS_BB23':'(0,0,0,0,0,0,0,0,0,0,0,0,0,0,0,0,0,0,0,0,0,0,0,0,0,0,0,0,0,0,0,0~
,BB23,0,0,0,0,0,0,0)';$S;
    'VSS_BB25':'(0,0,0,0,0,0,0,0,0,0,0,0,0,0,0,0,0,0,0,0,0,0,0,0,0,0,0,0,0,0,0,0~
,BB25,0,0,0,0,0,0,0)';$S;
    'VSS_BB27':'(0,0,0,0,0,0,0,0,0,0,0,0,0,0,0,0,0,0,0,0,0,0,0,0,0,0,0,0,0,0,0,0~
,BB27,0,0,0,0,0,0,0)';$S;
    'VSS_BB48':'(0,0,0,0,0,0,0,0,0,0,0,0,0,0,0,0,0,0,0,0,0,0,0,0,0,0,0,0,0,0,0,0~
,BB48,0,0,0,0,0,0,0)';$S;
    'VSS_BB50':'(0,0,0,0,0,0,0,0,0,0,0,0,0,0,0,0,0,0,0,0,0,0,0,0,0,0,0,0,0,0,0,0~
,BB50,0,0,0,0,0,0,0)';$S;
    'VSS_BB52':'(0,0,0,0,0,0,0,0,0,0,0,0,0,0,0,0,0,0,0,0,0,0,0,0,0,0,0,0,0,0,0,0~
,BB52,0,0,0,0,0,0,0)';$S;
    'VSS_BB54':'(0,0,0,0,0,0,0,0,0,0,0,0,0,0,0,0,0,0,0,0,0,0,0,0,0,0,0,0,0,0,0,0~
,BB54,0,0,0,0,0,0,0)';$S;
    'VSS_BB57':'(0,0,0,0,0,0,0,0,0,0,0,0,0,0,0,0,0,0,0,0,0,0,0,0,0,0,0,0,0,0,0,0~
,BB57,0,0,0,0,0,0,0)';$S;
    'VSS_BB59':'(0,0,0,0,0,0,0,0,0,0,0,0,0,0,0,0,0,0,0,0,0,0,0,0,0,0,0,0,0,0,0,0~
,BB59,0,0,0,0,0,0,0)';$S;
    'VSS_BB61':'(0,0,0,0,0,0,0,0,0,0,0,0,0,0,0,0,0,0,0,0,0,0,0,0,0,0,0,0,0,0,0,0~
,BB61,0,0,0,0,0,0,0)';$S;
    'VSS_BB64':'(0,0,0,0,0,0,0,0,0,0,0,0,0,0,0,0,0,0,0,0,0,0,0,0,0,0,0,0,0,0,0,0~
,BB64,0,0,0,0,0,0,0)';$S;
    'VSS_BB66':'(0,0,0,0,0,0,0,0,0,0,0,0,0,0,0,0,0,0,0,0,0,0,0,0,0,0,0,0,0,0,0,0~
,BB66,0,0,0,0,0,0,0)';$S;
    'VSS_BB68':'(0,0,0,0,0,0,0,0,0,0,0,0,0,0,0,0,0,0,0,0,0,0,0,0,0,0,0,0,0,0,0,0~
,BB68,0,0,0,0,0,0,0)';$S;
    'VSS_BB71':'(0,0,0,0,0,0,0,0,0,0,0,0,0,0,0,0,0,0,0,0,0,0,0,0,0,0,0,0,0,0,0,0~
,BB71,0,0,0,0,0,0,0)';$S;
    'VSS_BB73':'(0,0,0,0,0,0,0,0,0,0,0,0,0,0,0,0,0,0,0,0,0,0,0,0,0,0,0,0,0,0,0,0~
,BB73,0,0,0,0,0,0,0)';$S;
    'VSS_BC1':'(0,0,0,0,0,0,0,0,0,0,0,0,0,0,0,0,0,0,0,0,0,0,0,0,0,0,0,0,0,0,0,0,~
BC1,0,0,0,0,0,0,0)';$S;
    'VSS_BC4':'(0,0,0,0,0,0,0,0,0,0,0,0,0,0,0,0,0,0,0,0,0,0,0,0,0,0,0,0,0,0,0,0,~
BC4,0,0,0,0,0,0,0)';$S;
    'VSS_BC6':'(0,0,0,0,0,0,0,0,0,0,0,0,0,0,0,0,0,0,0,0,0,0,0,0,0,0,0,0,0,0,0,0,~
BC6,0,0,0,0,0,0,0)';$S;
    'VSS_BC8':'(0,0,0,0,0,0,0,0,0,0,0,0,0,0,0,0,0,0,0,0,0,0,0,0,0,0,0,0,0,0,0,0,~
BC8,0,0,0,0,0,0,0)';$S;
    'VSS_BC11':'(0,0,0,0,0,0,0,0,0,0,0,0,0,0,0,0,0,0,0,0,0,0,0,0,0,0,0,0,0,0,0,0~
,BC11,0,0,0,0,0,0,0)';$S;
    'VSS_BC13':'(0,0,0,0,0,0,0,0,0,0,0,0,0,0,0,0,0,0,0,0,0,0,0,0,0,0,0,0,0,0,0,0~
,BC13,0,0,0,0,0,0,0)';$S;
    'VSS_BC15':'(0,0,0,0,0,0,0,0,0,0,0,0,0,0,0,0,0,0,0,0,0,0,0,0,0,0,0,0,0,0,0,0~
,BC15,0,0,0,0,0,0,0)';$S;
    'VSS_BC18':'(0,0,0,0,0,0,0,0,0,0,0,0,0,0,0,0,0,0,0,0,0,0,0,0,0,0,0,0,0,0,0,0~
,BC18,0,0,0,0,0,0,0)';$S;
    'VSS_BC20':'(0,0,0,0,0,0,0,0,0,0,0,0,0,0,0,0,0,0,0,0,0,0,0,0,0,0,0,0,0,0,0,0~
,BC20,0,0,0,0,0,0,0)';$S;
    'VSS_BC22':'(0,0,0,0,0,0,0,0,0,0,0,0,0,0,0,0,0,0,0,0,0,0,0,0,0,0,0,0,0,0,0,0~
,BC22,0,0,0,0,0,0,0)';$S;
    'VSS_BC24':'(0,0,0,0,0,0,0,0,0,0,0,0,0,0,0,0,0,0,0,0,0,0,0,0,0,0,0,0,0,0,0,0~
,BC24,0,0,0,0,0,0,0)';$S;
    'VSS_BC26':'(0,0,0,0,0,0,0,0,0,0,0,0,0,0,0,0,0,0,0,0,0,0,0,0,0,0,0,0,0,0,0,0~
,BC26,0,0,0,0,0,0,0)';$S;
    'VSS_BC28':'(0,0,0,0,0,0,0,0,0,0,0,0,0,0,0,0,0,0,0,0,0,0,0,0,0,0,0,0,0,0,0,0~
,BC28,0,0,0,0,0,0,0)';$S;
    'VSS_BC49':'(0,0,0,0,0,0,0,0,0,0,0,0,0,0,0,0,0,0,0,0,0,0,0,0,0,0,0,0,0,0,0,0~
,BC49,0,0,0,0,0,0,0)';$S;
    'VSS_BC50':'(0,0,0,0,0,0,0,0,0,0,0,0,0,0,0,0,0,0,0,0,0,0,0,0,0,0,0,0,0,0,0,0~
,BC50,0,0,0,0,0,0,0)';$S;
    'VSS_BC51':'(0,0,0,0,0,0,0,0,0,0,0,0,0,0,0,0,0,0,0,0,0,0,0,0,0,0,0,0,0,0,0,0~
,BC51,0,0,0,0,0,0,0)';$S;
    'VSS_BC53':'(0,0,0,0,0,0,0,0,0,0,0,0,0,0,0,0,0,0,0,0,0,0,0,0,0,0,0,0,0,0,0,0~
,BC53,0,0,0,0,0,0,0)';$S;
    'VSS_BC56':'(0,0,0,0,0,0,0,0,0,0,0,0,0,0,0,0,0,0,0,0,0,0,0,0,0,0,0,0,0,0,0,0~
,BC56,0,0,0,0,0,0,0)';$S;
    'VSS_BC58':'(0,0,0,0,0,0,0,0,0,0,0,0,0,0,0,0,0,0,0,0,0,0,0,0,0,0,0,0,0,0,0,0~
,BC58,0,0,0,0,0,0,0)';$S;
    'VSS_BC61':'(0,0,0,0,0,0,0,0,0,0,0,0,0,0,0,0,0,0,0,0,0,0,0,0,0,0,0,0,0,0,0,0~
,BC61,0,0,0,0,0,0,0)';$S;
    'VSS_BC63':'(0,0,0,0,0,0,0,0,0,0,0,0,0,0,0,0,0,0,0,0,0,0,0,0,0,0,0,0,0,0,0,0~
,BC63,0,0,0,0,0,0,0)';$S;
    'VSS_BC65':'(0,0,0,0,0,0,0,0,0,0,0,0,0,0,0,0,0,0,0,0,0,0,0,0,0,0,0,0,0,0,0,0~
,BC65,0,0,0,0,0,0,0)';$S;
    'VSS_BC68':'(0,0,0,0,0,0,0,0,0,0,0,0,0,0,0,0,0,0,0,0,0,0,0,0,0,0,0,0,0,0,0,0~
,BC68,0,0,0,0,0,0,0)';$S;
    'VSS_BC70':'(0,0,0,0,0,0,0,0,0,0,0,0,0,0,0,0,0,0,0,0,0,0,0,0,0,0,0,0,0,0,0,0~
,BC70,0,0,0,0,0,0,0)';$S;
    'VSS_BC72':'(0,0,0,0,0,0,0,0,0,0,0,0,0,0,0,0,0,0,0,0,0,0,0,0,0,0,0,0,0,0,0,0~
,BC72,0,0,0,0,0,0,0)';$S;
    'VSS_BC75':'(0,0,0,0,0,0,0,0,0,0,0,0,0,0,0,0,0,0,0,0,0,0,0,0,0,0,0,0,0,0,0,0~
,BC75,0,0,0,0,0,0,0)';$S;
    'VSS_BD3':'(0,0,0,0,0,0,0,0,0,0,0,0,0,0,0,0,0,0,0,0,0,0,0,0,0,0,0,0,0,0,0,0,~
BD3,0,0,0,0,0,0,0)';$S;
    'VSS_BD8':'(0,0,0,0,0,0,0,0,0,0,0,0,0,0,0,0,0,0,0,0,0,0,0,0,0,0,0,0,0,0,0,0,~
BD8,0,0,0,0,0,0,0)';$S;
    'VSS_BD10':'(0,0,0,0,0,0,0,0,0,0,0,0,0,0,0,0,0,0,0,0,0,0,0,0,0,0,0,0,0,0,0,0~
,BD10,0,0,0,0,0,0,0)';$S;
    'VSS_BD15':'(0,0,0,0,0,0,0,0,0,0,0,0,0,0,0,0,0,0,0,0,0,0,0,0,0,0,0,0,0,0,0,0~
,BD15,0,0,0,0,0,0,0)';$S;
    'VSS_BD17':'(0,0,0,0,0,0,0,0,0,0,0,0,0,0,0,0,0,0,0,0,0,0,0,0,0,0,0,0,0,0,0,0~
,BD17,0,0,0,0,0,0,0)';$S;
    'VSS_BD23':'(0,0,0,0,0,0,0,0,0,0,0,0,0,0,0,0,0,0,0,0,0,0,0,0,0,0,0,0,0,0,0,0~
,BD23,0,0,0,0,0,0,0)';$S;
    'VSS_BD25':'(0,0,0,0,0,0,0,0,0,0,0,0,0,0,0,0,0,0,0,0,0,0,0,0,0,0,0,0,0,0,0,0~
,BD25,0,0,0,0,0,0,0)';$S;
    'VSS_BD27':'(0,0,0,0,0,0,0,0,0,0,0,0,0,0,0,0,0,0,0,0,0,0,0,0,0,0,0,0,0,0,0,0~
,BD27,0,0,0,0,0,0,0)';$S;
    'VSS_BD49':'(0,0,0,0,0,0,0,0,0,0,0,0,0,0,0,0,0,0,0,0,0,0,0,0,0,0,0,0,0,0,0,0~
,BD49,0,0,0,0,0,0,0)';$S;
    'VSS_BD51':'(0,0,0,0,0,0,0,0,0,0,0,0,0,0,0,0,0,0,0,0,0,0,0,0,0,0,0,0,0,0,0,0~
,BD51,0,0,0,0,0,0,0)';$S;
    'VSS_BD53':'(0,0,0,0,0,0,0,0,0,0,0,0,0,0,0,0,0,0,0,0,0,0,0,0,0,0,0,0,0,0,0,0~
,BD53,0,0,0,0,0,0,0)';$S;
    'VSS_BD57':'(0,0,0,0,0,0,0,0,0,0,0,0,0,0,0,0,0,0,0,0,0,0,0,0,0,0,0,0,0,0,0,0~
,BD57,0,0,0,0,0,0,0)';$S;
    'VSS_BD59':'(0,0,0,0,0,0,0,0,0,0,0,0,0,0,0,0,0,0,0,0,0,0,0,0,0,0,0,0,0,0,0,0~
,BD59,0,0,0,0,0,0,0)';$S;
    'VSS_BD61':'(0,0,0,0,0,0,0,0,0,0,0,0,0,0,0,0,0,0,0,0,0,0,0,0,0,0,0,0,0,0,0,0~
,BD61,0,0,0,0,0,0,0)';$S;
    'VSS_BD64':'(0,0,0,0,0,0,0,0,0,0,0,0,0,0,0,0,0,0,0,0,0,0,0,0,0,0,0,0,0,0,0,0~
,BD64,0,0,0,0,0,0,0)';$S;
    'VSS_BD66':'(0,0,0,0,0,0,0,0,0,0,0,0,0,0,0,0,0,0,0,0,0,0,0,0,0,0,0,0,0,0,0,0~
,BD66,0,0,0,0,0,0,0)';$S;
    'VSS_BD68':'(0,0,0,0,0,0,0,0,0,0,0,0,0,0,0,0,0,0,0,0,0,0,0,0,0,0,0,0,0,0,0,0~
,BD68,0,0,0,0,0,0,0)';$S;
    'VSS_BD71':'(0,0,0,0,0,0,0,0,0,0,0,0,0,0,0,0,0,0,0,0,0,0,0,0,0,0,0,0,0,0,0,0~
,BD71,0,0,0,0,0,0,0)';$S;
    'VSS_BD73':'(0,0,0,0,0,0,0,0,0,0,0,0,0,0,0,0,0,0,0,0,0,0,0,0,0,0,0,0,0,0,0,0~
,BD73,0,0,0,0,0,0,0)';$S;
    'VSS_BF3':'(0,0,0,0,0,0,0,0,0,0,0,0,0,0,0,0,0,0,0,0,0,0,0,0,0,0,0,0,0,0,0,0,~
BF3,0,0,0,0,0,0,0)';$S;
    'VSS_BF5':'(0,0,0,0,0,0,0,0,0,0,0,0,0,0,0,0,0,0,0,0,0,0,0,0,0,0,0,0,0,0,0,0,~
BF5,0,0,0,0,0,0,0)';$S;
    'VSS_BF8':'(0,0,0,0,0,0,0,0,0,0,0,0,0,0,0,0,0,0,0,0,0,0,0,0,0,0,0,0,0,0,0,0,~
BF8,0,0,0,0,0,0,0)';$S;
    'VSS_BF10':'(0,0,0,0,0,0,0,0,0,0,0,0,0,0,0,0,0,0,0,0,0,0,0,0,0,0,0,0,0,0,0,0~
,BF10,0,0,0,0,0,0,0)';$S;
    'VSS_BF12':'(0,0,0,0,0,0,0,0,0,0,0,0,0,0,0,0,0,0,0,0,0,0,0,0,0,0,0,0,0,0,0,0~
,BF12,0,0,0,0,0,0,0)';$S;
    'VSS_BF15':'(0,0,0,0,0,0,0,0,0,0,0,0,0,0,0,0,0,0,0,0,0,0,0,0,0,0,0,0,0,0,0,0~
,BF15,0,0,0,0,0,0,0)';$S;
    'VSS_BF17':'(0,0,0,0,0,0,0,0,0,0,0,0,0,0,0,0,0,0,0,0,0,0,0,0,0,0,0,0,0,0,0,0~
,BF17,0,0,0,0,0,0,0)';$S;
    'VSS_BF19':'(0,0,0,0,0,0,0,0,0,0,0,0,0,0,0,0,0,0,0,0,0,0,0,0,0,0,0,0,0,0,0,0~
,BF19,0,0,0,0,0,0,0)';$S;
    'VSS_BF22':'(0,0,0,0,0,0,0,0,0,0,0,0,0,0,0,0,0,0,0,0,0,0,0,0,0,0,0,0,0,0,0,0~
,BF22,0,0,0,0,0,0,0)';$S;
    'VSS_BF24':'(0,0,0,0,0,0,0,0,0,0,0,0,0,0,0,0,0,0,0,0,0,0,0,0,0,0,0,0,0,0,0,0~
,BF24,0,0,0,0,0,0,0)';$S;
    'VSS_BF26':'(0,0,0,0,0,0,0,0,0,0,0,0,0,0,0,0,0,0,0,0,0,0,0,0,0,0,0,0,0,0,0,0~
,BF26,0,0,0,0,0,0,0)';$S;
    'VSS_BF28':'(0,0,0,0,0,0,0,0,0,0,0,0,0,0,0,0,0,0,0,0,0,0,0,0,0,0,0,0,0,0,0,0~
,BF28,0,0,0,0,0,0,0)';$S;
    'VSS_BF49':'(0,0,0,0,0,0,0,0,0,0,0,0,0,0,0,0,0,0,0,0,0,0,0,0,0,0,0,0,0,0,0,0~
,BF49,0,0,0,0,0,0,0)';$S;
    'VSS_BF50':'(0,0,0,0,0,0,0,0,0,0,0,0,0,0,0,0,0,0,0,0,0,0,0,0,0,0,0,0,0,0,0,0~
,BF50,0,0,0,0,0,0,0)';$S;
    'VSS_BF52':'(0,0,0,0,0,0,0,0,0,0,0,0,0,0,0,0,0,0,0,0,0,0,0,0,0,0,0,0,0,0,0,0~
,BF52,0,0,0,0,0,0,0)';$S;
    'VSS_BF54':'(0,0,0,0,0,0,0,0,0,0,0,0,0,0,0,0,0,0,0,0,0,0,0,0,0,0,0,0,0,0,0,0~
,BF54,0,0,0,0,0,0,0)';$S;
    'VSS_BF59':'(0,0,0,0,0,0,0,0,0,0,0,0,0,0,0,0,0,0,0,0,0,0,0,0,0,0,0,0,0,0,0,0~
,BF59,0,0,0,0,0,0,0)';$S;
    'VSS_BF61':'(0,0,0,0,0,0,0,0,0,0,0,0,0,0,0,0,0,0,0,0,0,0,0,0,0,0,0,0,0,0,0,0~
,BF61,0,0,0,0,0,0,0)';$S;
    'VSS_BF66':'(0,0,0,0,0,0,0,0,0,0,0,0,0,0,0,0,0,0,0,0,0,0,0,0,0,0,0,0,0,0,0,0~
,BF66,0,0,0,0,0,0,0)';$S;
    'VSS_BF68':'(0,0,0,0,0,0,0,0,0,0,0,0,0,0,0,0,0,0,0,0,0,0,0,0,0,0,0,0,0,0,0,0~
,BF68,0,0,0,0,0,0,0)';$S;
    'VSS_BF73':'(0,0,0,0,0,0,0,0,0,0,0,0,0,0,0,0,0,0,0,0,0,0,0,0,0,0,0,0,0,0,0,0~
,BF73,0,0,0,0,0,0,0)';$S;
    'VSS_BG1':'(0,0,0,0,0,0,0,0,0,0,0,0,0,0,0,0,0,0,0,0,0,0,0,0,0,0,0,0,0,0,0,0,~
BG1,0,0,0,0,0,0,0)';$S;
    'VSS_BG4':'(0,0,0,0,0,0,0,0,0,0,0,0,0,0,0,0,0,0,0,0,0,0,0,0,0,0,0,0,0,0,0,0,~
BG4,0,0,0,0,0,0,0)';$S;
    'VSS_BG6':'(0,0,0,0,0,0,0,0,0,0,0,0,0,0,0,0,0,0,0,0,0,0,0,0,0,0,0,0,0,0,0,0,~
BG6,0,0,0,0,0,0,0)';$S;
    'VSS_BG8':'(0,0,0,0,0,0,0,0,0,0,0,0,0,0,0,0,0,0,0,0,0,0,0,0,0,0,0,0,0,0,0,0,~
BG8,0,0,0,0,0,0,0)';$S;
    'VSS_BG11':'(0,0,0,0,0,0,0,0,0,0,0,0,0,0,0,0,0,0,0,0,0,0,0,0,0,0,0,0,0,0,0,0~
,BG11,0,0,0,0,0,0,0)';$S;
    'VSS_BG13':'(0,0,0,0,0,0,0,0,0,0,0,0,0,0,0,0,0,0,0,0,0,0,0,0,0,0,0,0,0,0,0,0~
,BG13,0,0,0,0,0,0,0)';$S;
    'VSS_BG15':'(0,0,0,0,0,0,0,0,0,0,0,0,0,0,0,0,0,0,0,0,0,0,0,0,0,0,0,0,0,0,0,0~
,BG15,0,0,0,0,0,0,0)';$S;
    'VSS_BG18':'(0,0,0,0,0,0,0,0,0,0,0,0,0,0,0,0,0,0,0,0,0,0,0,0,0,0,0,0,0,0,0,0~
,BG18,0,0,0,0,0,0,0)';$S;
    'VSS_BG20':'(0,0,0,0,0,0,0,0,0,0,0,0,0,0,0,0,0,0,0,0,0,0,0,0,0,0,0,0,0,0,0,0~
,BG20,0,0,0,0,0,0,0)';$S;
    'VSS_BG23':'(0,0,0,0,0,0,0,0,0,0,0,0,0,0,0,0,0,0,0,0,0,0,0,0,0,0,0,0,0,0,0,0~
,BG23,0,0,0,0,0,0,0)';$S;
    'VSS_BG25':'(0,0,0,0,0,0,0,0,0,0,0,0,0,0,0,0,0,0,0,0,0,0,0,0,0,0,0,0,0,0,0,0~
,BG25,0,0,0,0,0,0,0)';$S;
    'VSS_BG27':'(0,0,0,0,0,0,0,0,0,0,0,0,0,0,0,0,0,0,0,0,0,0,0,0,0,0,0,0,0,0,0,0~
,BG27,0,0,0,0,0,0,0)';$S;
    'VSS_BG49':'(0,0,0,0,0,0,0,0,0,0,0,0,0,0,0,0,0,0,0,0,0,0,0,0,0,0,0,0,0,0,0,0~
,BG49,0,0,0,0,0,0,0)';$S;
    'VSS_BG51':'(0,0,0,0,0,0,0,0,0,0,0,0,0,0,0,0,0,0,0,0,0,0,0,0,0,0,0,0,0,0,0,0~
,BG51,0,0,0,0,0,0,0)';$S;
    'VSS_BG53':'(0,0,0,0,0,0,0,0,0,0,0,0,0,0,0,0,0,0,0,0,0,0,0,0,0,0,0,0,0,0,0,0~
,BG53,0,0,0,0,0,0,0)';$S;
    'VSS_BG56':'(0,0,0,0,0,0,0,0,0,0,0,0,0,0,0,0,0,0,0,0,0,0,0,0,0,0,0,0,0,0,0,0~
,BG56,0,0,0,0,0,0,0)';$S;
    'VSS_BG58':'(0,0,0,0,0,0,0,0,0,0,0,0,0,0,0,0,0,0,0,0,0,0,0,0,0,0,0,0,0,0,0,0~
,BG58,0,0,0,0,0,0,0)';$S;
    'VSS_BG61':'(0,0,0,0,0,0,0,0,0,0,0,0,0,0,0,0,0,0,0,0,0,0,0,0,0,0,0,0,0,0,0,0~
,BG61,0,0,0,0,0,0,0)';$S;
    'VSS_BG63':'(0,0,0,0,0,0,0,0,0,0,0,0,0,0,0,0,0,0,0,0,0,0,0,0,0,0,0,0,0,0,0,0~
,BG63,0,0,0,0,0,0,0)';$S;
    'VSS_BG65':'(0,0,0,0,0,0,0,0,0,0,0,0,0,0,0,0,0,0,0,0,0,0,0,0,0,0,0,0,0,0,0,0~
,BG65,0,0,0,0,0,0,0)';$S;
    'VSS_BG68':'(0,0,0,0,0,0,0,0,0,0,0,0,0,0,0,0,0,0,0,0,0,0,0,0,0,0,0,0,0,0,0,0~
,BG68,0,0,0,0,0,0,0)';$S;
    'VSS_BG70':'(0,0,0,0,0,0,0,0,0,0,0,0,0,0,0,0,0,0,0,0,0,0,0,0,0,0,0,0,0,0,0,0~
,BG70,0,0,0,0,0,0,0)';$S;
    'VSS_BG72':'(0,0,0,0,0,0,0,0,0,0,0,0,0,0,0,0,0,0,0,0,0,0,0,0,0,0,0,0,0,0,0,0~
,BG72,0,0,0,0,0,0,0)';$S;
    'VSS_BG75':'(0,0,0,0,0,0,0,0,0,0,0,0,0,0,0,0,0,0,0,0,0,0,0,0,0,0,0,0,0,0,0,0~
,BG75,0,0,0,0,0,0,0)';$S;
    'VSS_BH3':'(0,0,0,0,0,0,0,0,0,0,0,0,0,0,0,0,0,0,0,0,0,0,0,0,0,0,0,0,0,0,0,0,~
BH3,0,0,0,0,0,0,0)';$S;
    'VSS_BH5':'(0,0,0,0,0,0,0,0,0,0,0,0,0,0,0,0,0,0,0,0,0,0,0,0,0,0,0,0,0,0,0,0,~
BH5,0,0,0,0,0,0,0)';$S;
    'VSS_BH8':'(0,0,0,0,0,0,0,0,0,0,0,0,0,0,0,0,0,0,0,0,0,0,0,0,0,0,0,0,0,0,0,0,~
BH8,0,0,0,0,0,0,0)';$S;
    'VSS_BH10':'(0,0,0,0,0,0,0,0,0,0,0,0,0,0,0,0,0,0,0,0,0,0,0,0,0,0,0,0,0,0,0,0~
,BH10,0,0,0,0,0,0,0)';$S;
    'VSS_BH12':'(0,0,0,0,0,0,0,0,0,0,0,0,0,0,0,0,0,0,0,0,0,0,0,0,0,0,0,0,0,0,0,0~
,BH12,0,0,0,0,0,0,0)';$S;
    'VSS_BH15':'(0,0,0,0,0,0,0,0,0,0,0,0,0,0,0,0,0,0,0,0,0,0,0,0,0,0,0,0,0,0,0,0~
,BH15,0,0,0,0,0,0,0)';$S;
    'VSS_BH17':'(0,0,0,0,0,0,0,0,0,0,0,0,0,0,0,0,0,0,0,0,0,0,0,0,0,0,0,0,0,0,0,0~
,BH17,0,0,0,0,0,0,0)';$S;
    'VSS_BH19':'(0,0,0,0,0,0,0,0,0,0,0,0,0,0,0,0,0,0,0,0,0,0,0,0,0,0,0,0,0,0,0,0~
,BH19,0,0,0,0,0,0,0)';$S;
    'VSS_BH22':'(0,0,0,0,0,0,0,0,0,0,0,0,0,0,0,0,0,0,0,0,0,0,0,0,0,0,0,0,0,0,0,0~
,BH22,0,0,0,0,0,0,0)';$S;
    'VSS_BH24':'(0,0,0,0,0,0,0,0,0,0,0,0,0,0,0,0,0,0,0,0,0,0,0,0,0,0,0,0,0,0,0,0~
,BH24,0,0,0,0,0,0,0)';$S;
    'VSS_BH26':'(0,0,0,0,0,0,0,0,0,0,0,0,0,0,0,0,0,0,0,0,0,0,0,0,0,0,0,0,0,0,0,0~
,BH26,0,0,0,0,0,0,0)';$S;
    'VSS_BH28':'(0,0,0,0,0,0,0,0,0,0,0,0,0,0,0,0,0,0,0,0,0,0,0,0,0,0,0,0,0,0,0,0~
,BH28,0,0,0,0,0,0,0)';$S;
    'VSS_BH49':'(0,0,0,0,0,0,0,0,0,0,0,0,0,0,0,0,0,0,0,0,0,0,0,0,0,0,0,0,0,0,0,0~
,BH49,0,0,0,0,0,0,0)';$S;
    'VSS_BH50':'(0,0,0,0,0,0,0,0,0,0,0,0,0,0,0,0,0,0,0,0,0,0,0,0,0,0,0,0,0,0,0,0~
,BH50,0,0,0,0,0,0,0)';$S;
    'VSS_BH52':'(0,0,0,0,0,0,0,0,0,0,0,0,0,0,0,0,0,0,0,0,0,0,0,0,0,0,0,0,0,0,0,0~
,BH52,0,0,0,0,0,0,0)';$S;
    'VSS_BH54':'(0,0,0,0,0,0,0,0,0,0,0,0,0,0,0,0,0,0,0,0,0,0,0,0,0,0,0,0,0,0,0,0~
,BH54,0,0,0,0,0,0,0)';$S;
    'VSS_BH57':'(0,0,0,0,0,0,0,0,0,0,0,0,0,0,0,0,0,0,0,0,0,0,0,0,0,0,0,0,0,0,0,0~
,BH57,0,0,0,0,0,0,0)';$S;
    'VSS_BH59':'(0,0,0,0,0,0,0,0,0,0,0,0,0,0,0,0,0,0,0,0,0,0,0,0,0,0,0,0,0,0,0,0~
,BH59,0,0,0,0,0,0,0)';$S;
    'VSS_BH61':'(0,0,0,0,0,0,0,0,0,0,0,0,0,0,0,0,0,0,0,0,0,0,0,0,0,0,0,0,0,0,0,0~
,BH61,0,0,0,0,0,0,0)';$S;
    'VSS_BH64':'(0,0,0,0,0,0,0,0,0,0,0,0,0,0,0,0,0,0,0,0,0,0,0,0,0,0,0,0,0,0,0,0~
,BH64,0,0,0,0,0,0,0)';$S;
    'VSS_BH66':'(0,0,0,0,0,0,0,0,0,0,0,0,0,0,0,0,0,0,0,0,0,0,0,0,0,0,0,0,0,0,0,0~
,BH66,0,0,0,0,0,0,0)';$S;
    'VSS_BH68':'(0,0,0,0,0,0,0,0,0,0,0,0,0,0,0,0,0,0,0,0,0,0,0,0,0,0,0,0,0,0,0,0~
,BH68,0,0,0,0,0,0,0)';$S;
    'VSS_BH71':'(0,0,0,0,0,0,0,0,0,0,0,0,0,0,0,0,0,0,0,0,0,0,0,0,0,0,0,0,0,0,0,0~
,BH71,0,0,0,0,0,0,0)';$S;
    'VSS_BH73':'(0,0,0,0,0,0,0,0,0,0,0,0,0,0,0,0,0,0,0,0,0,0,0,0,0,0,0,0,0,0,0,0~
,BH73,0,0,0,0,0,0,0)';$S;
    'VSS_BJ1':'(0,0,0,0,0,0,0,0,0,0,0,0,0,0,0,0,0,0,0,0,0,0,0,0,0,0,0,0,0,0,0,0,~
BJ1,0,0,0,0,0,0,0)';$S;
    'VSS_BJ6':'(0,0,0,0,0,0,0,0,0,0,0,0,0,0,0,0,0,0,0,0,0,0,0,0,0,0,0,0,0,0,0,0,~
BJ6,0,0,0,0,0,0,0)';$S;
    'VSS_BJ8':'(0,0,0,0,0,0,0,0,0,0,0,0,0,0,0,0,0,0,0,0,0,0,0,0,0,0,0,0,0,0,0,0,~
BJ8,0,0,0,0,0,0,0)';$S;
    'VSS_BJ13':'(0,0,0,0,0,0,0,0,0,0,0,0,0,0,0,0,0,0,0,0,0,0,0,0,0,0,0,0,0,0,0,0~
,BJ13,0,0,0,0,0,0,0)';$S;
    'VSS_BJ15':'(0,0,0,0,0,0,0,0,0,0,0,0,0,0,0,0,0,0,0,0,0,0,0,0,0,0,0,0,0,0,0,0~
,BJ15,0,0,0,0,0,0,0)';$S;
    'VSS_BJ20':'(0,0,0,0,0,0,0,0,0,0,0,0,0,0,0,0,0,0,0,0,0,0,0,0,0,0,0,0,0,0,0,0~
,BJ20,0,0,0,0,0,0,0)';$S;
    'VSS_BJ22':'(0,0,0,0,0,0,0,0,0,0,0,0,0,0,0,0,0,0,0,0,0,0,0,0,0,0,0,0,0,0,0,0~
,BJ22,0,0,0,0,0,0,0)';$S;
    'VSS_BJ24':'(0,0,0,0,0,0,0,0,0,0,0,0,0,0,0,0,0,0,0,0,0,0,0,0,0,0,0,0,0,0,0,0~
,BJ24,0,0,0,0,0,0,0)';$S;
    'VSS_BJ26':'(0,0,0,0,0,0,0,0,0,0,0,0,0,0,0,0,0,0,0,0,0,0,0,0,0,0,0,0,0,0,0,0~
,BJ26,0,0,0,0,0,0,0)';$S;
    'VSS_BJ28':'(0,0,0,0,0,0,0,0,0,0,0,0,0,0,0,0,0,0,0,0,0,0,0,0,0,0,0,0,0,0,0,0~
,BJ28,0,0,0,0,0,0,0)';$S;
    'VSS_BJ49':'(0,0,0,0,0,0,0,0,0,0,0,0,0,0,0,0,0,0,0,0,0,0,0,0,0,0,0,0,0,0,0,0~
,BJ49,0,0,0,0,0,0,0)';$S;
    'VSS_BJ51':'(0,0,0,0,0,0,0,0,0,0,0,0,0,0,0,0,0,0,0,0,0,0,0,0,0,0,0,0,0,0,0,0~
,BJ51,0,0,0,0,0,0,0)';$S;
    'VSS_BJ53':'(0,0,0,0,0,0,0,0,0,0,0,0,0,0,0,0,0,0,0,0,0,0,0,0,0,0,0,0,0,0,0,0~
,BJ53,0,0,0,0,0,0,0)';$S;
    'VSS_BJ56':'(0,0,0,0,0,0,0,0,0,0,0,0,0,0,0,0,0,0,0,0,0,0,0,0,0,0,0,0,0,0,0,0~
,BJ56,0,0,0,0,0,0,0)';$S;
    'VSS_BJ61':'(0,0,0,0,0,0,0,0,0,0,0,0,0,0,0,0,0,0,0,0,0,0,0,0,0,0,0,0,0,0,0,0~
,BJ61,0,0,0,0,0,0,0)';$S;
    'VSS_BJ63':'(0,0,0,0,0,0,0,0,0,0,0,0,0,0,0,0,0,0,0,0,0,0,0,0,0,0,0,0,0,0,0,0~
,BJ63,0,0,0,0,0,0,0)';$S;
    'VSS_BJ68':'(0,0,0,0,0,0,0,0,0,0,0,0,0,0,0,0,0,0,0,0,0,0,0,0,0,0,0,0,0,0,0,0~
,BJ68,0,0,0,0,0,0,0)';$S;
    'VSS_BJ70':'(0,0,0,0,0,0,0,0,0,0,0,0,0,0,0,0,0,0,0,0,0,0,0,0,0,0,0,0,0,0,0,0~
,BJ70,0,0,0,0,0,0,0)';$S;
    'VSS_BJ75':'(0,0,0,0,0,0,0,0,0,0,0,0,0,0,0,0,0,0,0,0,0,0,0,0,0,0,0,0,0,0,0,0~
,BJ75,0,0,0,0,0,0,0)';$S;
    'VSS_BK3':'(0,0,0,0,0,0,0,0,0,0,0,0,0,0,0,0,0,0,0,0,0,0,0,0,0,0,0,0,0,0,0,0,~
BK3,0,0,0,0,0,0,0)';$S;
    'VSS_BK5':'(0,0,0,0,0,0,0,0,0,0,0,0,0,0,0,0,0,0,0,0,0,0,0,0,0,0,0,0,0,0,0,0,~
BK5,0,0,0,0,0,0,0)';$S;
    'VSS_BK8':'(0,0,0,0,0,0,0,0,0,0,0,0,0,0,0,0,0,0,0,0,0,0,0,0,0,0,0,0,0,0,0,0,~
BK8,0,0,0,0,0,0,0)';$S;
    'VSS_BK10':'(0,0,0,0,0,0,0,0,0,0,0,0,0,0,0,0,0,0,0,0,0,0,0,0,0,0,0,0,0,0,0,0~
,BK10,0,0,0,0,0,0,0)';$S;
    'VSS_BK12':'(0,0,0,0,0,0,0,0,0,0,0,0,0,0,0,0,0,0,0,0,0,0,0,0,0,0,0,0,0,0,0,0~
,BK12,0,0,0,0,0,0,0)';$S;
    'VSS_BK15':'(0,0,0,0,0,0,0,0,0,0,0,0,0,0,0,0,0,0,0,0,0,0,0,0,0,0,0,0,0,0,0,0~
,BK15,0,0,0,0,0,0,0)';$S;
    'VSS_BK17':'(0,0,0,0,0,0,0,0,0,0,0,0,0,0,0,0,0,0,0,0,0,0,0,0,0,0,0,0,0,0,0,0~
,BK17,0,0,0,0,0,0,0)';$S;
    'VSS_BK19':'(0,0,0,0,0,0,0,0,0,0,0,0,0,0,0,0,0,0,0,0,0,0,0,0,0,0,0,0,0,0,0,0~
,BK19,0,0,0,0,0,0,0)';$S;
    'VSS_BK23':'(0,0,0,0,0,0,0,0,0,0,0,0,0,0,0,0,0,0,0,0,0,0,0,0,0,0,0,0,0,0,0,0~
,BK23,0,0,0,0,0,0,0)';$S;
    'VSS_BK25':'(0,0,0,0,0,0,0,0,0,0,0,0,0,0,0,0,0,0,0,0,0,0,0,0,0,0,0,0,0,0,0,0~
,BK25,0,0,0,0,0,0,0)';$S;
    'VSS_BK27':'(0,0,0,0,0,0,0,0,0,0,0,0,0,0,0,0,0,0,0,0,0,0,0,0,0,0,0,0,0,0,0,0~
,BK27,0,0,0,0,0,0,0)';$S;
    'VSS_BK48':'(0,0,0,0,0,0,0,0,0,0,0,0,0,0,0,0,0,0,0,0,0,0,0,0,0,0,0,0,0,0,0,0~
,BK48,0,0,0,0,0,0,0)';$S;
    'VSS_BK50':'(0,0,0,0,0,0,0,0,0,0,0,0,0,0,0,0,0,0,0,0,0,0,0,0,0,0,0,0,0,0,0,0~
,BK50,0,0,0,0,0,0,0)';$S;
    'VSS_BK52':'(0,0,0,0,0,0,0,0,0,0,0,0,0,0,0,0,0,0,0,0,0,0,0,0,0,0,0,0,0,0,0,0~
,BK52,0,0,0,0,0,0,0)';$S;
    'VSS_BK54':'(0,0,0,0,0,0,0,0,0,0,0,0,0,0,0,0,0,0,0,0,0,0,0,0,0,0,0,0,0,0,0,0~
,BK54,0,0,0,0,0,0,0)';$S;
    'VSS_BK57':'(0,0,0,0,0,0,0,0,0,0,0,0,0,0,0,0,0,0,0,0,0,0,0,0,0,0,0,0,0,0,0,0~
,BK57,0,0,0,0,0,0,0)';$S;
    'VSS_BK59':'(0,0,0,0,0,0,0,0,0,0,0,0,0,0,0,0,0,0,0,0,0,0,0,0,0,0,0,0,0,0,0,0~
,BK59,0,0,0,0,0,0,0)';$S;
    'VSS_BK61':'(0,0,0,0,0,0,0,0,0,0,0,0,0,0,0,0,0,0,0,0,0,0,0,0,0,0,0,0,0,0,0,0~
,BK61,0,0,0,0,0,0,0)';$S;
    'VSS_BK64':'(0,0,0,0,0,0,0,0,0,0,0,0,0,0,0,0,0,0,0,0,0,0,0,0,0,0,0,0,0,0,0,0~
,BK64,0,0,0,0,0,0,0)';$S;
    'VSS_BK66':'(0,0,0,0,0,0,0,0,0,0,0,0,0,0,0,0,0,0,0,0,0,0,0,0,0,0,0,0,0,0,0,0~
,BK66,0,0,0,0,0,0,0)';$S;
    'VSS_BK68':'(0,0,0,0,0,0,0,0,0,0,0,0,0,0,0,0,0,0,0,0,0,0,0,0,0,0,0,0,0,0,0,0~
,BK68,0,0,0,0,0,0,0)';$S;
    'VSS_BK71':'(0,0,0,0,0,0,0,0,0,0,0,0,0,0,0,0,0,0,0,0,0,0,0,0,0,0,0,0,0,0,0,0~
,BK71,0,0,0,0,0,0,0)';$S;
    'VSS_BK73':'(0,0,0,0,0,0,0,0,0,0,0,0,0,0,0,0,0,0,0,0,0,0,0,0,0,0,0,0,0,0,0,0~
,BK73,0,0,0,0,0,0,0)';$S;
    'VSS_BL1':'(0,0,0,0,0,0,0,0,0,0,0,0,0,0,0,0,0,0,0,0,0,0,0,0,0,0,0,0,0,0,0,0,~
BL1,0,0,0,0,0,0,0)';$S;
    'VSS_BL4':'(0,0,0,0,0,0,0,0,0,0,0,0,0,0,0,0,0,0,0,0,0,0,0,0,0,0,0,0,0,0,0,0,~
BL4,0,0,0,0,0,0,0)';$S;
    'VSS_BL6':'(0,0,0,0,0,0,0,0,0,0,0,0,0,0,0,0,0,0,0,0,0,0,0,0,0,0,0,0,0,0,0,0,~
BL6,0,0,0,0,0,0,0)';$S;
    'VSS_BL8':'(0,0,0,0,0,0,0,0,0,0,0,0,0,0,0,0,0,0,0,0,0,0,0,0,0,0,0,0,0,0,0,0,~
BL8,0,0,0,0,0,0,0)';$S;
    'VSS_BL11':'(0,0,0,0,0,0,0,0,0,0,0,0,0,0,0,0,0,0,0,0,0,0,0,0,0,0,0,0,0,0,0,0~
,BL11,0,0,0,0,0,0,0)';$S;
    'VSS_BL13':'(0,0,0,0,0,0,0,0,0,0,0,0,0,0,0,0,0,0,0,0,0,0,0,0,0,0,0,0,0,0,0,0~
,BL13,0,0,0,0,0,0,0)';$S;
    'VSS_BL15':'(0,0,0,0,0,0,0,0,0,0,0,0,0,0,0,0,0,0,0,0,0,0,0,0,0,0,0,0,0,0,0,0~
,BL15,0,0,0,0,0,0,0)';$S;
    'VSS_BL18':'(0,0,0,0,0,0,0,0,0,0,0,0,0,0,0,0,0,0,0,0,0,0,0,0,0,0,0,0,0,0,0,0~
,BL18,0,0,0,0,0,0,0)';$S;
    'VSS_BL20':'(0,0,0,0,0,0,0,0,0,0,0,0,0,0,0,0,0,0,0,0,0,0,0,0,0,0,0,0,0,0,0,0~
,BL20,0,0,0,0,0,0,0)';$S;
    'VSS_BL22':'(0,0,0,0,0,0,0,0,0,0,0,0,0,0,0,0,0,0,0,0,0,0,0,0,0,0,0,0,0,0,0,0~
,BL22,0,0,0,0,0,0,0)';$S;
    'VSS_BL24':'(0,0,0,0,0,0,0,0,0,0,0,0,0,0,0,0,0,0,0,0,0,0,0,0,0,0,0,0,0,0,0,0~
,BL24,0,0,0,0,0,0,0)';$S;
    'VSS_BV37':'(0,0,0,0,0,0,0,0,0,0,0,0,0,0,0,0,0,0,0,0,0,0,0,0,0,0,0,0,0,0,0,0~
,0,BV37,0,0,0,0,0,0)';$S;
    'VSS_BL26':'(0,0,0,0,0,0,0,0,0,0,0,0,0,0,0,0,0,0,0,0,0,0,0,0,0,0,0,0,0,0,0,0~
,0,BL26,0,0,0,0,0,0)';$S;
    'VSS_BL28':'(0,0,0,0,0,0,0,0,0,0,0,0,0,0,0,0,0,0,0,0,0,0,0,0,0,0,0,0,0,0,0,0~
,0,BL28,0,0,0,0,0,0)';$S;
    'VSS_BL49':'(0,0,0,0,0,0,0,0,0,0,0,0,0,0,0,0,0,0,0,0,0,0,0,0,0,0,0,0,0,0,0,0~
,0,BL49,0,0,0,0,0,0)';$S;
    'VSS_BL51':'(0,0,0,0,0,0,0,0,0,0,0,0,0,0,0,0,0,0,0,0,0,0,0,0,0,0,0,0,0,0,0,0~
,0,BL51,0,0,0,0,0,0)';$S;
    'VSS_BL53':'(0,0,0,0,0,0,0,0,0,0,0,0,0,0,0,0,0,0,0,0,0,0,0,0,0,0,0,0,0,0,0,0~
,0,BL53,0,0,0,0,0,0)';$S;
    'VSS_BL56':'(0,0,0,0,0,0,0,0,0,0,0,0,0,0,0,0,0,0,0,0,0,0,0,0,0,0,0,0,0,0,0,0~
,0,BL56,0,0,0,0,0,0)';$S;
    'VSS_BL58':'(0,0,0,0,0,0,0,0,0,0,0,0,0,0,0,0,0,0,0,0,0,0,0,0,0,0,0,0,0,0,0,0~
,0,BL58,0,0,0,0,0,0)';$S;
    'VSS_BL61':'(0,0,0,0,0,0,0,0,0,0,0,0,0,0,0,0,0,0,0,0,0,0,0,0,0,0,0,0,0,0,0,0~
,0,BL61,0,0,0,0,0,0)';$S;
    'VSS_BL63':'(0,0,0,0,0,0,0,0,0,0,0,0,0,0,0,0,0,0,0,0,0,0,0,0,0,0,0,0,0,0,0,0~
,0,BL63,0,0,0,0,0,0)';$S;
    'VSS_BL65':'(0,0,0,0,0,0,0,0,0,0,0,0,0,0,0,0,0,0,0,0,0,0,0,0,0,0,0,0,0,0,0,0~
,0,BL65,0,0,0,0,0,0)';$S;
    'VSS_BL68':'(0,0,0,0,0,0,0,0,0,0,0,0,0,0,0,0,0,0,0,0,0,0,0,0,0,0,0,0,0,0,0,0~
,0,BL68,0,0,0,0,0,0)';$S;
    'VSS_BL70':'(0,0,0,0,0,0,0,0,0,0,0,0,0,0,0,0,0,0,0,0,0,0,0,0,0,0,0,0,0,0,0,0~
,0,BL70,0,0,0,0,0,0)';$S;
    'VSS_BL72':'(0,0,0,0,0,0,0,0,0,0,0,0,0,0,0,0,0,0,0,0,0,0,0,0,0,0,0,0,0,0,0,0~
,0,BL72,0,0,0,0,0,0)';$S;
    'VSS_BL75':'(0,0,0,0,0,0,0,0,0,0,0,0,0,0,0,0,0,0,0,0,0,0,0,0,0,0,0,0,0,0,0,0~
,0,BL75,0,0,0,0,0,0)';$S;
    'VSS_BM3':'(0,0,0,0,0,0,0,0,0,0,0,0,0,0,0,0,0,0,0,0,0,0,0,0,0,0,0,0,0,0,0,0,~
0,BM3,0,0,0,0,0,0)';$S;
    'VSS_BM8':'(0,0,0,0,0,0,0,0,0,0,0,0,0,0,0,0,0,0,0,0,0,0,0,0,0,0,0,0,0,0,0,0,~
0,BM8,0,0,0,0,0,0)';$S;
    'VSS_BM10':'(0,0,0,0,0,0,0,0,0,0,0,0,0,0,0,0,0,0,0,0,0,0,0,0,0,0,0,0,0,0,0,0~
,0,BM10,0,0,0,0,0,0)';$S;
    'VSS_BM15':'(0,0,0,0,0,0,0,0,0,0,0,0,0,0,0,0,0,0,0,0,0,0,0,0,0,0,0,0,0,0,0,0~
,0,BM15,0,0,0,0,0,0)';$S;
    'VSS_BM17':'(0,0,0,0,0,0,0,0,0,0,0,0,0,0,0,0,0,0,0,0,0,0,0,0,0,0,0,0,0,0,0,0~
,0,BM17,0,0,0,0,0,0)';$S;
    'VSS_BM23':'(0,0,0,0,0,0,0,0,0,0,0,0,0,0,0,0,0,0,0,0,0,0,0,0,0,0,0,0,0,0,0,0~
,0,BM23,0,0,0,0,0,0)';$S;
    'VSS_BM25':'(0,0,0,0,0,0,0,0,0,0,0,0,0,0,0,0,0,0,0,0,0,0,0,0,0,0,0,0,0,0,0,0~
,0,BM25,0,0,0,0,0,0)';$S;
    'VSS_BM27':'(0,0,0,0,0,0,0,0,0,0,0,0,0,0,0,0,0,0,0,0,0,0,0,0,0,0,0,0,0,0,0,0~
,0,BM27,0,0,0,0,0,0)';$S;
    'VSS_BM29':'(0,0,0,0,0,0,0,0,0,0,0,0,0,0,0,0,0,0,0,0,0,0,0,0,0,0,0,0,0,0,0,0~
,0,BM29,0,0,0,0,0,0)';$S;
    'VSS_BM31':'(0,0,0,0,0,0,0,0,0,0,0,0,0,0,0,0,0,0,0,0,0,0,0,0,0,0,0,0,0,0,0,0~
,0,BM31,0,0,0,0,0,0)';$S;
    'VSS_BM33':'(0,0,0,0,0,0,0,0,0,0,0,0,0,0,0,0,0,0,0,0,0,0,0,0,0,0,0,0,0,0,0,0~
,0,BM33,0,0,0,0,0,0)';$S;
    'VSS_BM35':'(0,0,0,0,0,0,0,0,0,0,0,0,0,0,0,0,0,0,0,0,0,0,0,0,0,0,0,0,0,0,0,0~
,0,BM35,0,0,0,0,0,0)';$S;
    'VSS_BM37':'(0,0,0,0,0,0,0,0,0,0,0,0,0,0,0,0,0,0,0,0,0,0,0,0,0,0,0,0,0,0,0,0~
,0,BM37,0,0,0,0,0,0)';$S;
    'VSS_BM40':'(0,0,0,0,0,0,0,0,0,0,0,0,0,0,0,0,0,0,0,0,0,0,0,0,0,0,0,0,0,0,0,0~
,0,BM40,0,0,0,0,0,0)';$S;
    'VSS_BM42':'(0,0,0,0,0,0,0,0,0,0,0,0,0,0,0,0,0,0,0,0,0,0,0,0,0,0,0,0,0,0,0,0~
,0,BM42,0,0,0,0,0,0)';$S;
    'VSS_BM44':'(0,0,0,0,0,0,0,0,0,0,0,0,0,0,0,0,0,0,0,0,0,0,0,0,0,0,0,0,0,0,0,0~
,0,BM44,0,0,0,0,0,0)';$S;
    'VSS_BM46':'(0,0,0,0,0,0,0,0,0,0,0,0,0,0,0,0,0,0,0,0,0,0,0,0,0,0,0,0,0,0,0,0~
,0,BM46,0,0,0,0,0,0)';$S;
    'VSS_BM48':'(0,0,0,0,0,0,0,0,0,0,0,0,0,0,0,0,0,0,0,0,0,0,0,0,0,0,0,0,0,0,0,0~
,0,BM48,0,0,0,0,0,0)';$S;
    'VSS_BM50':'(0,0,0,0,0,0,0,0,0,0,0,0,0,0,0,0,0,0,0,0,0,0,0,0,0,0,0,0,0,0,0,0~
,0,BM50,0,0,0,0,0,0)';$S;
    'VSS_BM52':'(0,0,0,0,0,0,0,0,0,0,0,0,0,0,0,0,0,0,0,0,0,0,0,0,0,0,0,0,0,0,0,0~
,0,BM52,0,0,0,0,0,0)';$S;
    'VSS_BM54':'(0,0,0,0,0,0,0,0,0,0,0,0,0,0,0,0,0,0,0,0,0,0,0,0,0,0,0,0,0,0,0,0~
,0,BM54,0,0,0,0,0,0)';$S;
    'VSS_BM59':'(0,0,0,0,0,0,0,0,0,0,0,0,0,0,0,0,0,0,0,0,0,0,0,0,0,0,0,0,0,0,0,0~
,0,BM59,0,0,0,0,0,0)';$S;
    'VSS_BM61':'(0,0,0,0,0,0,0,0,0,0,0,0,0,0,0,0,0,0,0,0,0,0,0,0,0,0,0,0,0,0,0,0~
,0,BM61,0,0,0,0,0,0)';$S;
    'VSS_BM66':'(0,0,0,0,0,0,0,0,0,0,0,0,0,0,0,0,0,0,0,0,0,0,0,0,0,0,0,0,0,0,0,0~
,0,BM66,0,0,0,0,0,0)';$S;
    'VSS_BM68':'(0,0,0,0,0,0,0,0,0,0,0,0,0,0,0,0,0,0,0,0,0,0,0,0,0,0,0,0,0,0,0,0~
,0,BM68,0,0,0,0,0,0)';$S;
    'VSS_BM73':'(0,0,0,0,0,0,0,0,0,0,0,0,0,0,0,0,0,0,0,0,0,0,0,0,0,0,0,0,0,0,0,0~
,0,BM73,0,0,0,0,0,0)';$S;
    'VSS_BN1':'(0,0,0,0,0,0,0,0,0,0,0,0,0,0,0,0,0,0,0,0,0,0,0,0,0,0,0,0,0,0,0,0,~
0,BN1,0,0,0,0,0,0)';$S;
    'VSS_BN4':'(0,0,0,0,0,0,0,0,0,0,0,0,0,0,0,0,0,0,0,0,0,0,0,0,0,0,0,0,0,0,0,0,~
0,BN4,0,0,0,0,0,0)';$S;
    'VSS_BN6':'(0,0,0,0,0,0,0,0,0,0,0,0,0,0,0,0,0,0,0,0,0,0,0,0,0,0,0,0,0,0,0,0,~
0,BN6,0,0,0,0,0,0)';$S;
    'VSS_BN8':'(0,0,0,0,0,0,0,0,0,0,0,0,0,0,0,0,0,0,0,0,0,0,0,0,0,0,0,0,0,0,0,0,~
0,BN8,0,0,0,0,0,0)';$S;
    'VSS_BN11':'(0,0,0,0,0,0,0,0,0,0,0,0,0,0,0,0,0,0,0,0,0,0,0,0,0,0,0,0,0,0,0,0~
,0,BN11,0,0,0,0,0,0)';$S;
    'VSS_BN13':'(0,0,0,0,0,0,0,0,0,0,0,0,0,0,0,0,0,0,0,0,0,0,0,0,0,0,0,0,0,0,0,0~
,0,BN13,0,0,0,0,0,0)';$S;
    'VSS_BN15':'(0,0,0,0,0,0,0,0,0,0,0,0,0,0,0,0,0,0,0,0,0,0,0,0,0,0,0,0,0,0,0,0~
,0,BN15,0,0,0,0,0,0)';$S;
    'VSS_BN18':'(0,0,0,0,0,0,0,0,0,0,0,0,0,0,0,0,0,0,0,0,0,0,0,0,0,0,0,0,0,0,0,0~
,0,BN18,0,0,0,0,0,0)';$S;
    'VSS_BN20':'(0,0,0,0,0,0,0,0,0,0,0,0,0,0,0,0,0,0,0,0,0,0,0,0,0,0,0,0,0,0,0,0~
,0,BN20,0,0,0,0,0,0)';$S;
    'VSS_BN22':'(0,0,0,0,0,0,0,0,0,0,0,0,0,0,0,0,0,0,0,0,0,0,0,0,0,0,0,0,0,0,0,0~
,0,BN22,0,0,0,0,0,0)';$S;
    'VSS_BN24':'(0,0,0,0,0,0,0,0,0,0,0,0,0,0,0,0,0,0,0,0,0,0,0,0,0,0,0,0,0,0,0,0~
,0,BN24,0,0,0,0,0,0)';$S;
    'VSS_BN26':'(0,0,0,0,0,0,0,0,0,0,0,0,0,0,0,0,0,0,0,0,0,0,0,0,0,0,0,0,0,0,0,0~
,0,BN26,0,0,0,0,0,0)';$S;
    'VSS_BN28':'(0,0,0,0,0,0,0,0,0,0,0,0,0,0,0,0,0,0,0,0,0,0,0,0,0,0,0,0,0,0,0,0~
,0,BN28,0,0,0,0,0,0)';$S;
    'VSS_BN30':'(0,0,0,0,0,0,0,0,0,0,0,0,0,0,0,0,0,0,0,0,0,0,0,0,0,0,0,0,0,0,0,0~
,0,BN30,0,0,0,0,0,0)';$S;
    'VSS_BN32':'(0,0,0,0,0,0,0,0,0,0,0,0,0,0,0,0,0,0,0,0,0,0,0,0,0,0,0,0,0,0,0,0~
,0,BN32,0,0,0,0,0,0)';$S;
    'VSS_BN34':'(0,0,0,0,0,0,0,0,0,0,0,0,0,0,0,0,0,0,0,0,0,0,0,0,0,0,0,0,0,0,0,0~
,0,BN34,0,0,0,0,0,0)';$S;
    'VSS_BN36':'(0,0,0,0,0,0,0,0,0,0,0,0,0,0,0,0,0,0,0,0,0,0,0,0,0,0,0,0,0,0,0,0~
,0,BN36,0,0,0,0,0,0)';$S;
    'VSS_BN41':'(0,0,0,0,0,0,0,0,0,0,0,0,0,0,0,0,0,0,0,0,0,0,0,0,0,0,0,0,0,0,0,0~
,0,BN41,0,0,0,0,0,0)';$S;
    'VSS_BN43':'(0,0,0,0,0,0,0,0,0,0,0,0,0,0,0,0,0,0,0,0,0,0,0,0,0,0,0,0,0,0,0,0~
,0,BN43,0,0,0,0,0,0)';$S;
    'VSS_BN45':'(0,0,0,0,0,0,0,0,0,0,0,0,0,0,0,0,0,0,0,0,0,0,0,0,0,0,0,0,0,0,0,0~
,0,BN45,0,0,0,0,0,0)';$S;
    'VSS_BN47':'(0,0,0,0,0,0,0,0,0,0,0,0,0,0,0,0,0,0,0,0,0,0,0,0,0,0,0,0,0,0,0,0~
,0,BN47,0,0,0,0,0,0)';$S;
    'VSS_BN49':'(0,0,0,0,0,0,0,0,0,0,0,0,0,0,0,0,0,0,0,0,0,0,0,0,0,0,0,0,0,0,0,0~
,0,BN49,0,0,0,0,0,0)';$S;
    'VSS_BN51':'(0,0,0,0,0,0,0,0,0,0,0,0,0,0,0,0,0,0,0,0,0,0,0,0,0,0,0,0,0,0,0,0~
,0,BN51,0,0,0,0,0,0)';$S;
    'VSS_BN53':'(0,0,0,0,0,0,0,0,0,0,0,0,0,0,0,0,0,0,0,0,0,0,0,0,0,0,0,0,0,0,0,0~
,0,BN53,0,0,0,0,0,0)';$S;
    'VSS_BN56':'(0,0,0,0,0,0,0,0,0,0,0,0,0,0,0,0,0,0,0,0,0,0,0,0,0,0,0,0,0,0,0,0~
,0,BN56,0,0,0,0,0,0)';$S;
    'VSS_BN58':'(0,0,0,0,0,0,0,0,0,0,0,0,0,0,0,0,0,0,0,0,0,0,0,0,0,0,0,0,0,0,0,0~
,0,BN58,0,0,0,0,0,0)';$S;
    'VSS_BN61':'(0,0,0,0,0,0,0,0,0,0,0,0,0,0,0,0,0,0,0,0,0,0,0,0,0,0,0,0,0,0,0,0~
,0,BN61,0,0,0,0,0,0)';$S;
    'VSS_BN63':'(0,0,0,0,0,0,0,0,0,0,0,0,0,0,0,0,0,0,0,0,0,0,0,0,0,0,0,0,0,0,0,0~
,0,BN63,0,0,0,0,0,0)';$S;
    'VSS_BN65':'(0,0,0,0,0,0,0,0,0,0,0,0,0,0,0,0,0,0,0,0,0,0,0,0,0,0,0,0,0,0,0,0~
,0,BN65,0,0,0,0,0,0)';$S;
    'VSS_BN68':'(0,0,0,0,0,0,0,0,0,0,0,0,0,0,0,0,0,0,0,0,0,0,0,0,0,0,0,0,0,0,0,0~
,0,BN68,0,0,0,0,0,0)';$S;
    'VSS_BN70':'(0,0,0,0,0,0,0,0,0,0,0,0,0,0,0,0,0,0,0,0,0,0,0,0,0,0,0,0,0,0,0,0~
,0,BN70,0,0,0,0,0,0)';$S;
    'VSS_BN72':'(0,0,0,0,0,0,0,0,0,0,0,0,0,0,0,0,0,0,0,0,0,0,0,0,0,0,0,0,0,0,0,0~
,0,BN72,0,0,0,0,0,0)';$S;
    'VSS_BN75':'(0,0,0,0,0,0,0,0,0,0,0,0,0,0,0,0,0,0,0,0,0,0,0,0,0,0,0,0,0,0,0,0~
,0,BN75,0,0,0,0,0,0)';$S;
    'VSS_BP3':'(0,0,0,0,0,0,0,0,0,0,0,0,0,0,0,0,0,0,0,0,0,0,0,0,0,0,0,0,0,0,0,0,~
0,BP3,0,0,0,0,0,0)';$S;
    'VSS_BP5':'(0,0,0,0,0,0,0,0,0,0,0,0,0,0,0,0,0,0,0,0,0,0,0,0,0,0,0,0,0,0,0,0,~
0,BP5,0,0,0,0,0,0)';$S;
    'VSS_BP8':'(0,0,0,0,0,0,0,0,0,0,0,0,0,0,0,0,0,0,0,0,0,0,0,0,0,0,0,0,0,0,0,0,~
0,BP8,0,0,0,0,0,0)';$S;
    'VSS_BP10':'(0,0,0,0,0,0,0,0,0,0,0,0,0,0,0,0,0,0,0,0,0,0,0,0,0,0,0,0,0,0,0,0~
,0,BP10,0,0,0,0,0,0)';$S;
    'VSS_BP12':'(0,0,0,0,0,0,0,0,0,0,0,0,0,0,0,0,0,0,0,0,0,0,0,0,0,0,0,0,0,0,0,0~
,0,BP12,0,0,0,0,0,0)';$S;
    'VSS_BP15':'(0,0,0,0,0,0,0,0,0,0,0,0,0,0,0,0,0,0,0,0,0,0,0,0,0,0,0,0,0,0,0,0~
,0,BP15,0,0,0,0,0,0)';$S;
    'VSS_BP17':'(0,0,0,0,0,0,0,0,0,0,0,0,0,0,0,0,0,0,0,0,0,0,0,0,0,0,0,0,0,0,0,0~
,0,BP17,0,0,0,0,0,0)';$S;
    'VSS_BP19':'(0,0,0,0,0,0,0,0,0,0,0,0,0,0,0,0,0,0,0,0,0,0,0,0,0,0,0,0,0,0,0,0~
,0,BP19,0,0,0,0,0,0)';$S;
    'VSS_BP23':'(0,0,0,0,0,0,0,0,0,0,0,0,0,0,0,0,0,0,0,0,0,0,0,0,0,0,0,0,0,0,0,0~
,0,BP23,0,0,0,0,0,0)';$S;
    'VSS_BP25':'(0,0,0,0,0,0,0,0,0,0,0,0,0,0,0,0,0,0,0,0,0,0,0,0,0,0,0,0,0,0,0,0~
,0,BP25,0,0,0,0,0,0)';$S;
    'VSS_BP27':'(0,0,0,0,0,0,0,0,0,0,0,0,0,0,0,0,0,0,0,0,0,0,0,0,0,0,0,0,0,0,0,0~
,0,BP27,0,0,0,0,0,0)';$S;
    'VSS_BP29':'(0,0,0,0,0,0,0,0,0,0,0,0,0,0,0,0,0,0,0,0,0,0,0,0,0,0,0,0,0,0,0,0~
,0,BP29,0,0,0,0,0,0)';$S;
    'VSS_BP31':'(0,0,0,0,0,0,0,0,0,0,0,0,0,0,0,0,0,0,0,0,0,0,0,0,0,0,0,0,0,0,0,0~
,0,BP31,0,0,0,0,0,0)';$S;
    'VSS_BP33':'(0,0,0,0,0,0,0,0,0,0,0,0,0,0,0,0,0,0,0,0,0,0,0,0,0,0,0,0,0,0,0,0~
,0,BP33,0,0,0,0,0,0)';$S;
    'VSS_BP35':'(0,0,0,0,0,0,0,0,0,0,0,0,0,0,0,0,0,0,0,0,0,0,0,0,0,0,0,0,0,0,0,0~
,0,BP35,0,0,0,0,0,0)';$S;
    'VSS_BP37':'(0,0,0,0,0,0,0,0,0,0,0,0,0,0,0,0,0,0,0,0,0,0,0,0,0,0,0,0,0,0,0,0~
,0,BP37,0,0,0,0,0,0)';$S;
    'VSS_BP40':'(0,0,0,0,0,0,0,0,0,0,0,0,0,0,0,0,0,0,0,0,0,0,0,0,0,0,0,0,0,0,0,0~
,0,BP40,0,0,0,0,0,0)';$S;
    'VSS_BP42':'(0,0,0,0,0,0,0,0,0,0,0,0,0,0,0,0,0,0,0,0,0,0,0,0,0,0,0,0,0,0,0,0~
,0,BP42,0,0,0,0,0,0)';$S;
    'VSS_BP44':'(0,0,0,0,0,0,0,0,0,0,0,0,0,0,0,0,0,0,0,0,0,0,0,0,0,0,0,0,0,0,0,0~
,0,BP44,0,0,0,0,0,0)';$S;
    'VSS_BP46':'(0,0,0,0,0,0,0,0,0,0,0,0,0,0,0,0,0,0,0,0,0,0,0,0,0,0,0,0,0,0,0,0~
,0,BP46,0,0,0,0,0,0)';$S;
    'VSS_BP48':'(0,0,0,0,0,0,0,0,0,0,0,0,0,0,0,0,0,0,0,0,0,0,0,0,0,0,0,0,0,0,0,0~
,0,BP48,0,0,0,0,0,0)';$S;
    'VSS_BP50':'(0,0,0,0,0,0,0,0,0,0,0,0,0,0,0,0,0,0,0,0,0,0,0,0,0,0,0,0,0,0,0,0~
,0,BP50,0,0,0,0,0,0)';$S;
    'VSS_BP52':'(0,0,0,0,0,0,0,0,0,0,0,0,0,0,0,0,0,0,0,0,0,0,0,0,0,0,0,0,0,0,0,0~
,0,BP52,0,0,0,0,0,0)';$S;
    'VSS_BP54':'(0,0,0,0,0,0,0,0,0,0,0,0,0,0,0,0,0,0,0,0,0,0,0,0,0,0,0,0,0,0,0,0~
,0,BP54,0,0,0,0,0,0)';$S;
    'VSS_BP57':'(0,0,0,0,0,0,0,0,0,0,0,0,0,0,0,0,0,0,0,0,0,0,0,0,0,0,0,0,0,0,0,0~
,0,BP57,0,0,0,0,0,0)';$S;
    'VSS_BP59':'(0,0,0,0,0,0,0,0,0,0,0,0,0,0,0,0,0,0,0,0,0,0,0,0,0,0,0,0,0,0,0,0~
,0,BP59,0,0,0,0,0,0)';$S;
    'VSS_BP61':'(0,0,0,0,0,0,0,0,0,0,0,0,0,0,0,0,0,0,0,0,0,0,0,0,0,0,0,0,0,0,0,0~
,0,BP61,0,0,0,0,0,0)';$S;
    'VSS_BP64':'(0,0,0,0,0,0,0,0,0,0,0,0,0,0,0,0,0,0,0,0,0,0,0,0,0,0,0,0,0,0,0,0~
,0,BP64,0,0,0,0,0,0)';$S;
    'VSS_BP66':'(0,0,0,0,0,0,0,0,0,0,0,0,0,0,0,0,0,0,0,0,0,0,0,0,0,0,0,0,0,0,0,0~
,0,BP66,0,0,0,0,0,0)';$S;
    'VSS_BP68':'(0,0,0,0,0,0,0,0,0,0,0,0,0,0,0,0,0,0,0,0,0,0,0,0,0,0,0,0,0,0,0,0~
,0,BP68,0,0,0,0,0,0)';$S;
    'VSS_BP71':'(0,0,0,0,0,0,0,0,0,0,0,0,0,0,0,0,0,0,0,0,0,0,0,0,0,0,0,0,0,0,0,0~
,0,BP71,0,0,0,0,0,0)';$S;
    'VSS_BP73':'(0,0,0,0,0,0,0,0,0,0,0,0,0,0,0,0,0,0,0,0,0,0,0,0,0,0,0,0,0,0,0,0~
,0,BP73,0,0,0,0,0,0)';$S;
    'VSS_BR1':'(0,0,0,0,0,0,0,0,0,0,0,0,0,0,0,0,0,0,0,0,0,0,0,0,0,0,0,0,0,0,0,0,~
0,BR1,0,0,0,0,0,0)';$S;
    'VSS_BR3':'(0,0,0,0,0,0,0,0,0,0,0,0,0,0,0,0,0,0,0,0,0,0,0,0,0,0,0,0,0,0,0,0,~
0,BR3,0,0,0,0,0,0)';$S;
    'VSS_BR6':'(0,0,0,0,0,0,0,0,0,0,0,0,0,0,0,0,0,0,0,0,0,0,0,0,0,0,0,0,0,0,0,0,~
0,BR6,0,0,0,0,0,0)';$S;
    'VSS_BR7':'(0,0,0,0,0,0,0,0,0,0,0,0,0,0,0,0,0,0,0,0,0,0,0,0,0,0,0,0,0,0,0,0,~
0,BR7,0,0,0,0,0,0)';$S;
    'VSS_BR8':'(0,0,0,0,0,0,0,0,0,0,0,0,0,0,0,0,0,0,0,0,0,0,0,0,0,0,0,0,0,0,0,0,~
0,BR8,0,0,0,0,0,0)';$S;
    'VSS_BR10':'(0,0,0,0,0,0,0,0,0,0,0,0,0,0,0,0,0,0,0,0,0,0,0,0,0,0,0,0,0,0,0,0~
,0,BR10,0,0,0,0,0,0)';$S;
    'VSS_BR13':'(0,0,0,0,0,0,0,0,0,0,0,0,0,0,0,0,0,0,0,0,0,0,0,0,0,0,0,0,0,0,0,0~
,0,BR13,0,0,0,0,0,0)';$S;
    'VSS_BR14':'(0,0,0,0,0,0,0,0,0,0,0,0,0,0,0,0,0,0,0,0,0,0,0,0,0,0,0,0,0,0,0,0~
,0,BR14,0,0,0,0,0,0)';$S;
    'VSS_BR15':'(0,0,0,0,0,0,0,0,0,0,0,0,0,0,0,0,0,0,0,0,0,0,0,0,0,0,0,0,0,0,0,0~
,0,BR15,0,0,0,0,0,0)';$S;
    'VSS_BR17':'(0,0,0,0,0,0,0,0,0,0,0,0,0,0,0,0,0,0,0,0,0,0,0,0,0,0,0,0,0,0,0,0~
,0,BR17,0,0,0,0,0,0)';$S;
    'VSS_BR20':'(0,0,0,0,0,0,0,0,0,0,0,0,0,0,0,0,0,0,0,0,0,0,0,0,0,0,0,0,0,0,0,0~
,0,BR20,0,0,0,0,0,0)';$S;
    'VSS_BR21':'(0,0,0,0,0,0,0,0,0,0,0,0,0,0,0,0,0,0,0,0,0,0,0,0,0,0,0,0,0,0,0,0~
,0,BR21,0,0,0,0,0,0)';$S;
    'VSS_BR22':'(0,0,0,0,0,0,0,0,0,0,0,0,0,0,0,0,0,0,0,0,0,0,0,0,0,0,0,0,0,0,0,0~
,0,BR22,0,0,0,0,0,0)';$S;
    'VSS_BR24':'(0,0,0,0,0,0,0,0,0,0,0,0,0,0,0,0,0,0,0,0,0,0,0,0,0,0,0,0,0,0,0,0~
,0,BR24,0,0,0,0,0,0)';$S;
    'VSS_BR26':'(0,0,0,0,0,0,0,0,0,0,0,0,0,0,0,0,0,0,0,0,0,0,0,0,0,0,0,0,0,0,0,0~
,0,BR26,0,0,0,0,0,0)';$S;
    'VSS_BR28':'(0,0,0,0,0,0,0,0,0,0,0,0,0,0,0,0,0,0,0,0,0,0,0,0,0,0,0,0,0,0,0,0~
,0,BR28,0,0,0,0,0,0)';$S;
    'VSS_BR30':'(0,0,0,0,0,0,0,0,0,0,0,0,0,0,0,0,0,0,0,0,0,0,0,0,0,0,0,0,0,0,0,0~
,0,BR30,0,0,0,0,0,0)';$S;
    'VSS_BR32':'(0,0,0,0,0,0,0,0,0,0,0,0,0,0,0,0,0,0,0,0,0,0,0,0,0,0,0,0,0,0,0,0~
,0,BR32,0,0,0,0,0,0)';$S;
    'VSS_BR34':'(0,0,0,0,0,0,0,0,0,0,0,0,0,0,0,0,0,0,0,0,0,0,0,0,0,0,0,0,0,0,0,0~
,0,BR34,0,0,0,0,0,0)';$S;
    'VSS_BR36':'(0,0,0,0,0,0,0,0,0,0,0,0,0,0,0,0,0,0,0,0,0,0,0,0,0,0,0,0,0,0,0,0~
,0,BR36,0,0,0,0,0,0)';$S;
    'VSS_BR41':'(0,0,0,0,0,0,0,0,0,0,0,0,0,0,0,0,0,0,0,0,0,0,0,0,0,0,0,0,0,0,0,0~
,0,BR41,0,0,0,0,0,0)';$S;
    'VSS_BR43':'(0,0,0,0,0,0,0,0,0,0,0,0,0,0,0,0,0,0,0,0,0,0,0,0,0,0,0,0,0,0,0,0~
,0,BR43,0,0,0,0,0,0)';$S;
    'VSS_BR45':'(0,0,0,0,0,0,0,0,0,0,0,0,0,0,0,0,0,0,0,0,0,0,0,0,0,0,0,0,0,0,0,0~
,0,BR45,0,0,0,0,0,0)';$S;
    'VSS_BR47':'(0,0,0,0,0,0,0,0,0,0,0,0,0,0,0,0,0,0,0,0,0,0,0,0,0,0,0,0,0,0,0,0~
,0,BR47,0,0,0,0,0,0)';$S;
    'VSS_BR49':'(0,0,0,0,0,0,0,0,0,0,0,0,0,0,0,0,0,0,0,0,0,0,0,0,0,0,0,0,0,0,0,0~
,0,BR49,0,0,0,0,0,0)';$S;
    'VSS_BR51':'(0,0,0,0,0,0,0,0,0,0,0,0,0,0,0,0,0,0,0,0,0,0,0,0,0,0,0,0,0,0,0,0~
,0,BR51,0,0,0,0,0,0)';$S;
    'VSS_BR55':'(0,0,0,0,0,0,0,0,0,0,0,0,0,0,0,0,0,0,0,0,0,0,0,0,0,0,0,0,0,0,0,0~
,0,BR55,0,0,0,0,0,0)';$S;
    'VSS_BR56':'(0,0,0,0,0,0,0,0,0,0,0,0,0,0,0,0,0,0,0,0,0,0,0,0,0,0,0,0,0,0,0,0~
,0,BR56,0,0,0,0,0,0)';$S;
    'VSS_BR59':'(0,0,0,0,0,0,0,0,0,0,0,0,0,0,0,0,0,0,0,0,0,0,0,0,0,0,0,0,0,0,0,0~
,0,BR59,0,0,0,0,0,0)';$S;
    'VSS_BR61':'(0,0,0,0,0,0,0,0,0,0,0,0,0,0,0,0,0,0,0,0,0,0,0,0,0,0,0,0,0,0,0,0~
,0,BR61,0,0,0,0,0,0)';$S;
    'VSS_BR62':'(0,0,0,0,0,0,0,0,0,0,0,0,0,0,0,0,0,0,0,0,0,0,0,0,0,0,0,0,0,0,0,0~
,0,BR62,0,0,0,0,0,0)';$S;
    'VSS_BR63':'(0,0,0,0,0,0,0,0,0,0,0,0,0,0,0,0,0,0,0,0,0,0,0,0,0,0,0,0,0,0,0,0~
,0,BR63,0,0,0,0,0,0)';$S;
    'VSS_BR66':'(0,0,0,0,0,0,0,0,0,0,0,0,0,0,0,0,0,0,0,0,0,0,0,0,0,0,0,0,0,0,0,0~
,0,BR66,0,0,0,0,0,0)';$S;
    'VSS_BR68':'(0,0,0,0,0,0,0,0,0,0,0,0,0,0,0,0,0,0,0,0,0,0,0,0,0,0,0,0,0,0,0,0~
,0,BR68,0,0,0,0,0,0)';$S;
    'VSS_BR69':'(0,0,0,0,0,0,0,0,0,0,0,0,0,0,0,0,0,0,0,0,0,0,0,0,0,0,0,0,0,0,0,0~
,0,BR69,0,0,0,0,0,0)';$S;
    'VSS_BR70':'(0,0,0,0,0,0,0,0,0,0,0,0,0,0,0,0,0,0,0,0,0,0,0,0,0,0,0,0,0,0,0,0~
,0,BR70,0,0,0,0,0,0)';$S;
    'VSS_BR73':'(0,0,0,0,0,0,0,0,0,0,0,0,0,0,0,0,0,0,0,0,0,0,0,0,0,0,0,0,0,0,0,0~
,0,BR73,0,0,0,0,0,0)';$S;
    'VSS_BR75':'(0,0,0,0,0,0,0,0,0,0,0,0,0,0,0,0,0,0,0,0,0,0,0,0,0,0,0,0,0,0,0,0~
,0,BR75,0,0,0,0,0,0)';$S;
    'VSS_BT3':'(0,0,0,0,0,0,0,0,0,0,0,0,0,0,0,0,0,0,0,0,0,0,0,0,0,0,0,0,0,0,0,0,~
0,BT3,0,0,0,0,0,0)';$S;
    'VSS_BT4':'(0,0,0,0,0,0,0,0,0,0,0,0,0,0,0,0,0,0,0,0,0,0,0,0,0,0,0,0,0,0,0,0,~
0,BT4,0,0,0,0,0,0)';$S;
    'VSS_BT5':'(0,0,0,0,0,0,0,0,0,0,0,0,0,0,0,0,0,0,0,0,0,0,0,0,0,0,0,0,0,0,0,0,~
0,BT5,0,0,0,0,0,0)';$S;
    'VSS_BT7':'(0,0,0,0,0,0,0,0,0,0,0,0,0,0,0,0,0,0,0,0,0,0,0,0,0,0,0,0,0,0,0,0,~
0,BT7,0,0,0,0,0,0)';$S;
    'VSS_BT8':'(0,0,0,0,0,0,0,0,0,0,0,0,0,0,0,0,0,0,0,0,0,0,0,0,0,0,0,0,0,0,0,0,~
0,BT8,0,0,0,0,0,0)';$S;
    'VSS_BT10':'(0,0,0,0,0,0,0,0,0,0,0,0,0,0,0,0,0,0,0,0,0,0,0,0,0,0,0,0,0,0,0,0~
,0,BT10,0,0,0,0,0,0)';$S;
    'VSS_BT11':'(0,0,0,0,0,0,0,0,0,0,0,0,0,0,0,0,0,0,0,0,0,0,0,0,0,0,0,0,0,0,0,0~
,0,BT11,0,0,0,0,0,0)';$S;
    'VSS_BT12':'(0,0,0,0,0,0,0,0,0,0,0,0,0,0,0,0,0,0,0,0,0,0,0,0,0,0,0,0,0,0,0,0~
,0,BT12,0,0,0,0,0,0)';$S;
    'VSS_BT14':'(0,0,0,0,0,0,0,0,0,0,0,0,0,0,0,0,0,0,0,0,0,0,0,0,0,0,0,0,0,0,0,0~
,0,BT14,0,0,0,0,0,0)';$S;
    'VSS_BT15':'(0,0,0,0,0,0,0,0,0,0,0,0,0,0,0,0,0,0,0,0,0,0,0,0,0,0,0,0,0,0,0,0~
,0,BT15,0,0,0,0,0,0)';$S;
    'VSS_BT17':'(0,0,0,0,0,0,0,0,0,0,0,0,0,0,0,0,0,0,0,0,0,0,0,0,0,0,0,0,0,0,0,0~
,0,BT17,0,0,0,0,0,0)';$S;
    'VSS_BT18':'(0,0,0,0,0,0,0,0,0,0,0,0,0,0,0,0,0,0,0,0,0,0,0,0,0,0,0,0,0,0,0,0~
,0,BT18,0,0,0,0,0,0)';$S;
    'VSS_BT19':'(0,0,0,0,0,0,0,0,0,0,0,0,0,0,0,0,0,0,0,0,0,0,0,0,0,0,0,0,0,0,0,0~
,0,BT19,0,0,0,0,0,0)';$S;
    'VSS_BT21':'(0,0,0,0,0,0,0,0,0,0,0,0,0,0,0,0,0,0,0,0,0,0,0,0,0,0,0,0,0,0,0,0~
,0,BT21,0,0,0,0,0,0)';$S;
    'VSS_BT22':'(0,0,0,0,0,0,0,0,0,0,0,0,0,0,0,0,0,0,0,0,0,0,0,0,0,0,0,0,0,0,0,0~
,0,BT22,0,0,0,0,0,0)';$S;
    'VSS_BT25':'(0,0,0,0,0,0,0,0,0,0,0,0,0,0,0,0,0,0,0,0,0,0,0,0,0,0,0,0,0,0,0,0~
,0,BT25,0,0,0,0,0,0)';$S;
    'VSS_BT28':'(0,0,0,0,0,0,0,0,0,0,0,0,0,0,0,0,0,0,0,0,0,0,0,0,0,0,0,0,0,0,0,0~
,0,BT28,0,0,0,0,0,0)';$S;
    'VSS_BT31':'(0,0,0,0,0,0,0,0,0,0,0,0,0,0,0,0,0,0,0,0,0,0,0,0,0,0,0,0,0,0,0,0~
,0,BT31,0,0,0,0,0,0)';$S;
    'VSS_BT34':'(0,0,0,0,0,0,0,0,0,0,0,0,0,0,0,0,0,0,0,0,0,0,0,0,0,0,0,0,0,0,0,0~
,0,BT34,0,0,0,0,0,0)';$S;
    'VSS_BT37':'(0,0,0,0,0,0,0,0,0,0,0,0,0,0,0,0,0,0,0,0,0,0,0,0,0,0,0,0,0,0,0,0~
,0,BT37,0,0,0,0,0,0)';$S;
    'VSS_BT39':'(0,0,0,0,0,0,0,0,0,0,0,0,0,0,0,0,0,0,0,0,0,0,0,0,0,0,0,0,0,0,0,0~
,0,BT39,0,0,0,0,0,0)';$S;
    'VSS_BT42':'(0,0,0,0,0,0,0,0,0,0,0,0,0,0,0,0,0,0,0,0,0,0,0,0,0,0,0,0,0,0,0,0~
,0,BT42,0,0,0,0,0,0)';$S;
    'VSS_BT45':'(0,0,0,0,0,0,0,0,0,0,0,0,0,0,0,0,0,0,0,0,0,0,0,0,0,0,0,0,0,0,0,0~
,0,BT45,0,0,0,0,0,0)';$S;
    'VSS_BT48':'(0,0,0,0,0,0,0,0,0,0,0,0,0,0,0,0,0,0,0,0,0,0,0,0,0,0,0,0,0,0,0,0~
,0,BT48,0,0,0,0,0,0)';$S;
    'VSS_BT51':'(0,0,0,0,0,0,0,0,0,0,0,0,0,0,0,0,0,0,0,0,0,0,0,0,0,0,0,0,0,0,0,0~
,0,BT51,0,0,0,0,0,0)';$S;
    'VSS_BT54':'(0,0,0,0,0,0,0,0,0,0,0,0,0,0,0,0,0,0,0,0,0,0,0,0,0,0,0,0,0,0,0,0~
,0,BT54,0,0,0,0,0,0)';$S;
    'VSS_BT55':'(0,0,0,0,0,0,0,0,0,0,0,0,0,0,0,0,0,0,0,0,0,0,0,0,0,0,0,0,0,0,0,0~
,0,BT55,0,0,0,0,0,0)';$S;
    'VSS_BT57':'(0,0,0,0,0,0,0,0,0,0,0,0,0,0,0,0,0,0,0,0,0,0,0,0,0,0,0,0,0,0,0,0~
,0,BT57,0,0,0,0,0,0)';$S;
    'VSS_BT58':'(0,0,0,0,0,0,0,0,0,0,0,0,0,0,0,0,0,0,0,0,0,0,0,0,0,0,0,0,0,0,0,0~
,0,BT58,0,0,0,0,0,0)';$S;
    'VSS_BT59':'(0,0,0,0,0,0,0,0,0,0,0,0,0,0,0,0,0,0,0,0,0,0,0,0,0,0,0,0,0,0,0,0~
,0,BT59,0,0,0,0,0,0)';$S;
    'VSS_BT61':'(0,0,0,0,0,0,0,0,0,0,0,0,0,0,0,0,0,0,0,0,0,0,0,0,0,0,0,0,0,0,0,0~
,0,BT61,0,0,0,0,0,0)';$S;
    'VSS_BT62':'(0,0,0,0,0,0,0,0,0,0,0,0,0,0,0,0,0,0,0,0,0,0,0,0,0,0,0,0,0,0,0,0~
,0,BT62,0,0,0,0,0,0)';$S;
    'VSS_BT64':'(0,0,0,0,0,0,0,0,0,0,0,0,0,0,0,0,0,0,0,0,0,0,0,0,0,0,0,0,0,0,0,0~
,0,BT64,0,0,0,0,0,0)';$S;
    'VSS_BT65':'(0,0,0,0,0,0,0,0,0,0,0,0,0,0,0,0,0,0,0,0,0,0,0,0,0,0,0,0,0,0,0,0~
,0,BT65,0,0,0,0,0,0)';$S;
    'VSS_BT66':'(0,0,0,0,0,0,0,0,0,0,0,0,0,0,0,0,0,0,0,0,0,0,0,0,0,0,0,0,0,0,0,0~
,0,BT66,0,0,0,0,0,0)';$S;
    'VSS_BT68':'(0,0,0,0,0,0,0,0,0,0,0,0,0,0,0,0,0,0,0,0,0,0,0,0,0,0,0,0,0,0,0,0~
,0,BT68,0,0,0,0,0,0)';$S;
    'VSS_BT69':'(0,0,0,0,0,0,0,0,0,0,0,0,0,0,0,0,0,0,0,0,0,0,0,0,0,0,0,0,0,0,0,0~
,0,BT69,0,0,0,0,0,0)';$S;
    'VSS_BT71':'(0,0,0,0,0,0,0,0,0,0,0,0,0,0,0,0,0,0,0,0,0,0,0,0,0,0,0,0,0,0,0,0~
,0,BT71,0,0,0,0,0,0)';$S;
    'VSS_BT72':'(0,0,0,0,0,0,0,0,0,0,0,0,0,0,0,0,0,0,0,0,0,0,0,0,0,0,0,0,0,0,0,0~
,0,BT72,0,0,0,0,0,0)';$S;
    'VSS_BT73':'(0,0,0,0,0,0,0,0,0,0,0,0,0,0,0,0,0,0,0,0,0,0,0,0,0,0,0,0,0,0,0,0~
,0,BT73,0,0,0,0,0,0)';$S;
    'VSS_BU1':'(0,0,0,0,0,0,0,0,0,0,0,0,0,0,0,0,0,0,0,0,0,0,0,0,0,0,0,0,0,0,0,0,~
0,BU1,0,0,0,0,0,0)';$S;
    'VSS_BU4':'(0,0,0,0,0,0,0,0,0,0,0,0,0,0,0,0,0,0,0,0,0,0,0,0,0,0,0,0,0,0,0,0,~
0,BU4,0,0,0,0,0,0)';$S;
    'VSS_BU6':'(0,0,0,0,0,0,0,0,0,0,0,0,0,0,0,0,0,0,0,0,0,0,0,0,0,0,0,0,0,0,0,0,~
0,BU6,0,0,0,0,0,0)';$S;
    'VSS_BU8':'(0,0,0,0,0,0,0,0,0,0,0,0,0,0,0,0,0,0,0,0,0,0,0,0,0,0,0,0,0,0,0,0,~
0,BU8,0,0,0,0,0,0)';$S;
    'VSS_BU11':'(0,0,0,0,0,0,0,0,0,0,0,0,0,0,0,0,0,0,0,0,0,0,0,0,0,0,0,0,0,0,0,0~
,0,BU11,0,0,0,0,0,0)';$S;
    'VSS_BU13':'(0,0,0,0,0,0,0,0,0,0,0,0,0,0,0,0,0,0,0,0,0,0,0,0,0,0,0,0,0,0,0,0~
,0,BU13,0,0,0,0,0,0)';$S;
    'VSS_BU15':'(0,0,0,0,0,0,0,0,0,0,0,0,0,0,0,0,0,0,0,0,0,0,0,0,0,0,0,0,0,0,0,0~
,0,BU15,0,0,0,0,0,0)';$S;
    'VSS_BU18':'(0,0,0,0,0,0,0,0,0,0,0,0,0,0,0,0,0,0,0,0,0,0,0,0,0,0,0,0,0,0,0,0~
,0,BU18,0,0,0,0,0,0)';$S;
    'VSS_BU20':'(0,0,0,0,0,0,0,0,0,0,0,0,0,0,0,0,0,0,0,0,0,0,0,0,0,0,0,0,0,0,0,0~
,0,BU20,0,0,0,0,0,0)';$S;
    'VSS_BU22':'(0,0,0,0,0,0,0,0,0,0,0,0,0,0,0,0,0,0,0,0,0,0,0,0,0,0,0,0,0,0,0,0~
,0,BU22,0,0,0,0,0,0)';$S;
    'VSS_BU25':'(0,0,0,0,0,0,0,0,0,0,0,0,0,0,0,0,0,0,0,0,0,0,0,0,0,0,0,0,0,0,0,0~
,0,BU25,0,0,0,0,0,0)';$S;
    'VSS_BU28':'(0,0,0,0,0,0,0,0,0,0,0,0,0,0,0,0,0,0,0,0,0,0,0,0,0,0,0,0,0,0,0,0~
,0,BU28,0,0,0,0,0,0)';$S;
    'VSS_BU31':'(0,0,0,0,0,0,0,0,0,0,0,0,0,0,0,0,0,0,0,0,0,0,0,0,0,0,0,0,0,0,0,0~
,0,BU31,0,0,0,0,0,0)';$S;
    'VSS_BU34':'(0,0,0,0,0,0,0,0,0,0,0,0,0,0,0,0,0,0,0,0,0,0,0,0,0,0,0,0,0,0,0,0~
,0,BU34,0,0,0,0,0,0)';$S;
    'VSS_BU35':'(0,0,0,0,0,0,0,0,0,0,0,0,0,0,0,0,0,0,0,0,0,0,0,0,0,0,0,0,0,0,0,0~
,0,BU35,0,0,0,0,0,0)';$S;
    'VSS_BU36':'(0,0,0,0,0,0,0,0,0,0,0,0,0,0,0,0,0,0,0,0,0,0,0,0,0,0,0,0,0,0,0,0~
,0,BU36,0,0,0,0,0,0)';$S;
    'VSS_BU40':'(0,0,0,0,0,0,0,0,0,0,0,0,0,0,0,0,0,0,0,0,0,0,0,0,0,0,0,0,0,0,0,0~
,0,BU40,0,0,0,0,0,0)';$S;
    'VSS_BU41':'(0,0,0,0,0,0,0,0,0,0,0,0,0,0,0,0,0,0,0,0,0,0,0,0,0,0,0,0,0,0,0,0~
,0,BU41,0,0,0,0,0,0)';$S;
    'VSS_BU42':'(0,0,0,0,0,0,0,0,0,0,0,0,0,0,0,0,0,0,0,0,0,0,0,0,0,0,0,0,0,0,0,0~
,0,BU42,0,0,0,0,0,0)';$S;
    'VSS_BU45':'(0,0,0,0,0,0,0,0,0,0,0,0,0,0,0,0,0,0,0,0,0,0,0,0,0,0,0,0,0,0,0,0~
,0,BU45,0,0,0,0,0,0)';$S;
    'VSS_BU48':'(0,0,0,0,0,0,0,0,0,0,0,0,0,0,0,0,0,0,0,0,0,0,0,0,0,0,0,0,0,0,0,0~
,0,BU48,0,0,0,0,0,0)';$S;
    'VSS_BU51':'(0,0,0,0,0,0,0,0,0,0,0,0,0,0,0,0,0,0,0,0,0,0,0,0,0,0,0,0,0,0,0,0~
,0,BU51,0,0,0,0,0,0)';$S;
    'VSS_BU54':'(0,0,0,0,0,0,0,0,0,0,0,0,0,0,0,0,0,0,0,0,0,0,0,0,0,0,0,0,0,0,0,0~
,0,BU54,0,0,0,0,0,0)';$S;
    'VSS_BU56':'(0,0,0,0,0,0,0,0,0,0,0,0,0,0,0,0,0,0,0,0,0,0,0,0,0,0,0,0,0,0,0,0~
,0,BU56,0,0,0,0,0,0)';$S;
    'VSS_BU58':'(0,0,0,0,0,0,0,0,0,0,0,0,0,0,0,0,0,0,0,0,0,0,0,0,0,0,0,0,0,0,0,0~
,0,BU58,0,0,0,0,0,0)';$S;
    'VSS_BU61':'(0,0,0,0,0,0,0,0,0,0,0,0,0,0,0,0,0,0,0,0,0,0,0,0,0,0,0,0,0,0,0,0~
,0,BU61,0,0,0,0,0,0)';$S;
    'VSS_BU63':'(0,0,0,0,0,0,0,0,0,0,0,0,0,0,0,0,0,0,0,0,0,0,0,0,0,0,0,0,0,0,0,0~
,0,BU63,0,0,0,0,0,0)';$S;
    'VSS_BU65':'(0,0,0,0,0,0,0,0,0,0,0,0,0,0,0,0,0,0,0,0,0,0,0,0,0,0,0,0,0,0,0,0~
,0,BU65,0,0,0,0,0,0)';$S;
    'VSS_BU68':'(0,0,0,0,0,0,0,0,0,0,0,0,0,0,0,0,0,0,0,0,0,0,0,0,0,0,0,0,0,0,0,0~
,0,BU68,0,0,0,0,0,0)';$S;
    'VSS_BU70':'(0,0,0,0,0,0,0,0,0,0,0,0,0,0,0,0,0,0,0,0,0,0,0,0,0,0,0,0,0,0,0,0~
,0,BU70,0,0,0,0,0,0)';$S;
    'VSS_BU72':'(0,0,0,0,0,0,0,0,0,0,0,0,0,0,0,0,0,0,0,0,0,0,0,0,0,0,0,0,0,0,0,0~
,0,BU72,0,0,0,0,0,0)';$S;
    'VSS_BU75':'(0,0,0,0,0,0,0,0,0,0,0,0,0,0,0,0,0,0,0,0,0,0,0,0,0,0,0,0,0,0,0,0~
,0,BU75,0,0,0,0,0,0)';$S;
    'VSS_BV3':'(0,0,0,0,0,0,0,0,0,0,0,0,0,0,0,0,0,0,0,0,0,0,0,0,0,0,0,0,0,0,0,0,~
0,BV3,0,0,0,0,0,0)';$S;
    'VSS_BV8':'(0,0,0,0,0,0,0,0,0,0,0,0,0,0,0,0,0,0,0,0,0,0,0,0,0,0,0,0,0,0,0,0,~
0,BV8,0,0,0,0,0,0)';$S;
    'VSS_BV10':'(0,0,0,0,0,0,0,0,0,0,0,0,0,0,0,0,0,0,0,0,0,0,0,0,0,0,0,0,0,0,0,0~
,0,BV10,0,0,0,0,0,0)';$S;
    'VSS_BV15':'(0,0,0,0,0,0,0,0,0,0,0,0,0,0,0,0,0,0,0,0,0,0,0,0,0,0,0,0,0,0,0,0~
,0,BV15,0,0,0,0,0,0)';$S;
    'VSS_BV17':'(0,0,0,0,0,0,0,0,0,0,0,0,0,0,0,0,0,0,0,0,0,0,0,0,0,0,0,0,0,0,0,0~
,0,BV17,0,0,0,0,0,0)';$S;
    'VSS_BV23':'(0,0,0,0,0,0,0,0,0,0,0,0,0,0,0,0,0,0,0,0,0,0,0,0,0,0,0,0,0,0,0,0~
,0,BV23,0,0,0,0,0,0)';$S;
    'VSS_BV24':'(0,0,0,0,0,0,0,0,0,0,0,0,0,0,0,0,0,0,0,0,0,0,0,0,0,0,0,0,0,0,0,0~
,0,BV24,0,0,0,0,0,0)';$S;
    'VSS_BV25':'(0,0,0,0,0,0,0,0,0,0,0,0,0,0,0,0,0,0,0,0,0,0,0,0,0,0,0,0,0,0,0,0~
,0,BV25,0,0,0,0,0,0)';$S;
    'VSS_BV26':'(0,0,0,0,0,0,0,0,0,0,0,0,0,0,0,0,0,0,0,0,0,0,0,0,0,0,0,0,0,0,0,0~
,0,BV26,0,0,0,0,0,0)';$S;
    'VSS_BV27':'(0,0,0,0,0,0,0,0,0,0,0,0,0,0,0,0,0,0,0,0,0,0,0,0,0,0,0,0,0,0,0,0~
,0,BV27,0,0,0,0,0,0)';$S;
    'VSS_BV28':'(0,0,0,0,0,0,0,0,0,0,0,0,0,0,0,0,0,0,0,0,0,0,0,0,0,0,0,0,0,0,0,0~
,0,BV28,0,0,0,0,0,0)';$S;
    'VSS_BV29':'(0,0,0,0,0,0,0,0,0,0,0,0,0,0,0,0,0,0,0,0,0,0,0,0,0,0,0,0,0,0,0,0~
,0,BV29,0,0,0,0,0,0)';$S;
    'VSS_BV30':'(0,0,0,0,0,0,0,0,0,0,0,0,0,0,0,0,0,0,0,0,0,0,0,0,0,0,0,0,0,0,0,0~
,0,BV30,0,0,0,0,0,0)';$S;
    'VSS_BV31':'(0,0,0,0,0,0,0,0,0,0,0,0,0,0,0,0,0,0,0,0,0,0,0,0,0,0,0,0,0,0,0,0~
,0,BV31,0,0,0,0,0,0)';$S;
    'VSS_BV32':'(0,0,0,0,0,0,0,0,0,0,0,0,0,0,0,0,0,0,0,0,0,0,0,0,0,0,0,0,0,0,0,0~
,0,BV32,0,0,0,0,0,0)';$S;
    'VSS_BV33':'(0,0,0,0,0,0,0,0,0,0,0,0,0,0,0,0,0,0,0,0,0,0,0,0,0,0,0,0,0,0,0,0~
,0,BV33,0,0,0,0,0,0)';$S;
    'VSS_BV34':'(0,0,0,0,0,0,0,0,0,0,0,0,0,0,0,0,0,0,0,0,0,0,0,0,0,0,0,0,0,0,0,0~
,0,BV34,0,0,0,0,0,0)';$S;
    'VSS_BV39':'(0,0,0,0,0,0,0,0,0,0,0,0,0,0,0,0,0,0,0,0,0,0,0,0,0,0,0,0,0,0,0,0~
,0,BV39,0,0,0,0,0,0)';$S;
    'VSS_BV43':'(0,0,0,0,0,0,0,0,0,0,0,0,0,0,0,0,0,0,0,0,0,0,0,0,0,0,0,0,0,0,0,0~
,0,BV43,0,0,0,0,0,0)';$S;
    'VSS_BV44':'(0,0,0,0,0,0,0,0,0,0,0,0,0,0,0,0,0,0,0,0,0,0,0,0,0,0,0,0,0,0,0,0~
,0,BV44,0,0,0,0,0,0)';$S;
    'VSS_BV45':'(0,0,0,0,0,0,0,0,0,0,0,0,0,0,0,0,0,0,0,0,0,0,0,0,0,0,0,0,0,0,0,0~
,0,BV45,0,0,0,0,0,0)';$S;
    'MLB_DQS_L9':'(0,0,0,0,0,0,0,0,0,0,0,0,0,0,0,0,0,0,0,0,0,0,0,0,0,0,0,0,0,0,0~
,0,0,0,BW9,0,0,0,0,0)';$S;BIDI;
    'MLB_DQS_H5':'(0,0,0,0,0,0,0,0,0,0,0,0,0,0,0,0,0,0,0,0,0,0,0,0,0,0,0,0,0,0,0~
,0,0,0,CF11,0,0,0,0,0)';$S;BIDI;
    'MLB_DATA4':'(0,0,0,0,0,0,0,0,0,0,0,0,0,0,0,0,0,0,0,0,0,0,0,0,0,0,0,0,0,0,0,~
0,0,0,CF9,0,0,0,0,0)';$S;BIDI;
    'MLB_CA1':'(0,0,0,0,0,0,0,0,0,0,0,0,0,0,0,0,0,0,0,0,0,0,0,0,0,0,0,0,0,0,0,0,~
0,0,BH11,0,0,0,0,0)';$S;OUT;
    'MLA_DATA22':'(0,0,0,0,0,0,0,0,0,0,0,0,0,0,0,0,0,0,0,0,0,0,0,0,0,0,0,0,0,0,0~
,0,0,0,AB9,0,0,0,0,0)';$S;BIDI;
    'MLA_DATA11':'(0,0,0,0,0,0,0,0,0,0,0,0,0,0,0,0,0,0,0,0,0,0,0,0,0,0,0,0,0,0,0~
,0,0,0,N10,0,0,0,0,0)';$S;BIDI;
    'MLA_DATA5':'(0,0,0,0,0,0,0,0,0,0,0,0,0,0,0,0,0,0,0,0,0,0,0,0,0,0,0,0,0,0,0,~
0,0,0,K11,0,0,0,0,0)';$S;BIDI;
    'MLA_CHECK2':'(0,0,0,0,0,0,0,0,0,0,0,0,0,0,0,0,0,0,0,0,0,0,0,0,0,0,0,0,0,0,0~
,0,0,0,AK9,0,0,0,0,0)';$S;BIDI;
    'MLA_CA2':'(0,0,0,0,0,0,0,0,0,0,0,0,0,0,0,0,0,0,0,0,0,0,0,0,0,0,0,0,0,0,0,0,~
0,0,AY11,0,0,0,0,0)';$S;OUT;
    'ML_RESET_L':'(0,0,0,0,0,0,0,0,0,0,0,0,0,0,0,0,0,0,0,0,0,0,0,0,0,0,0,0,0,0,0~
,0,0,0,AU10,0,0,0,0,0)';$S;OUT;
    'MLB_DQS_H6':'(0,0,0,0,0,0,0,0,0,0,0,0,0,0,0,0,0,0,0,0,0,0,0,0,0,0,0,0,0,0,0~
,0,0,0,CM11,0,0,0,0,0)';$S;BIDI;
    'MLB_DATA5':'(0,0,0,0,0,0,0,0,0,0,0,0,0,0,0,0,0,0,0,0,0,0,0,0,0,0,0,0,0,0,0,~
0,0,0,CG10,0,0,0,0,0)';$S;BIDI;
    'MLB_CA2':'(0,0,0,0,0,0,0,0,0,0,0,0,0,0,0,0,0,0,0,0,0,0,0,0,0,0,0,0,0,0,0,0,~
0,0,BH9,0,0,0,0,0)';$S;OUT;
    'MLB0_CS_L0':'(0,0,0,0,0,0,0,0,0,0,0,0,0,0,0,0,0,0,0,0,0,0,0,0,0,0,0,0,0,0,0~
,0,0,0,BM11,0,0,0,0,0)';$S;OUT;
    'MLA_DATA23':'(0,0,0,0,0,0,0,0,0,0,0,0,0,0,0,0,0,0,0,0,0,0,0,0,0,0,0,0,0,0,0~
,0,0,0,AC10,0,0,0,0,0)';$S;BIDI;
    'MLA_DATA12':'(0,0,0,0,0,0,0,0,0,0,0,0,0,0,0,0,0,0,0,0,0,0,0,0,0,0,0,0,0,0,0~
,0,0,0,R9,0,0,0,0,0)';$S;BIDI;
    'MLA_DATA6':'(0,0,0,0,0,0,0,0,0,0,0,0,0,0,0,0,0,0,0,0,0,0,0,0,0,0,0,0,0,0,0,~
0,0,0,K9,0,0,0,0,0)';$S;BIDI;
    'MLA_CHECK3':'(0,0,0,0,0,0,0,0,0,0,0,0,0,0,0,0,0,0,0,0,0,0,0,0,0,0,0,0,0,0,0~
,0,0,0,AL10,0,0,0,0,0)';$S;BIDI;
    'MLA_CA3':'(0,0,0,0,0,0,0,0,0,0,0,0,0,0,0,0,0,0,0,0,0,0,0,0,0,0,0,0,0,0,0,0,~
0,0,BA10,0,0,0,0,0)';$S;OUT;
    'MLB_DQS_H7':'(0,0,0,0,0,0,0,0,0,0,0,0,0,0,0,0,0,0,0,0,0,0,0,0,0,0,0,0,0,0,0~
,0,0,0,CV11,0,0,0,0,0)';$S;BIDI;
    'MLB_DATA6':'(0,0,0,0,0,0,0,0,0,0,0,0,0,0,0,0,0,0,0,0,0,0,0,0,0,0,0,0,0,0,0,~
0,0,0,CG9,0,0,0,0,0)';$S;BIDI;
    'MLB_CA3':'(0,0,0,0,0,0,0,0,0,0,0,0,0,0,0,0,0,0,0,0,0,0,0,0,0,0,0,0,0,0,0,0,~
0,0,BJ9,0,0,0,0,0)';$S;OUT;
    'MLB1_CS_L0':'(0,0,0,0,0,0,0,0,0,0,0,0,0,0,0,0,0,0,0,0,0,0,0,0,0,0,0,0,0,0,0~
,0,0,0,BL9,0,0,0,0,0)';$S;OUT;
    'MLB0_CS_L1':'(0,0,0,0,0,0,0,0,0,0,0,0,0,0,0,0,0,0,0,0,0,0,0,0,0,0,0,0,0,0,0~
,0,0,0,BN9,0,0,0,0,0)';$S;OUT;
    'MLA_DQS_L0':'(0,0,0,0,0,0,0,0,0,0,0,0,0,0,0,0,0,0,0,0,0,0,0,0,0,0,0,0,0,0,0~
,0,0,0,H9,0,0,0,0,0)';$S;BIDI;
    'MLA_DATA24':'(0,0,0,0,0,0,0,0,0,0,0,0,0,0,0,0,0,0,0,0,0,0,0,0,0,0,0,0,0,0,0~
,0,0,0,AC9,0,0,0,0,0)';$S;BIDI;
    'MLA_DATA13':'(0,0,0,0,0,0,0,0,0,0,0,0,0,0,0,0,0,0,0,0,0,0,0,0,0,0,0,0,0,0,0~
,0,0,0,T11,0,0,0,0,0)';$S;BIDI;
    'MLA_DATA7':'(0,0,0,0,0,0,0,0,0,0,0,0,0,0,0,0,0,0,0,0,0,0,0,0,0,0,0,0,0,0,0,~
0,0,0,L10,0,0,0,0,0)';$S;BIDI;
    'MLA_CHECK4':'(0,0,0,0,0,0,0,0,0,0,0,0,0,0,0,0,0,0,0,0,0,0,0,0,0,0,0,0,0,0,0~
,0,0,0,AN9,0,0,0,0,0)';$S;BIDI;
    'MLA_CA4':'(0,0,0,0,0,0,0,0,0,0,0,0,0,0,0,0,0,0,0,0,0,0,0,0,0,0,0,0,0,0,0,0,~
0,0,BA9,0,0,0,0,0)';$S;OUT;
    'MLB_DQS_H8':'(0,0,0,0,0,0,0,0,0,0,0,0,0,0,0,0,0,0,0,0,0,0,0,0,0,0,0,0,0,0,0~
,0,0,0,DD11,0,0,0,0,0)';$S;BIDI;
    'MLB_DATA30':'(0,0,0,0,0,0,0,0,0,0,0,0,0,0,0,0,0,0,0,0,0,0,0,0,0,0,0,0,0,0,0~
,0,0,0,DE9,0,0,0,0,0)';$S;BIDI;
    'MLB_DATA7':'(0,0,0,0,0,0,0,0,0,0,0,0,0,0,0,0,0,0,0,0,0,0,0,0,0,0,0,0,0,0,0,~
0,0,0,CH11,0,0,0,0,0)';$S;BIDI;
    'MLB_CA4':'(0,0,0,0,0,0,0,0,0,0,0,0,0,0,0,0,0,0,0,0,0,0,0,0,0,0,0,0,0,0,0,0,~
0,0,BJ10,0,0,0,0,0)';$S;OUT;
    'MLB1_CS_L1':'(0,0,0,0,0,0,0,0,0,0,0,0,0,0,0,0,0,0,0,0,0,0,0,0,0,0,0,0,0,0,0~
,0,0,0,BM9,0,0,0,0,0)';$S;OUT;
    'MLA_DQS_L1':'(0,0,0,0,0,0,0,0,0,0,0,0,0,0,0,0,0,0,0,0,0,0,0,0,0,0,0,0,0,0,0~
,0,0,0,P9,0,0,0,0,0)';$S;BIDI;
    'MLA_DATA25':'(0,0,0,0,0,0,0,0,0,0,0,0,0,0,0,0,0,0,0,0,0,0,0,0,0,0,0,0,0,0,0~
,0,0,0,AD11,0,0,0,0,0)';$S;BIDI;
    'MLA_DATA14':'(0,0,0,0,0,0,0,0,0,0,0,0,0,0,0,0,0,0,0,0,0,0,0,0,0,0,0,0,0,0,0~
,0,0,0,T9,0,0,0,0,0)';$S;BIDI;
    'MLA_DATA8':'(0,0,0,0,0,0,0,0,0,0,0,0,0,0,0,0,0,0,0,0,0,0,0,0,0,0,0,0,0,0,0,~
0,0,0,L9,0,0,0,0,0)';$S;BIDI;
    'MLA_CHECK5':'(0,0,0,0,0,0,0,0,0,0,0,0,0,0,0,0,0,0,0,0,0,0,0,0,0,0,0,0,0,0,0~
,0,0,0,AP11,0,0,0,0,0)';$S;BIDI;
    'MLA_CA5':'(0,0,0,0,0,0,0,0,0,0,0,0,0,0,0,0,0,0,0,0,0,0,0,0,0,0,0,0,0,0,0,0,~
0,0,BB9,0,0,0,0,0)';$S;OUT;
    'MLB_DQS_H9':'(0,0,0,0,0,0,0,0,0,0,0,0,0,0,0,0,0,0,0,0,0,0,0,0,0,0,0,0,0,0,0~
,0,0,0,BV9,0,0,0,0,0)';$S;BIDI;
    'MLB_DATA31':'(0,0,0,0,0,0,0,0,0,0,0,0,0,0,0,0,0,0,0,0,0,0,0,0,0,0,0,0,0,0,0~
,0,0,0,DF9,0,0,0,0,0)';$S;BIDI;
    'MLB_DATA20':'(0,0,0,0,0,0,0,0,0,0,0,0,0,0,0,0,0,0,0,0,0,0,0,0,0,0,0,0,0,0,0~
,0,0,0,CV9,0,0,0,0,0)';$S;BIDI;
    'MLB_DATA8':'(0,0,0,0,0,0,0,0,0,0,0,0,0,0,0,0,0,0,0,0,0,0,0,0,0,0,0,0,0,0,0,~
0,0,0,CH9,0,0,0,0,0)';$S;BIDI;
    'MLB_CHECK0':'(0,0,0,0,0,0,0,0,0,0,0,0,0,0,0,0,0,0,0,0,0,0,0,0,0,0,0,0,0,0,0~
,0,0,0,BY9,0,0,0,0,0)';$S;BIDI;
    'MLB_CA5':'(0,0,0,0,0,0,0,0,0,0,0,0,0,0,0,0,0,0,0,0,0,0,0,0,0,0,0,0,0,0,0,0,~
0,0,BK11,0,0,0,0,0)';$S;OUT;
    'MLA_DQS_L2':'(0,0,0,0,0,0,0,0,0,0,0,0,0,0,0,0,0,0,0,0,0,0,0,0,0,0,0,0,0,0,0~
,0,0,0,Y9,0,0,0,0,0)';$S;BIDI;
    'MLA_DATA26':'(0,0,0,0,0,0,0,0,0,0,0,0,0,0,0,0,0,0,0,0,0,0,0,0,0,0,0,0,0,0,0~
,0,0,0,AD9,0,0,0,0,0)';$S;BIDI;
    'MLA_DATA15':'(0,0,0,0,0,0,0,0,0,0,0,0,0,0,0,0,0,0,0,0,0,0,0,0,0,0,0,0,0,0,0~
,0,0,0,U10,0,0,0,0,0)';$S;BIDI;
    'MLA_DATA9':'(0,0,0,0,0,0,0,0,0,0,0,0,0,0,0,0,0,0,0,0,0,0,0,0,0,0,0,0,0,0,0,~
0,0,0,M11,0,0,0,0,0)';$S;BIDI;
    'MLA_CHECK6':'(0,0,0,0,0,0,0,0,0,0,0,0,0,0,0,0,0,0,0,0,0,0,0,0,0,0,0,0,0,0,0~
,0,0,0,AP9,0,0,0,0,0)';$S;BIDI;
    'MLA_CA6':'(0,0,0,0,0,0,0,0,0,0,0,0,0,0,0,0,0,0,0,0,0,0,0,0,0,0,0,0,0,0,0,0,~
0,0,BB11,0,0,0,0,0)';$S;OUT;
    'MLA0_RSP_L':'(0,0,0,0,0,0,0,0,0,0,0,0,0,0,0,0,0,0,0,0,0,0,0,0,0,0,0,0,0,0,0~
,0,0,0,BN10,0,0,0,0,0)';$S;IN;
    'MLB_DATA21':'(0,0,0,0,0,0,0,0,0,0,0,0,0,0,0,0,0,0,0,0,0,0,0,0,0,0,0,0,0,0,0~
,0,0,0,CW10,0,0,0,0,0)';$S;BIDI;
    'MLB_DATA10':'(0,0,0,0,0,0,0,0,0,0,0,0,0,0,0,0,0,0,0,0,0,0,0,0,0,0,0,0,0,0,0~
,0,0,0,CJ9,0,0,0,0,0)';$S;BIDI;
    'MLB_DATA9':'(0,0,0,0,0,0,0,0,0,0,0,0,0,0,0,0,0,0,0,0,0,0,0,0,0,0,0,0,0,0,0,~
0,0,0,CJ10,0,0,0,0,0)';$S;BIDI;
    'MLB_CHECK1':'(0,0,0,0,0,0,0,0,0,0,0,0,0,0,0,0,0,0,0,0,0,0,0,0,0,0,0,0,0,0,0~
,0,0,0,CA10,0,0,0,0,0)';$S;BIDI;
    'MLB_CA6':'(0,0,0,0,0,0,0,0,0,0,0,0,0,0,0,0,0,0,0,0,0,0,0,0,0,0,0,0,0,0,0,0,~
0,0,BK9,0,0,0,0,0)';$S;OUT;
    'MLA_DQS_L3':'(0,0,0,0,0,0,0,0,0,0,0,0,0,0,0,0,0,0,0,0,0,0,0,0,0,0,0,0,0,0,0~
,0,0,0,AF9,0,0,0,0,0)';$S;BIDI;
    'MLA_DATA27':'(0,0,0,0,0,0,0,0,0,0,0,0,0,0,0,0,0,0,0,0,0,0,0,0,0,0,0,0,0,0,0~
,0,0,0,AE10,0,0,0,0,0)';$S;BIDI;
    'MLA_DATA16':'(0,0,0,0,0,0,0,0,0,0,0,0,0,0,0,0,0,0,0,0,0,0,0,0,0,0,0,0,0,0,0~
,0,0,0,U9,0,0,0,0,0)';$S;BIDI;
    'MLA_CHECK7':'(0,0,0,0,0,0,0,0,0,0,0,0,0,0,0,0,0,0,0,0,0,0,0,0,0,0,0,0,0,0,0~
,0,0,0,AR10,0,0,0,0,0)';$S;BIDI;
    'MLA1_RSP_L':'(0,0,0,0,0,0,0,0,0,0,0,0,0,0,0,0,0,0,0,0,0,0,0,0,0,0,0,0,0,0,0~
,0,0,0,BP11,0,0,0,0,0)';$S;IN;
    'ML_ALERT_L':'(0,0,0,0,0,0,0,0,0,0,0,0,0,0,0,0,0,0,0,0,0,0,0,0,0,0,0,0,0,0,0~
,0,0,0,AT11,0,0,0,0,0)';$S;IN;
    'MLB_DATA22':'(0,0,0,0,0,0,0,0,0,0,0,0,0,0,0,0,0,0,0,0,0,0,0,0,0,0,0,0,0,0,0~
,0,0,0,CW9,0,0,0,0,0)';$S;BIDI;
    'MLB_DATA11':'(0,0,0,0,0,0,0,0,0,0,0,0,0,0,0,0,0,0,0,0,0,0,0,0,0,0,0,0,0,0,0~
,0,0,0,CK11,0,0,0,0,0)';$S;BIDI;
    'MLB_CHECK2':'(0,0,0,0,0,0,0,0,0,0,0,0,0,0,0,0,0,0,0,0,0,0,0,0,0,0,0,0,0,0,0~
,0,0,0,CA9,0,0,0,0,0)';$S;BIDI;
    'MLA_DQS_L4':'(0,0,0,0,0,0,0,0,0,0,0,0,0,0,0,0,0,0,0,0,0,0,0,0,0,0,0,0,0,0,0~
,0,0,0,AM9,0,0,0,0,0)';$S;BIDI;
    'MLA_DQS_H0':'(0,0,0,0,0,0,0,0,0,0,0,0,0,0,0,0,0,0,0,0,0,0,0,0,0,0,0,0,0,0,0~
,0,0,0,G9,0,0,0,0,0)';$S;BIDI;
    'MLA_DATA28':'(0,0,0,0,0,0,0,0,0,0,0,0,0,0,0,0,0,0,0,0,0,0,0,0,0,0,0,0,0,0,0~
,0,0,0,AG9,0,0,0,0,0)';$S;BIDI;
    'MLA_DATA17':'(0,0,0,0,0,0,0,0,0,0,0,0,0,0,0,0,0,0,0,0,0,0,0,0,0,0,0,0,0,0,0~
,0,0,0,V11,0,0,0,0,0)';$S;BIDI;
    'MLB_DATA23':'(0,0,0,0,0,0,0,0,0,0,0,0,0,0,0,0,0,0,0,0,0,0,0,0,0,0,0,0,0,0,0~
,0,0,0,CY11,0,0,0,0,0)';$S;BIDI;
    'MLB_DATA12':'(0,0,0,0,0,0,0,0,0,0,0,0,0,0,0,0,0,0,0,0,0,0,0,0,0,0,0,0,0,0,0~
,0,0,0,CM9,0,0,0,0,0)';$S;BIDI;
    'MLB_CHECK3':'(0,0,0,0,0,0,0,0,0,0,0,0,0,0,0,0,0,0,0,0,0,0,0,0,0,0,0,0,0,0,0~
,0,0,0,CB11,0,0,0,0,0)';$S;BIDI;
    'MLA_DQS_L5':'(0,0,0,0,0,0,0,0,0,0,0,0,0,0,0,0,0,0,0,0,0,0,0,0,0,0,0,0,0,0,0~
,0,0,0,H11,0,0,0,0,0)';$S;BIDI;
    'MLA_DQS_H1':'(0,0,0,0,0,0,0,0,0,0,0,0,0,0,0,0,0,0,0,0,0,0,0,0,0,0,0,0,0,0,0~
,0,0,0,N9,0,0,0,0,0)';$S;BIDI;
    'MLA_DATA29':'(0,0,0,0,0,0,0,0,0,0,0,0,0,0,0,0,0,0,0,0,0,0,0,0,0,0,0,0,0,0,0~
,0,0,0,AH11,0,0,0,0,0)';$S;BIDI;
    'MLA_DATA18':'(0,0,0,0,0,0,0,0,0,0,0,0,0,0,0,0,0,0,0,0,0,0,0,0,0,0,0,0,0,0,0~
,0,0,0,V9,0,0,0,0,0)';$S;BIDI;
    'ML0_CLK_H':'(0,0,0,0,0,0,0,0,0,0,0,0,0,0,0,0,0,0,0,0,0,0,0,0,0,0,0,0,0,0,0,~
0,0,0,BC9,0,0,0,0,0)';$S;OUT;
    'MLB_DQS_L0':'(0,0,0,0,0,0,0,0,0,0,0,0,0,0,0,0,0,0,0,0,0,0,0,0,0,0,0,0,0,0,0~
,0,0,0,CE9,0,0,0,0,0)';$S;BIDI;
    'MLB_DATA24':'(0,0,0,0,0,0,0,0,0,0,0,0,0,0,0,0,0,0,0,0,0,0,0,0,0,0,0,0,0,0,0~
,0,0,0,CY9,0,0,0,0,0)';$S;BIDI;
    'MLB_DATA13':'(0,0,0,0,0,0,0,0,0,0,0,0,0,0,0,0,0,0,0,0,0,0,0,0,0,0,0,0,0,0,0~
,0,0,0,CN10,0,0,0,0,0)';$S;BIDI;
    'MLB_CHECK4':'(0,0,0,0,0,0,0,0,0,0,0,0,0,0,0,0,0,0,0,0,0,0,0,0,0,0,0,0,0,0,0~
,0,0,0,BT9,0,0,0,0,0)';$S;BIDI;
    'MLA_DQS_L6':'(0,0,0,0,0,0,0,0,0,0,0,0,0,0,0,0,0,0,0,0,0,0,0,0,0,0,0,0,0,0,0~
,0,0,0,P11,0,0,0,0,0)';$S;BIDI;
    'MLA_DQS_H2':'(0,0,0,0,0,0,0,0,0,0,0,0,0,0,0,0,0,0,0,0,0,0,0,0,0,0,0,0,0,0,0~
,0,0,0,W9,0,0,0,0,0)';$S;BIDI;
    'MLA_DATA19':'(0,0,0,0,0,0,0,0,0,0,0,0,0,0,0,0,0,0,0,0,0,0,0,0,0,0,0,0,0,0,0~
,0,0,0,W10,0,0,0,0,0)';$S;BIDI;
    'ML1_CLK_H':'(0,0,0,0,0,0,0,0,0,0,0,0,0,0,0,0,0,0,0,0,0,0,0,0,0,0,0,0,0,0,0,~
0,0,0,BF9,0,0,0,0,0)';$S;OUT;
    'MLB_DQS_L1':'(0,0,0,0,0,0,0,0,0,0,0,0,0,0,0,0,0,0,0,0,0,0,0,0,0,0,0,0,0,0,0~
,0,0,0,CL9,0,0,0,0,0)';$S;BIDI;
    'MLB_DATA25':'(0,0,0,0,0,0,0,0,0,0,0,0,0,0,0,0,0,0,0,0,0,0,0,0,0,0,0,0,0,0,0~
,0,0,0,DA10,0,0,0,0,0)';$S;BIDI;
    'MLB_DATA14':'(0,0,0,0,0,0,0,0,0,0,0,0,0,0,0,0,0,0,0,0,0,0,0,0,0,0,0,0,0,0,0~
,0,0,0,CN9,0,0,0,0,0)';$S;BIDI;
    'MLB_CHECK5':'(0,0,0,0,0,0,0,0,0,0,0,0,0,0,0,0,0,0,0,0,0,0,0,0,0,0,0,0,0,0,0~
,0,0,0,BU10,0,0,0,0,0)';$S;BIDI;
    'MLA_DQS_L7':'(0,0,0,0,0,0,0,0,0,0,0,0,0,0,0,0,0,0,0,0,0,0,0,0,0,0,0,0,0,0,0~
,0,0,0,Y11,0,0,0,0,0)';$S;BIDI;
    'MLA_DQS_H3':'(0,0,0,0,0,0,0,0,0,0,0,0,0,0,0,0,0,0,0,0,0,0,0,0,0,0,0,0,0,0,0~
,0,0,0,AE9,0,0,0,0,0)';$S;BIDI;
    'MLB_DQS_L2':'(0,0,0,0,0,0,0,0,0,0,0,0,0,0,0,0,0,0,0,0,0,0,0,0,0,0,0,0,0,0,0~
,0,0,0,CU9,0,0,0,0,0)';$S;BIDI;
    'MLB_DATA26':'(0,0,0,0,0,0,0,0,0,0,0,0,0,0,0,0,0,0,0,0,0,0,0,0,0,0,0,0,0,0,0~
,0,0,0,DA9,0,0,0,0,0)';$S;BIDI;
    'MLB_DATA15':'(0,0,0,0,0,0,0,0,0,0,0,0,0,0,0,0,0,0,0,0,0,0,0,0,0,0,0,0,0,0,0~
,0,0,0,CP11,0,0,0,0,0)';$S;BIDI;
    'MLB_CHECK6':'(0,0,0,0,0,0,0,0,0,0,0,0,0,0,0,0,0,0,0,0,0,0,0,0,0,0,0,0,0,0,0~
,0,0,0,BU9,0,0,0,0,0)';$S;BIDI;
    'MLB0_RSP_L':'(0,0,0,0,0,0,0,0,0,0,0,0,0,0,0,0,0,0,0,0,0,0,0,0,0,0,0,0,0,0,0~
,0,0,0,BP9,0,0,0,0,0)';$S;IN;
    'MLA_DQS_L8':'(0,0,0,0,0,0,0,0,0,0,0,0,0,0,0,0,0,0,0,0,0,0,0,0,0,0,0,0,0,0,0~
,0,0,0,AF11,0,0,0,0,0)';$S;BIDI;
    'MLA_DQS_H4':'(0,0,0,0,0,0,0,0,0,0,0,0,0,0,0,0,0,0,0,0,0,0,0,0,0,0,0,0,0,0,0~
,0,0,0,AL9,0,0,0,0,0)';$S;BIDI;
    'MLB_DQS_L3':'(0,0,0,0,0,0,0,0,0,0,0,0,0,0,0,0,0,0,0,0,0,0,0,0,0,0,0,0,0,0,0~
,0,0,0,DC9,0,0,0,0,0)';$S;BIDI;
    'MLB_DATA27':'(0,0,0,0,0,0,0,0,0,0,0,0,0,0,0,0,0,0,0,0,0,0,0,0,0,0,0,0,0,0,0~
,0,0,0,DB11,0,0,0,0,0)';$S;BIDI;
    'MLB_DATA16':'(0,0,0,0,0,0,0,0,0,0,0,0,0,0,0,0,0,0,0,0,0,0,0,0,0,0,0,0,0,0,0~
,0,0,0,CP9,0,0,0,0,0)';$S;BIDI;
    'MLB_CHECK7':'(0,0,0,0,0,0,0,0,0,0,0,0,0,0,0,0,0,0,0,0,0,0,0,0,0,0,0,0,0,0,0~
,0,0,0,BV11,0,0,0,0,0)';$S;BIDI;
    'MLB1_RSP_L':'(0,0,0,0,0,0,0,0,0,0,0,0,0,0,0,0,0,0,0,0,0,0,0,0,0,0,0,0,0,0,0~
,0,0,0,BR9,0,0,0,0,0)';$S;IN;
    'MLA_PAR':'(0,0,0,0,0,0,0,0,0,0,0,0,0,0,0,0,0,0,0,0,0,0,0,0,0,0,0,0,0,0,0,0,~
0,0,BC10,0,0,0,0,0)';$S;OUT;
    'MLA_DQS_L9':'(0,0,0,0,0,0,0,0,0,0,0,0,0,0,0,0,0,0,0,0,0,0,0,0,0,0,0,0,0,0,0~
,0,0,0,AM11,0,0,0,0,0)';$S;BIDI;
    'MLA_DQS_H5':'(0,0,0,0,0,0,0,0,0,0,0,0,0,0,0,0,0,0,0,0,0,0,0,0,0,0,0,0,0,0,0~
,0,0,0,J10,0,0,0,0,0)';$S;BIDI;
    'ML0_CLK_L':'(0,0,0,0,0,0,0,0,0,0,0,0,0,0,0,0,0,0,0,0,0,0,0,0,0,0,0,0,0,0,0,~
0,0,0,BD9,0,0,0,0,0)';$S;OUT;
    'MLB_PAR':'(0,0,0,0,0,0,0,0,0,0,0,0,0,0,0,0,0,0,0,0,0,0,0,0,0,0,0,0,0,0,0,0,~
0,0,BL10,0,0,0,0,0)';$S;OUT;
    'MLB_DQS_L4':'(0,0,0,0,0,0,0,0,0,0,0,0,0,0,0,0,0,0,0,0,0,0,0,0,0,0,0,0,0,0,0~
,0,0,0,BW10,0,0,0,0,0)';$S;BIDI;
    'MLB_DQS_H0':'(0,0,0,0,0,0,0,0,0,0,0,0,0,0,0,0,0,0,0,0,0,0,0,0,0,0,0,0,0,0,0~
,0,0,0,CD9,0,0,0,0,0)';$S;BIDI;
    'MLB_DATA28':'(0,0,0,0,0,0,0,0,0,0,0,0,0,0,0,0,0,0,0,0,0,0,0,0,0,0,0,0,0,0,0~
,0,0,0,DD9,0,0,0,0,0)';$S;BIDI;
    'MLB_DATA17':'(0,0,0,0,0,0,0,0,0,0,0,0,0,0,0,0,0,0,0,0,0,0,0,0,0,0,0,0,0,0,0~
,0,0,0,CR10,0,0,0,0,0)';$S;BIDI;
    'MLA_DQS_H6':'(0,0,0,0,0,0,0,0,0,0,0,0,0,0,0,0,0,0,0,0,0,0,0,0,0,0,0,0,0,0,0~
,0,0,0,R10,0,0,0,0,0)';$S;BIDI;
    'MLA_DATA0':'(0,0,0,0,0,0,0,0,0,0,0,0,0,0,0,0,0,0,0,0,0,0,0,0,0,0,0,0,0,0,0,~
0,0,0,E9,0,0,0,0,0)';$S;BIDI;
    'MLA0_CS_L0':'(0,0,0,0,0,0,0,0,0,0,0,0,0,0,0,0,0,0,0,0,0,0,0,0,0,0,0,0,0,0,0~
,0,0,0,AU9,0,0,0,0,0)';$S;OUT;
    'ML1_CLK_L':'(0,0,0,0,0,0,0,0,0,0,0,0,0,0,0,0,0,0,0,0,0,0,0,0,0,0,0,0,0,0,0,~
0,0,0,BG9,0,0,0,0,0)';$S;OUT;
    'MLB_DQS_L5':'(0,0,0,0,0,0,0,0,0,0,0,0,0,0,0,0,0,0,0,0,0,0,0,0,0,0,0,0,0,0,0~
,0,0,0,CE10,0,0,0,0,0)';$S;BIDI;
    'MLB_DQS_H1':'(0,0,0,0,0,0,0,0,0,0,0,0,0,0,0,0,0,0,0,0,0,0,0,0,0,0,0,0,0,0,0~
,0,0,0,CK9,0,0,0,0,0)';$S;BIDI;
    'MLB_DATA29':'(0,0,0,0,0,0,0,0,0,0,0,0,0,0,0,0,0,0,0,0,0,0,0,0,0,0,0,0,0,0,0~
,0,0,0,DE10,0,0,0,0,0)';$S;BIDI;
    'MLB_DATA18':'(0,0,0,0,0,0,0,0,0,0,0,0,0,0,0,0,0,0,0,0,0,0,0,0,0,0,0,0,0,0,0~
,0,0,0,CR9,0,0,0,0,0)';$S;BIDI;
    'MLB_DATA0':'(0,0,0,0,0,0,0,0,0,0,0,0,0,0,0,0,0,0,0,0,0,0,0,0,0,0,0,0,0,0,0,~
0,0,0,CB9,0,0,0,0,0)';$S;BIDI;
    'MLA_DQS_H7':'(0,0,0,0,0,0,0,0,0,0,0,0,0,0,0,0,0,0,0,0,0,0,0,0,0,0,0,0,0,0,0~
,0,0,0,AA10,0,0,0,0,0)';$S;BIDI;
    'MLA_DATA1':'(0,0,0,0,0,0,0,0,0,0,0,0,0,0,0,0,0,0,0,0,0,0,0,0,0,0,0,0,0,0,0,~
0,0,0,F11,0,0,0,0,0)';$S;BIDI;
    'MLA1_CS_L0':'(0,0,0,0,0,0,0,0,0,0,0,0,0,0,0,0,0,0,0,0,0,0,0,0,0,0,0,0,0,0,0~
,0,0,0,AV9,0,0,0,0,0)';$S;OUT;
    'MLA0_CS_L1':'(0,0,0,0,0,0,0,0,0,0,0,0,0,0,0,0,0,0,0,0,0,0,0,0,0,0,0,0,0,0,0~
,0,0,0,AV11,0,0,0,0,0)';$S;OUT;
    'MLB_DQS_L6':'(0,0,0,0,0,0,0,0,0,0,0,0,0,0,0,0,0,0,0,0,0,0,0,0,0,0,0,0,0,0,0~
,0,0,0,CL10,0,0,0,0,0)';$S;BIDI;
    'MLB_DQS_H2':'(0,0,0,0,0,0,0,0,0,0,0,0,0,0,0,0,0,0,0,0,0,0,0,0,0,0,0,0,0,0,0~
,0,0,0,CT9,0,0,0,0,0)';$S;BIDI;
    'MLB_DATA19':'(0,0,0,0,0,0,0,0,0,0,0,0,0,0,0,0,0,0,0,0,0,0,0,0,0,0,0,0,0,0,0~
,0,0,0,CT11,0,0,0,0,0)';$S;BIDI;
    'MLB_DATA1':'(0,0,0,0,0,0,0,0,0,0,0,0,0,0,0,0,0,0,0,0,0,0,0,0,0,0,0,0,0,0,0,~
0,0,0,CC10,0,0,0,0,0)';$S;BIDI;
    'MLA_DQS_H8':'(0,0,0,0,0,0,0,0,0,0,0,0,0,0,0,0,0,0,0,0,0,0,0,0,0,0,0,0,0,0,0~
,0,0,0,AG10,0,0,0,0,0)';$S;BIDI;
    'MLA_DATA30':'(0,0,0,0,0,0,0,0,0,0,0,0,0,0,0,0,0,0,0,0,0,0,0,0,0,0,0,0,0,0,0~
,0,0,0,AH9,0,0,0,0,0)';$S;BIDI;
    'MLA_DATA2':'(0,0,0,0,0,0,0,0,0,0,0,0,0,0,0,0,0,0,0,0,0,0,0,0,0,0,0,0,0,0,0,~
0,0,0,F9,0,0,0,0,0)';$S;BIDI;
    'MLA1_CS_L1':'(0,0,0,0,0,0,0,0,0,0,0,0,0,0,0,0,0,0,0,0,0,0,0,0,0,0,0,0,0,0,0~
,0,0,0,AW10,0,0,0,0,0)';$S;OUT;
    'MLB_DQS_L7':'(0,0,0,0,0,0,0,0,0,0,0,0,0,0,0,0,0,0,0,0,0,0,0,0,0,0,0,0,0,0,0~
,0,0,0,CU10,0,0,0,0,0)';$S;BIDI;
    'MLB_DQS_H3':'(0,0,0,0,0,0,0,0,0,0,0,0,0,0,0,0,0,0,0,0,0,0,0,0,0,0,0,0,0,0,0~
,0,0,0,DB9,0,0,0,0,0)';$S;BIDI;
    'MLB_DATA2':'(0,0,0,0,0,0,0,0,0,0,0,0,0,0,0,0,0,0,0,0,0,0,0,0,0,0,0,0,0,0,0,~
0,0,0,CC9,0,0,0,0,0)';$S;BIDI;
    'MLA_DQS_H9':'(0,0,0,0,0,0,0,0,0,0,0,0,0,0,0,0,0,0,0,0,0,0,0,0,0,0,0,0,0,0,0~
,0,0,0,AN10,0,0,0,0,0)';$S;BIDI;
    'MLA_DATA31':'(0,0,0,0,0,0,0,0,0,0,0,0,0,0,0,0,0,0,0,0,0,0,0,0,0,0,0,0,0,0,0~
,0,0,0,AJ10,0,0,0,0,0)';$S;BIDI;
    'MLA_DATA20':'(0,0,0,0,0,0,0,0,0,0,0,0,0,0,0,0,0,0,0,0,0,0,0,0,0,0,0,0,0,0,0~
,0,0,0,AA9,0,0,0,0,0)';$S;BIDI;
    'MLA_DATA3':'(0,0,0,0,0,0,0,0,0,0,0,0,0,0,0,0,0,0,0,0,0,0,0,0,0,0,0,0,0,0,0,~
0,0,0,G10,0,0,0,0,0)';$S;BIDI;
    'MLA_CHECK0':'(0,0,0,0,0,0,0,0,0,0,0,0,0,0,0,0,0,0,0,0,0,0,0,0,0,0,0,0,0,0,0~
,0,0,0,AJ9,0,0,0,0,0)';$S;BIDI;
    'MLA_CA0':'(0,0,0,0,0,0,0,0,0,0,0,0,0,0,0,0,0,0,0,0,0,0,0,0,0,0,0,0,0,0,0,0,~
0,0,AW9,0,0,0,0,0)';$S;OUT;
    'MLB_DQS_L8':'(0,0,0,0,0,0,0,0,0,0,0,0,0,0,0,0,0,0,0,0,0,0,0,0,0,0,0,0,0,0,0~
,0,0,0,DC10,0,0,0,0,0)';$S;BIDI;
    'MLB_DQS_H4':'(0,0,0,0,0,0,0,0,0,0,0,0,0,0,0,0,0,0,0,0,0,0,0,0,0,0,0,0,0,0,0~
,0,0,0,BY11,0,0,0,0,0)';$S;BIDI;
    'MLB_DATA3':'(0,0,0,0,0,0,0,0,0,0,0,0,0,0,0,0,0,0,0,0,0,0,0,0,0,0,0,0,0,0,0,~
0,0,0,CD11,0,0,0,0,0)';$S;BIDI;
    'MLB_CA0':'(0,0,0,0,0,0,0,0,0,0,0,0,0,0,0,0,0,0,0,0,0,0,0,0,0,0,0,0,0,0,0,0,~
0,0,BG10,0,0,0,0,0)';$S;OUT;
    'MLA_DATA21':'(0,0,0,0,0,0,0,0,0,0,0,0,0,0,0,0,0,0,0,0,0,0,0,0,0,0,0,0,0,0,0~
,0,0,0,AB11,0,0,0,0,0)';$S;BIDI;
    'MLA_DATA10':'(0,0,0,0,0,0,0,0,0,0,0,0,0,0,0,0,0,0,0,0,0,0,0,0,0,0,0,0,0,0,0~
,0,0,0,M9,0,0,0,0,0)';$S;BIDI;
    'MLA_DATA4':'(0,0,0,0,0,0,0,0,0,0,0,0,0,0,0,0,0,0,0,0,0,0,0,0,0,0,0,0,0,0,0,~
0,0,0,J9,0,0,0,0,0)';$S;BIDI;
    'MLA_CHECK1':'(0,0,0,0,0,0,0,0,0,0,0,0,0,0,0,0,0,0,0,0,0,0,0,0,0,0,0,0,0,0,0~
,0,0,0,AK11,0,0,0,0,0)';$S;BIDI;
    'MLA_CA1':'(0,0,0,0,0,0,0,0,0,0,0,0,0,0,0,0,0,0,0,0,0,0,0,0,0,0,0,0,0,0,0,0,~
0,0,AY9,0,0,0,0,0)';$S;OUT;
    'TEST39L':'(0,0,0,0,0,0,0,0,0,0,0,0,0,0,0,0,0,0,0,0,0,0,0,0,0,0,0,0,0,0,0,0,~
0,0,BF11,0,0,0,0,0)';$S;OUT;
    'MKB_DQS_L6':'(0,0,0,0,0,0,0,0,0,0,0,0,0,0,0,0,0,0,0,0,0,0,0,0,0,0,0,0,0,0,0~
,0,0,0,0,CL7,0,0,0,0)';$S;BIDI;
    'MKB_DQS_H2':'(0,0,0,0,0,0,0,0,0,0,0,0,0,0,0,0,0,0,0,0,0,0,0,0,0,0,0,0,0,0,0~
,0,0,0,0,CT6,0,0,0,0)';$S;BIDI;
    'MKB_DATA19':'(0,0,0,0,0,0,0,0,0,0,0,0,0,0,0,0,0,0,0,0,0,0,0,0,0,0,0,0,0,0,0~
,0,0,0,0,CT7,0,0,0,0)';$S;BIDI;
    'MKB_CA0':'(0,0,0,0,0,0,0,0,0,0,0,0,0,0,0,0,0,0,0,0,0,0,0,0,0,0,0,0,0,0,0,0,~
0,0,0,BG7,0,0,0,0)';$S;OUT;
    'MKA_DQS_H8':'(0,0,0,0,0,0,0,0,0,0,0,0,0,0,0,0,0,0,0,0,0,0,0,0,0,0,0,0,0,0,0~
,0,0,0,0,AG7,0,0,0,0)';$S;BIDI;
    'MKA_DATA30':'(0,0,0,0,0,0,0,0,0,0,0,0,0,0,0,0,0,0,0,0,0,0,0,0,0,0,0,0,0,0,0~
,0,0,0,0,AH6,0,0,0,0)';$S;BIDI;
    'MKA_CA1':'(0,0,0,0,0,0,0,0,0,0,0,0,0,0,0,0,0,0,0,0,0,0,0,0,0,0,0,0,0,0,0,0,~
0,0,0,AY6,0,0,0,0)';$S;OUT;
    'MKA1_CS_L0':'(0,0,0,0,0,0,0,0,0,0,0,0,0,0,0,0,0,0,0,0,0,0,0,0,0,0,0,0,0,0,0~
,0,0,0,0,AV6,0,0,0,0)';$S;OUT;
    'MKA0_CS_L1':'(0,0,0,0,0,0,0,0,0,0,0,0,0,0,0,0,0,0,0,0,0,0,0,0,0,0,0,0,0,0,0~
,0,0,0,0,AV7,0,0,0,0)';$S;OUT;
    'MKB_DQS_L7':'(0,0,0,0,0,0,0,0,0,0,0,0,0,0,0,0,0,0,0,0,0,0,0,0,0,0,0,0,0,0,0~
,0,0,0,0,CU7,0,0,0,0)';$S;BIDI;
    'MKB_DQS_H3':'(0,0,0,0,0,0,0,0,0,0,0,0,0,0,0,0,0,0,0,0,0,0,0,0,0,0,0,0,0,0,0~
,0,0,0,0,DB6,0,0,0,0)';$S;BIDI;
    'MKB_CA1':'(0,0,0,0,0,0,0,0,0,0,0,0,0,0,0,0,0,0,0,0,0,0,0,0,0,0,0,0,0,0,0,0,~
0,0,0,BH7,0,0,0,0)';$S;OUT;
    'MKA_DQS_H9':'(0,0,0,0,0,0,0,0,0,0,0,0,0,0,0,0,0,0,0,0,0,0,0,0,0,0,0,0,0,0,0~
,0,0,0,0,AN7,0,0,0,0)';$S;BIDI;
    'MKA_DATA31':'(0,0,0,0,0,0,0,0,0,0,0,0,0,0,0,0,0,0,0,0,0,0,0,0,0,0,0,0,0,0,0~
,0,0,0,0,AJ7,0,0,0,0)';$S;BIDI;
    'MKA_DATA20':'(0,0,0,0,0,0,0,0,0,0,0,0,0,0,0,0,0,0,0,0,0,0,0,0,0,0,0,0,0,0,0~
,0,0,0,0,AA5,0,0,0,0)';$S;BIDI;
    'MKA_CHECK0':'(0,0,0,0,0,0,0,0,0,0,0,0,0,0,0,0,0,0,0,0,0,0,0,0,0,0,0,0,0,0,0~
,0,0,0,0,AJ5,0,0,0,0)';$S;BIDI;
    'MKA_CA2':'(0,0,0,0,0,0,0,0,0,0,0,0,0,0,0,0,0,0,0,0,0,0,0,0,0,0,0,0,0,0,0,0,~
0,0,0,AY7,0,0,0,0)';$S;OUT;
    'MKA1_CS_L1':'(0,0,0,0,0,0,0,0,0,0,0,0,0,0,0,0,0,0,0,0,0,0,0,0,0,0,0,0,0,0,0~
,0,0,0,0,AW7,0,0,0,0)';$S;OUT;
    'MK0_CLK_H':'(0,0,0,0,0,0,0,0,0,0,0,0,0,0,0,0,0,0,0,0,0,0,0,0,0,0,0,0,0,0,0,~
0,0,0,0,BC5,0,0,0,0)';$S;OUT;
    'MKB_DQS_L8':'(0,0,0,0,0,0,0,0,0,0,0,0,0,0,0,0,0,0,0,0,0,0,0,0,0,0,0,0,0,0,0~
,0,0,0,0,DC7,0,0,0,0)';$S;BIDI;
    'MKB_DQS_H4':'(0,0,0,0,0,0,0,0,0,0,0,0,0,0,0,0,0,0,0,0,0,0,0,0,0,0,0,0,0,0,0~
,0,0,0,0,BY7,0,0,0,0)';$S;BIDI;
    'MKB_CA2':'(0,0,0,0,0,0,0,0,0,0,0,0,0,0,0,0,0,0,0,0,0,0,0,0,0,0,0,0,0,0,0,0,~
0,0,0,BH6,0,0,0,0)';$S;OUT;
    'MKA_DATA21':'(0,0,0,0,0,0,0,0,0,0,0,0,0,0,0,0,0,0,0,0,0,0,0,0,0,0,0,0,0,0,0~
,0,0,0,0,AB7,0,0,0,0)';$S;BIDI;
    'MKA_DATA10':'(0,0,0,0,0,0,0,0,0,0,0,0,0,0,0,0,0,0,0,0,0,0,0,0,0,0,0,0,0,0,0~
,0,0,0,0,M6,0,0,0,0)';$S;BIDI;
    'MKA_CHECK1':'(0,0,0,0,0,0,0,0,0,0,0,0,0,0,0,0,0,0,0,0,0,0,0,0,0,0,0,0,0,0,0~
,0,0,0,0,AK7,0,0,0,0)';$S;BIDI;
    'MKA_CA3':'(0,0,0,0,0,0,0,0,0,0,0,0,0,0,0,0,0,0,0,0,0,0,0,0,0,0,0,0,0,0,0,0,~
0,0,0,BA7,0,0,0,0)';$S;OUT;
    'MK1_CLK_H':'(0,0,0,0,0,0,0,0,0,0,0,0,0,0,0,0,0,0,0,0,0,0,0,0,0,0,0,0,0,0,0,~
0,0,0,0,BF6,0,0,0,0)';$S;OUT;
    'MKB_DQS_L9':'(0,0,0,0,0,0,0,0,0,0,0,0,0,0,0,0,0,0,0,0,0,0,0,0,0,0,0,0,0,0,0~
,0,0,0,0,BW5,0,0,0,0)';$S;BIDI;
    'MKB_DQS_H5':'(0,0,0,0,0,0,0,0,0,0,0,0,0,0,0,0,0,0,0,0,0,0,0,0,0,0,0,0,0,0,0~
,0,0,0,0,CF7,0,0,0,0)';$S;BIDI;
    'MKB_CA3':'(0,0,0,0,0,0,0,0,0,0,0,0,0,0,0,0,0,0,0,0,0,0,0,0,0,0,0,0,0,0,0,0,~
0,0,0,BJ5,0,0,0,0)';$S;OUT;
    'MKA_DATA22':'(0,0,0,0,0,0,0,0,0,0,0,0,0,0,0,0,0,0,0,0,0,0,0,0,0,0,0,0,0,0,0~
,0,0,0,0,AB6,0,0,0,0)';$S;BIDI;
    'MKA_DATA11':'(0,0,0,0,0,0,0,0,0,0,0,0,0,0,0,0,0,0,0,0,0,0,0,0,0,0,0,0,0,0,0~
,0,0,0,0,N7,0,0,0,0)';$S;BIDI;
    'MKA_CHECK2':'(0,0,0,0,0,0,0,0,0,0,0,0,0,0,0,0,0,0,0,0,0,0,0,0,0,0,0,0,0,0,0~
,0,0,0,0,AK6,0,0,0,0)';$S;BIDI;
    'MKA_CA4':'(0,0,0,0,0,0,0,0,0,0,0,0,0,0,0,0,0,0,0,0,0,0,0,0,0,0,0,0,0,0,0,0,~
0,0,0,BA5,0,0,0,0)';$S;OUT;
    'MK_RESET_L':'(0,0,0,0,0,0,0,0,0,0,0,0,0,0,0,0,0,0,0,0,0,0,0,0,0,0,0,0,0,0,0~
,0,0,0,0,AU7,0,0,0,0)';$S;OUT;
    'MKB_DQS_H6':'(0,0,0,0,0,0,0,0,0,0,0,0,0,0,0,0,0,0,0,0,0,0,0,0,0,0,0,0,0,0,0~
,0,0,0,0,CM7,0,0,0,0)';$S;BIDI;
    'MKB_CA4':'(0,0,0,0,0,0,0,0,0,0,0,0,0,0,0,0,0,0,0,0,0,0,0,0,0,0,0,0,0,0,0,0,~
0,0,0,BJ7,0,0,0,0)';$S;OUT;
    'MKA_DATA23':'(0,0,0,0,0,0,0,0,0,0,0,0,0,0,0,0,0,0,0,0,0,0,0,0,0,0,0,0,0,0,0~
,0,0,0,0,AC7,0,0,0,0)';$S;BIDI;
    'MKA_DATA12':'(0,0,0,0,0,0,0,0,0,0,0,0,0,0,0,0,0,0,0,0,0,0,0,0,0,0,0,0,0,0,0~
,0,0,0,0,R5,0,0,0,0)';$S;BIDI;
    'MKA_CHECK3':'(0,0,0,0,0,0,0,0,0,0,0,0,0,0,0,0,0,0,0,0,0,0,0,0,0,0,0,0,0,0,0~
,0,0,0,0,AL7,0,0,0,0)';$S;BIDI;
    'MKA_CA5':'(0,0,0,0,0,0,0,0,0,0,0,0,0,0,0,0,0,0,0,0,0,0,0,0,0,0,0,0,0,0,0,0,~
0,0,0,BB6,0,0,0,0)';$S;OUT;
    'MKB_DQS_H7':'(0,0,0,0,0,0,0,0,0,0,0,0,0,0,0,0,0,0,0,0,0,0,0,0,0,0,0,0,0,0,0~
,0,0,0,0,CV7,0,0,0,0)';$S;BIDI;
    'MKB_CA5':'(0,0,0,0,0,0,0,0,0,0,0,0,0,0,0,0,0,0,0,0,0,0,0,0,0,0,0,0,0,0,0,0,~
0,0,0,BK7,0,0,0,0)';$S;OUT;
    'MKB0_CS_L0':'(0,0,0,0,0,0,0,0,0,0,0,0,0,0,0,0,0,0,0,0,0,0,0,0,0,0,0,0,0,0,0~
,0,0,0,0,BM7,0,0,0,0)';$S;OUT;
    'MKA_DQS_L0':'(0,0,0,0,0,0,0,0,0,0,0,0,0,0,0,0,0,0,0,0,0,0,0,0,0,0,0,0,0,0,0~
,0,0,0,0,H6,0,0,0,0)';$S;BIDI;
    'MKA_DATA24':'(0,0,0,0,0,0,0,0,0,0,0,0,0,0,0,0,0,0,0,0,0,0,0,0,0,0,0,0,0,0,0~
,0,0,0,0,AC5,0,0,0,0)';$S;BIDI;
    'MKA_DATA13':'(0,0,0,0,0,0,0,0,0,0,0,0,0,0,0,0,0,0,0,0,0,0,0,0,0,0,0,0,0,0,0~
,0,0,0,0,T7,0,0,0,0)';$S;BIDI;
    'MKA_CHECK4':'(0,0,0,0,0,0,0,0,0,0,0,0,0,0,0,0,0,0,0,0,0,0,0,0,0,0,0,0,0,0,0~
,0,0,0,0,AN5,0,0,0,0)';$S;BIDI;
    'MKA_CA6':'(0,0,0,0,0,0,0,0,0,0,0,0,0,0,0,0,0,0,0,0,0,0,0,0,0,0,0,0,0,0,0,0,~
0,0,0,BB7,0,0,0,0)';$S;OUT;
    'MK0_CLK_L':'(0,0,0,0,0,0,0,0,0,0,0,0,0,0,0,0,0,0,0,0,0,0,0,0,0,0,0,0,0,0,0,~
0,0,0,0,BD6,0,0,0,0)';$S;OUT;
    'MKB_DQS_H8':'(0,0,0,0,0,0,0,0,0,0,0,0,0,0,0,0,0,0,0,0,0,0,0,0,0,0,0,0,0,0,0~
,0,0,0,0,DD7,0,0,0,0)';$S;BIDI;
    'MKB_DATA30':'(0,0,0,0,0,0,0,0,0,0,0,0,0,0,0,0,0,0,0,0,0,0,0,0,0,0,0,0,0,0,0~
,0,0,0,0,DE5,0,0,0,0)';$S;BIDI;
    'MKB_CA6':'(0,0,0,0,0,0,0,0,0,0,0,0,0,0,0,0,0,0,0,0,0,0,0,0,0,0,0,0,0,0,0,0,~
0,0,0,BK6,0,0,0,0)';$S;OUT;
    'MKB1_CS_L0':'(0,0,0,0,0,0,0,0,0,0,0,0,0,0,0,0,0,0,0,0,0,0,0,0,0,0,0,0,0,0,0~
,0,0,0,0,BL5,0,0,0,0)';$S;OUT;
    'MKB0_CS_L1':'(0,0,0,0,0,0,0,0,0,0,0,0,0,0,0,0,0,0,0,0,0,0,0,0,0,0,0,0,0,0,0~
,0,0,0,0,BN5,0,0,0,0)';$S;OUT;
    'MKA_DQS_L1':'(0,0,0,0,0,0,0,0,0,0,0,0,0,0,0,0,0,0,0,0,0,0,0,0,0,0,0,0,0,0,0~
,0,0,0,0,P6,0,0,0,0)';$S;BIDI;
    'MKA_DATA25':'(0,0,0,0,0,0,0,0,0,0,0,0,0,0,0,0,0,0,0,0,0,0,0,0,0,0,0,0,0,0,0~
,0,0,0,0,AD7,0,0,0,0)';$S;BIDI;
    'MKA_DATA14':'(0,0,0,0,0,0,0,0,0,0,0,0,0,0,0,0,0,0,0,0,0,0,0,0,0,0,0,0,0,0,0~
,0,0,0,0,T6,0,0,0,0)';$S;BIDI;
    'MKA_DATA0':'(0,0,0,0,0,0,0,0,0,0,0,0,0,0,0,0,0,0,0,0,0,0,0,0,0,0,0,0,0,0,0,~
0,0,0,0,E5,0,0,0,0)';$S;BIDI;
    'MKA_CHECK5':'(0,0,0,0,0,0,0,0,0,0,0,0,0,0,0,0,0,0,0,0,0,0,0,0,0,0,0,0,0,0,0~
,0,0,0,0,AP7,0,0,0,0)';$S;BIDI;
    'MK1_CLK_L':'(0,0,0,0,0,0,0,0,0,0,0,0,0,0,0,0,0,0,0,0,0,0,0,0,0,0,0,0,0,0,0,~
0,0,0,0,BG5,0,0,0,0)';$S;OUT;
    'MKB_DQS_H9':'(0,0,0,0,0,0,0,0,0,0,0,0,0,0,0,0,0,0,0,0,0,0,0,0,0,0,0,0,0,0,0~
,0,0,0,0,BV6,0,0,0,0)';$S;BIDI;
    'MKB_DATA31':'(0,0,0,0,0,0,0,0,0,0,0,0,0,0,0,0,0,0,0,0,0,0,0,0,0,0,0,0,0,0,0~
,0,0,0,0,DF7,0,0,0,0)';$S;BIDI;
    'MKB_DATA20':'(0,0,0,0,0,0,0,0,0,0,0,0,0,0,0,0,0,0,0,0,0,0,0,0,0,0,0,0,0,0,0~
,0,0,0,0,CV6,0,0,0,0)';$S;BIDI;
    'MKB_DATA0':'(0,0,0,0,0,0,0,0,0,0,0,0,0,0,0,0,0,0,0,0,0,0,0,0,0,0,0,0,0,0,0,~
0,0,0,0,CB6,0,0,0,0)';$S;BIDI;
    'MKB_CHECK0':'(0,0,0,0,0,0,0,0,0,0,0,0,0,0,0,0,0,0,0,0,0,0,0,0,0,0,0,0,0,0,0~
,0,0,0,0,BY6,0,0,0,0)';$S;BIDI;
    'MKB1_CS_L1':'(0,0,0,0,0,0,0,0,0,0,0,0,0,0,0,0,0,0,0,0,0,0,0,0,0,0,0,0,0,0,0~
,0,0,0,0,BM6,0,0,0,0)';$S;OUT;
    'MKA_DQS_L2':'(0,0,0,0,0,0,0,0,0,0,0,0,0,0,0,0,0,0,0,0,0,0,0,0,0,0,0,0,0,0,0~
,0,0,0,0,Y6,0,0,0,0)';$S;BIDI;
    'MKA_DATA26':'(0,0,0,0,0,0,0,0,0,0,0,0,0,0,0,0,0,0,0,0,0,0,0,0,0,0,0,0,0,0,0~
,0,0,0,0,AD6,0,0,0,0)';$S;BIDI;
    'MKA_DATA15':'(0,0,0,0,0,0,0,0,0,0,0,0,0,0,0,0,0,0,0,0,0,0,0,0,0,0,0,0,0,0,0~
,0,0,0,0,U7,0,0,0,0)';$S;BIDI;
    'MKA_DATA1':'(0,0,0,0,0,0,0,0,0,0,0,0,0,0,0,0,0,0,0,0,0,0,0,0,0,0,0,0,0,0,0,~
0,0,0,0,F7,0,0,0,0)';$S;BIDI;
    'MKA_CHECK6':'(0,0,0,0,0,0,0,0,0,0,0,0,0,0,0,0,0,0,0,0,0,0,0,0,0,0,0,0,0,0,0~
,0,0,0,0,AP6,0,0,0,0)';$S;BIDI;
    'MKB_DATA21':'(0,0,0,0,0,0,0,0,0,0,0,0,0,0,0,0,0,0,0,0,0,0,0,0,0,0,0,0,0,0,0~
,0,0,0,0,CW7,0,0,0,0)';$S;BIDI;
    'MKB_DATA10':'(0,0,0,0,0,0,0,0,0,0,0,0,0,0,0,0,0,0,0,0,0,0,0,0,0,0,0,0,0,0,0~
,0,0,0,0,CJ5,0,0,0,0)';$S;BIDI;
    'MKB_DATA1':'(0,0,0,0,0,0,0,0,0,0,0,0,0,0,0,0,0,0,0,0,0,0,0,0,0,0,0,0,0,0,0,~
0,0,0,0,CC7,0,0,0,0)';$S;BIDI;
    'MKB_CHECK1':'(0,0,0,0,0,0,0,0,0,0,0,0,0,0,0,0,0,0,0,0,0,0,0,0,0,0,0,0,0,0,0~
,0,0,0,0,CA7,0,0,0,0)';$S;BIDI;
    'MKA_DQS_L3':'(0,0,0,0,0,0,0,0,0,0,0,0,0,0,0,0,0,0,0,0,0,0,0,0,0,0,0,0,0,0,0~
,0,0,0,0,AF6,0,0,0,0)';$S;BIDI;
    'MKA_DATA27':'(0,0,0,0,0,0,0,0,0,0,0,0,0,0,0,0,0,0,0,0,0,0,0,0,0,0,0,0,0,0,0~
,0,0,0,0,AE7,0,0,0,0)';$S;BIDI;
    'MKA_DATA16':'(0,0,0,0,0,0,0,0,0,0,0,0,0,0,0,0,0,0,0,0,0,0,0,0,0,0,0,0,0,0,0~
,0,0,0,0,U5,0,0,0,0)';$S;BIDI;
    'MKA_DATA2':'(0,0,0,0,0,0,0,0,0,0,0,0,0,0,0,0,0,0,0,0,0,0,0,0,0,0,0,0,0,0,0,~
0,0,0,0,F6,0,0,0,0)';$S;BIDI;
    'MKA_CHECK7':'(0,0,0,0,0,0,0,0,0,0,0,0,0,0,0,0,0,0,0,0,0,0,0,0,0,0,0,0,0,0,0~
,0,0,0,0,AR7,0,0,0,0)';$S;BIDI;
    'MKA0_RSP_L':'(0,0,0,0,0,0,0,0,0,0,0,0,0,0,0,0,0,0,0,0,0,0,0,0,0,0,0,0,0,0,0~
,0,0,0,0,BN7,0,0,0,0)';$S;IN;
    'MK_ALERT_L':'(0,0,0,0,0,0,0,0,0,0,0,0,0,0,0,0,0,0,0,0,0,0,0,0,0,0,0,0,0,0,0~
,0,0,0,0,AT7,0,0,0,0)';$S;IN;
    'MKB_DATA22':'(0,0,0,0,0,0,0,0,0,0,0,0,0,0,0,0,0,0,0,0,0,0,0,0,0,0,0,0,0,0,0~
,0,0,0,0,CW5,0,0,0,0)';$S;BIDI;
    'MKB_DATA11':'(0,0,0,0,0,0,0,0,0,0,0,0,0,0,0,0,0,0,0,0,0,0,0,0,0,0,0,0,0,0,0~
,0,0,0,0,CK7,0,0,0,0)';$S;BIDI;
    'MKB_DATA2':'(0,0,0,0,0,0,0,0,0,0,0,0,0,0,0,0,0,0,0,0,0,0,0,0,0,0,0,0,0,0,0,~
0,0,0,0,CC5,0,0,0,0)';$S;BIDI;
    'MKB_CHECK2':'(0,0,0,0,0,0,0,0,0,0,0,0,0,0,0,0,0,0,0,0,0,0,0,0,0,0,0,0,0,0,0~
,0,0,0,0,CA5,0,0,0,0)';$S;BIDI;
    'MKA_DQS_L4':'(0,0,0,0,0,0,0,0,0,0,0,0,0,0,0,0,0,0,0,0,0,0,0,0,0,0,0,0,0,0,0~
,0,0,0,0,AM6,0,0,0,0)';$S;BIDI;
    'MKA_DQS_H0':'(0,0,0,0,0,0,0,0,0,0,0,0,0,0,0,0,0,0,0,0,0,0,0,0,0,0,0,0,0,0,0~
,0,0,0,0,G5,0,0,0,0)';$S;BIDI;
    'MKA_DATA28':'(0,0,0,0,0,0,0,0,0,0,0,0,0,0,0,0,0,0,0,0,0,0,0,0,0,0,0,0,0,0,0~
,0,0,0,0,AG5,0,0,0,0)';$S;BIDI;
    'MKA_DATA17':'(0,0,0,0,0,0,0,0,0,0,0,0,0,0,0,0,0,0,0,0,0,0,0,0,0,0,0,0,0,0,0~
,0,0,0,0,V7,0,0,0,0)';$S;BIDI;
    'MKA_DATA3':'(0,0,0,0,0,0,0,0,0,0,0,0,0,0,0,0,0,0,0,0,0,0,0,0,0,0,0,0,0,0,0,~
0,0,0,0,G7,0,0,0,0)';$S;BIDI;
    'MKA1_RSP_L':'(0,0,0,0,0,0,0,0,0,0,0,0,0,0,0,0,0,0,0,0,0,0,0,0,0,0,0,0,0,0,0~
,0,0,0,0,BP7,0,0,0,0)';$S;IN;
    'MKB_DATA23':'(0,0,0,0,0,0,0,0,0,0,0,0,0,0,0,0,0,0,0,0,0,0,0,0,0,0,0,0,0,0,0~
,0,0,0,0,CY7,0,0,0,0)';$S;BIDI;
    'MKB_DATA12':'(0,0,0,0,0,0,0,0,0,0,0,0,0,0,0,0,0,0,0,0,0,0,0,0,0,0,0,0,0,0,0~
,0,0,0,0,CM6,0,0,0,0)';$S;BIDI;
    'MKB_DATA3':'(0,0,0,0,0,0,0,0,0,0,0,0,0,0,0,0,0,0,0,0,0,0,0,0,0,0,0,0,0,0,0,~
0,0,0,0,CD7,0,0,0,0)';$S;BIDI;
    'MKB_CHECK3':'(0,0,0,0,0,0,0,0,0,0,0,0,0,0,0,0,0,0,0,0,0,0,0,0,0,0,0,0,0,0,0~
,0,0,0,0,CB7,0,0,0,0)';$S;BIDI;
    'MKA_DQS_L5':'(0,0,0,0,0,0,0,0,0,0,0,0,0,0,0,0,0,0,0,0,0,0,0,0,0,0,0,0,0,0,0~
,0,0,0,0,H7,0,0,0,0)';$S;BIDI;
    'MKA_DQS_H1':'(0,0,0,0,0,0,0,0,0,0,0,0,0,0,0,0,0,0,0,0,0,0,0,0,0,0,0,0,0,0,0~
,0,0,0,0,N5,0,0,0,0)';$S;BIDI;
    'MKA_DATA29':'(0,0,0,0,0,0,0,0,0,0,0,0,0,0,0,0,0,0,0,0,0,0,0,0,0,0,0,0,0,0,0~
,0,0,0,0,AH7,0,0,0,0)';$S;BIDI;
    'MKA_DATA18':'(0,0,0,0,0,0,0,0,0,0,0,0,0,0,0,0,0,0,0,0,0,0,0,0,0,0,0,0,0,0,0~
,0,0,0,0,V6,0,0,0,0)';$S;BIDI;
    'MKA_DATA4':'(0,0,0,0,0,0,0,0,0,0,0,0,0,0,0,0,0,0,0,0,0,0,0,0,0,0,0,0,0,0,0,~
0,0,0,0,J5,0,0,0,0)';$S;BIDI;
    'MKB_DQS_L0':'(0,0,0,0,0,0,0,0,0,0,0,0,0,0,0,0,0,0,0,0,0,0,0,0,0,0,0,0,0,0,0~
,0,0,0,0,CE5,0,0,0,0)';$S;BIDI;
    'MKB_DATA24':'(0,0,0,0,0,0,0,0,0,0,0,0,0,0,0,0,0,0,0,0,0,0,0,0,0,0,0,0,0,0,0~
,0,0,0,0,CY6,0,0,0,0)';$S;BIDI;
    'MKB_DATA13':'(0,0,0,0,0,0,0,0,0,0,0,0,0,0,0,0,0,0,0,0,0,0,0,0,0,0,0,0,0,0,0~
,0,0,0,0,CN7,0,0,0,0)';$S;BIDI;
    'MKB_DATA4':'(0,0,0,0,0,0,0,0,0,0,0,0,0,0,0,0,0,0,0,0,0,0,0,0,0,0,0,0,0,0,0,~
0,0,0,0,CF6,0,0,0,0)';$S;BIDI;
    'MKB_CHECK4':'(0,0,0,0,0,0,0,0,0,0,0,0,0,0,0,0,0,0,0,0,0,0,0,0,0,0,0,0,0,0,0~
,0,0,0,0,BT6,0,0,0,0)';$S;BIDI;
    'MKA_DQS_L6':'(0,0,0,0,0,0,0,0,0,0,0,0,0,0,0,0,0,0,0,0,0,0,0,0,0,0,0,0,0,0,0~
,0,0,0,0,P7,0,0,0,0)';$S;BIDI;
    'MKA_DQS_H2':'(0,0,0,0,0,0,0,0,0,0,0,0,0,0,0,0,0,0,0,0,0,0,0,0,0,0,0,0,0,0,0~
,0,0,0,0,W5,0,0,0,0)';$S;BIDI;
    'MKA_DATA19':'(0,0,0,0,0,0,0,0,0,0,0,0,0,0,0,0,0,0,0,0,0,0,0,0,0,0,0,0,0,0,0~
,0,0,0,0,W7,0,0,0,0)';$S;BIDI;
    'MKA_DATA5':'(0,0,0,0,0,0,0,0,0,0,0,0,0,0,0,0,0,0,0,0,0,0,0,0,0,0,0,0,0,0,0,~
0,0,0,0,K7,0,0,0,0)';$S;BIDI;
    'MKB_DQS_L1':'(0,0,0,0,0,0,0,0,0,0,0,0,0,0,0,0,0,0,0,0,0,0,0,0,0,0,0,0,0,0,0~
,0,0,0,0,CL5,0,0,0,0)';$S;BIDI;
    'MKB_DATA25':'(0,0,0,0,0,0,0,0,0,0,0,0,0,0,0,0,0,0,0,0,0,0,0,0,0,0,0,0,0,0,0~
,0,0,0,0,DA7,0,0,0,0)';$S;BIDI;
    'MKB_DATA14':'(0,0,0,0,0,0,0,0,0,0,0,0,0,0,0,0,0,0,0,0,0,0,0,0,0,0,0,0,0,0,0~
,0,0,0,0,CN5,0,0,0,0)';$S;BIDI;
    'MKB_DATA5':'(0,0,0,0,0,0,0,0,0,0,0,0,0,0,0,0,0,0,0,0,0,0,0,0,0,0,0,0,0,0,0,~
0,0,0,0,CG7,0,0,0,0)';$S;BIDI;
    'MKB_CHECK5':'(0,0,0,0,0,0,0,0,0,0,0,0,0,0,0,0,0,0,0,0,0,0,0,0,0,0,0,0,0,0,0~
,0,0,0,0,BU7,0,0,0,0)';$S;BIDI;
    'MKA_PAR':'(0,0,0,0,0,0,0,0,0,0,0,0,0,0,0,0,0,0,0,0,0,0,0,0,0,0,0,0,0,0,0,0,~
0,0,0,BC7,0,0,0,0)';$S;OUT;
    'MKA_DQS_L7':'(0,0,0,0,0,0,0,0,0,0,0,0,0,0,0,0,0,0,0,0,0,0,0,0,0,0,0,0,0,0,0~
,0,0,0,0,Y7,0,0,0,0)';$S;BIDI;
    'MKA_DQS_H3':'(0,0,0,0,0,0,0,0,0,0,0,0,0,0,0,0,0,0,0,0,0,0,0,0,0,0,0,0,0,0,0~
,0,0,0,0,AE5,0,0,0,0)';$S;BIDI;
    'MKA_DATA6':'(0,0,0,0,0,0,0,0,0,0,0,0,0,0,0,0,0,0,0,0,0,0,0,0,0,0,0,0,0,0,0,~
0,0,0,0,K6,0,0,0,0)';$S;BIDI;
    'MKB_PAR':'(0,0,0,0,0,0,0,0,0,0,0,0,0,0,0,0,0,0,0,0,0,0,0,0,0,0,0,0,0,0,0,0,~
0,0,0,BL7,0,0,0,0)';$S;OUT;
    'MKB_DQS_L2':'(0,0,0,0,0,0,0,0,0,0,0,0,0,0,0,0,0,0,0,0,0,0,0,0,0,0,0,0,0,0,0~
,0,0,0,0,CU5,0,0,0,0)';$S;BIDI;
    'MKB_DATA26':'(0,0,0,0,0,0,0,0,0,0,0,0,0,0,0,0,0,0,0,0,0,0,0,0,0,0,0,0,0,0,0~
,0,0,0,0,DA5,0,0,0,0)';$S;BIDI;
    'MKB_DATA15':'(0,0,0,0,0,0,0,0,0,0,0,0,0,0,0,0,0,0,0,0,0,0,0,0,0,0,0,0,0,0,0~
,0,0,0,0,CP7,0,0,0,0)';$S;BIDI;
    'MKB_DATA6':'(0,0,0,0,0,0,0,0,0,0,0,0,0,0,0,0,0,0,0,0,0,0,0,0,0,0,0,0,0,0,0,~
0,0,0,0,CG5,0,0,0,0)';$S;BIDI;
    'MKB_CHECK6':'(0,0,0,0,0,0,0,0,0,0,0,0,0,0,0,0,0,0,0,0,0,0,0,0,0,0,0,0,0,0,0~
,0,0,0,0,BU5,0,0,0,0)';$S;BIDI;
    'MKA_DQS_L8':'(0,0,0,0,0,0,0,0,0,0,0,0,0,0,0,0,0,0,0,0,0,0,0,0,0,0,0,0,0,0,0~
,0,0,0,0,AF7,0,0,0,0)';$S;BIDI;
    'MKA_DQS_H4':'(0,0,0,0,0,0,0,0,0,0,0,0,0,0,0,0,0,0,0,0,0,0,0,0,0,0,0,0,0,0,0~
,0,0,0,0,AL5,0,0,0,0)';$S;BIDI;
    'MKA_DATA7':'(0,0,0,0,0,0,0,0,0,0,0,0,0,0,0,0,0,0,0,0,0,0,0,0,0,0,0,0,0,0,0,~
0,0,0,0,L7,0,0,0,0)';$S;BIDI;
    'MKB_DQS_L3':'(0,0,0,0,0,0,0,0,0,0,0,0,0,0,0,0,0,0,0,0,0,0,0,0,0,0,0,0,0,0,0~
,0,0,0,0,DC5,0,0,0,0)';$S;BIDI;
    'MKB_DATA27':'(0,0,0,0,0,0,0,0,0,0,0,0,0,0,0,0,0,0,0,0,0,0,0,0,0,0,0,0,0,0,0~
,0,0,0,0,DB7,0,0,0,0)';$S;BIDI;
    'MKB_DATA16':'(0,0,0,0,0,0,0,0,0,0,0,0,0,0,0,0,0,0,0,0,0,0,0,0,0,0,0,0,0,0,0~
,0,0,0,0,CP6,0,0,0,0)';$S;BIDI;
    'MKB_DATA7':'(0,0,0,0,0,0,0,0,0,0,0,0,0,0,0,0,0,0,0,0,0,0,0,0,0,0,0,0,0,0,0,~
0,0,0,0,CH7,0,0,0,0)';$S;BIDI;
    'MKB_CHECK7':'(0,0,0,0,0,0,0,0,0,0,0,0,0,0,0,0,0,0,0,0,0,0,0,0,0,0,0,0,0,0,0~
,0,0,0,0,BV7,0,0,0,0)';$S;BIDI;
    'MKB0_RSP_L':'(0,0,0,0,0,0,0,0,0,0,0,0,0,0,0,0,0,0,0,0,0,0,0,0,0,0,0,0,0,0,0~
,0,0,0,0,BP6,0,0,0,0)';$S;IN;
    'MKA_DQS_L9':'(0,0,0,0,0,0,0,0,0,0,0,0,0,0,0,0,0,0,0,0,0,0,0,0,0,0,0,0,0,0,0~
,0,0,0,0,AM7,0,0,0,0)';$S;BIDI;
    'MKA_DQS_H5':'(0,0,0,0,0,0,0,0,0,0,0,0,0,0,0,0,0,0,0,0,0,0,0,0,0,0,0,0,0,0,0~
,0,0,0,0,J7,0,0,0,0)';$S;BIDI;
    'MKA_DATA8':'(0,0,0,0,0,0,0,0,0,0,0,0,0,0,0,0,0,0,0,0,0,0,0,0,0,0,0,0,0,0,0,~
0,0,0,0,L5,0,0,0,0)';$S;BIDI;
    'MKB_DQS_L4':'(0,0,0,0,0,0,0,0,0,0,0,0,0,0,0,0,0,0,0,0,0,0,0,0,0,0,0,0,0,0,0~
,0,0,0,0,BW7,0,0,0,0)';$S;BIDI;
    'MKB_DQS_H0':'(0,0,0,0,0,0,0,0,0,0,0,0,0,0,0,0,0,0,0,0,0,0,0,0,0,0,0,0,0,0,0~
,0,0,0,0,CD6,0,0,0,0)';$S;BIDI;
    'MKB_DATA28':'(0,0,0,0,0,0,0,0,0,0,0,0,0,0,0,0,0,0,0,0,0,0,0,0,0,0,0,0,0,0,0~
,0,0,0,0,DD6,0,0,0,0)';$S;BIDI;
    'MKB_DATA17':'(0,0,0,0,0,0,0,0,0,0,0,0,0,0,0,0,0,0,0,0,0,0,0,0,0,0,0,0,0,0,0~
,0,0,0,0,CR7,0,0,0,0)';$S;BIDI;
    'MKB_DATA8':'(0,0,0,0,0,0,0,0,0,0,0,0,0,0,0,0,0,0,0,0,0,0,0,0,0,0,0,0,0,0,0,~
0,0,0,0,CH6,0,0,0,0)';$S;BIDI;
    'MKB1_RSP_L':'(0,0,0,0,0,0,0,0,0,0,0,0,0,0,0,0,0,0,0,0,0,0,0,0,0,0,0,0,0,0,0~
,0,0,0,0,BR5,0,0,0,0)';$S;IN;
    'MKA_DQS_H6':'(0,0,0,0,0,0,0,0,0,0,0,0,0,0,0,0,0,0,0,0,0,0,0,0,0,0,0,0,0,0,0~
,0,0,0,0,R7,0,0,0,0)';$S;BIDI;
    'MKA_DATA9':'(0,0,0,0,0,0,0,0,0,0,0,0,0,0,0,0,0,0,0,0,0,0,0,0,0,0,0,0,0,0,0,~
0,0,0,0,M7,0,0,0,0)';$S;BIDI;
    'MKB_DQS_L5':'(0,0,0,0,0,0,0,0,0,0,0,0,0,0,0,0,0,0,0,0,0,0,0,0,0,0,0,0,0,0,0~
,0,0,0,0,CE7,0,0,0,0)';$S;BIDI;
    'MKB_DQS_H1':'(0,0,0,0,0,0,0,0,0,0,0,0,0,0,0,0,0,0,0,0,0,0,0,0,0,0,0,0,0,0,0~
,0,0,0,0,CK6,0,0,0,0)';$S;BIDI;
    'MKB_DATA29':'(0,0,0,0,0,0,0,0,0,0,0,0,0,0,0,0,0,0,0,0,0,0,0,0,0,0,0,0,0,0,0~
,0,0,0,0,DE7,0,0,0,0)';$S;BIDI;
    'MKB_DATA18':'(0,0,0,0,0,0,0,0,0,0,0,0,0,0,0,0,0,0,0,0,0,0,0,0,0,0,0,0,0,0,0~
,0,0,0,0,CR5,0,0,0,0)';$S;BIDI;
    'MKB_DATA9':'(0,0,0,0,0,0,0,0,0,0,0,0,0,0,0,0,0,0,0,0,0,0,0,0,0,0,0,0,0,0,0,~
0,0,0,0,CJ7,0,0,0,0)';$S;BIDI;
    'MKA_DQS_H7':'(0,0,0,0,0,0,0,0,0,0,0,0,0,0,0,0,0,0,0,0,0,0,0,0,0,0,0,0,0,0,0~
,0,0,0,0,AA7,0,0,0,0)';$S;BIDI;
    'MKA_CA0':'(0,0,0,0,0,0,0,0,0,0,0,0,0,0,0,0,0,0,0,0,0,0,0,0,0,0,0,0,0,0,0,0,~
0,0,0,AW5,0,0,0,0)';$S;OUT;
    'MKA0_CS_L0':'(0,0,0,0,0,0,0,0,0,0,0,0,0,0,0,0,0,0,0,0,0,0,0,0,0,0,0,0,0,0,0~
,0,0,0,0,AU5,0,0,0,0)';$S;OUT;
    'TEST39K':'(0,0,0,0,0,0,0,0,0,0,0,0,0,0,0,0,0,0,0,0,0,0,0,0,0,0,0,0,0,0,0,0,~
0,0,0,BF7,0,0,0,0)';$S;OUT;
    'VSS_BV46':'(0,0,0,0,0,0,0,0,0,0,0,0,0,0,0,0,0,0,0,0,0,0,0,0,0,0,0,0,0,0,0,0~
,0,0,0,0,BV46,0,0,0)';$S;
    'VSS_BV47':'(0,0,0,0,0,0,0,0,0,0,0,0,0,0,0,0,0,0,0,0,0,0,0,0,0,0,0,0,0,0,0,0~
,0,0,0,0,BV47,0,0,0)';$S;
    'VSS_BV48':'(0,0,0,0,0,0,0,0,0,0,0,0,0,0,0,0,0,0,0,0,0,0,0,0,0,0,0,0,0,0,0,0~
,0,0,0,0,BV48,0,0,0)';$S;
    'VSS_BV49':'(0,0,0,0,0,0,0,0,0,0,0,0,0,0,0,0,0,0,0,0,0,0,0,0,0,0,0,0,0,0,0,0~
,0,0,0,0,BV49,0,0,0)';$S;
    'VSS_BV50':'(0,0,0,0,0,0,0,0,0,0,0,0,0,0,0,0,0,0,0,0,0,0,0,0,0,0,0,0,0,0,0,0~
,0,0,0,0,BV50,0,0,0)';$S;
    'VSS_BV51':'(0,0,0,0,0,0,0,0,0,0,0,0,0,0,0,0,0,0,0,0,0,0,0,0,0,0,0,0,0,0,0,0~
,0,0,0,0,BV51,0,0,0)';$S;
    'VSS_BV52':'(0,0,0,0,0,0,0,0,0,0,0,0,0,0,0,0,0,0,0,0,0,0,0,0,0,0,0,0,0,0,0,0~
,0,0,0,0,BV52,0,0,0)';$S;
    'VSS_BV53':'(0,0,0,0,0,0,0,0,0,0,0,0,0,0,0,0,0,0,0,0,0,0,0,0,0,0,0,0,0,0,0,0~
,0,0,0,0,BV53,0,0,0)';$S;
    'VSS_BV59':'(0,0,0,0,0,0,0,0,0,0,0,0,0,0,0,0,0,0,0,0,0,0,0,0,0,0,0,0,0,0,0,0~
,0,0,0,0,BV59,0,0,0)';$S;
    'VSS_BV61':'(0,0,0,0,0,0,0,0,0,0,0,0,0,0,0,0,0,0,0,0,0,0,0,0,0,0,0,0,0,0,0,0~
,0,0,0,0,BV61,0,0,0)';$S;
    'VSS_BV66':'(0,0,0,0,0,0,0,0,0,0,0,0,0,0,0,0,0,0,0,0,0,0,0,0,0,0,0,0,0,0,0,0~
,0,0,0,0,BV66,0,0,0)';$S;
    'VSS_BV68':'(0,0,0,0,0,0,0,0,0,0,0,0,0,0,0,0,0,0,0,0,0,0,0,0,0,0,0,0,0,0,0,0~
,0,0,0,0,BV68,0,0,0)';$S;
    'VSS_BV73':'(0,0,0,0,0,0,0,0,0,0,0,0,0,0,0,0,0,0,0,0,0,0,0,0,0,0,0,0,0,0,0,0~
,0,0,0,0,BV73,0,0,0)';$S;
    'VSS_BW1':'(0,0,0,0,0,0,0,0,0,0,0,0,0,0,0,0,0,0,0,0,0,0,0,0,0,0,0,0,0,0,0,0,~
0,0,0,0,BW1,0,0,0)';$S;
    'VSS_BW4':'(0,0,0,0,0,0,0,0,0,0,0,0,0,0,0,0,0,0,0,0,0,0,0,0,0,0,0,0,0,0,0,0,~
0,0,0,0,BW4,0,0,0)';$S;
    'VSS_BW6':'(0,0,0,0,0,0,0,0,0,0,0,0,0,0,0,0,0,0,0,0,0,0,0,0,0,0,0,0,0,0,0,0,~
0,0,0,0,BW6,0,0,0)';$S;
    'VSS_BW8':'(0,0,0,0,0,0,0,0,0,0,0,0,0,0,0,0,0,0,0,0,0,0,0,0,0,0,0,0,0,0,0,0,~
0,0,0,0,BW8,0,0,0)';$S;
    'VSS_BW11':'(0,0,0,0,0,0,0,0,0,0,0,0,0,0,0,0,0,0,0,0,0,0,0,0,0,0,0,0,0,0,0,0~
,0,0,0,0,BW11,0,0,0)';$S;
    'VSS_BW13':'(0,0,0,0,0,0,0,0,0,0,0,0,0,0,0,0,0,0,0,0,0,0,0,0,0,0,0,0,0,0,0,0~
,0,0,0,0,BW13,0,0,0)';$S;
    'VSS_BW15':'(0,0,0,0,0,0,0,0,0,0,0,0,0,0,0,0,0,0,0,0,0,0,0,0,0,0,0,0,0,0,0,0~
,0,0,0,0,BW15,0,0,0)';$S;
    'VSS_BW18':'(0,0,0,0,0,0,0,0,0,0,0,0,0,0,0,0,0,0,0,0,0,0,0,0,0,0,0,0,0,0,0,0~
,0,0,0,0,BW18,0,0,0)';$S;
    'VSS_BW20':'(0,0,0,0,0,0,0,0,0,0,0,0,0,0,0,0,0,0,0,0,0,0,0,0,0,0,0,0,0,0,0,0~
,0,0,0,0,BW20,0,0,0)';$S;
    'VSS_BW22':'(0,0,0,0,0,0,0,0,0,0,0,0,0,0,0,0,0,0,0,0,0,0,0,0,0,0,0,0,0,0,0,0~
,0,0,0,0,BW22,0,0,0)';$S;
    'VSS_BW28':'(0,0,0,0,0,0,0,0,0,0,0,0,0,0,0,0,0,0,0,0,0,0,0,0,0,0,0,0,0,0,0,0~
,0,0,0,0,BW28,0,0,0)';$S;
    'VSS_BW31':'(0,0,0,0,0,0,0,0,0,0,0,0,0,0,0,0,0,0,0,0,0,0,0,0,0,0,0,0,0,0,0,0~
,0,0,0,0,BW31,0,0,0)';$S;
    'VSS_BW34':'(0,0,0,0,0,0,0,0,0,0,0,0,0,0,0,0,0,0,0,0,0,0,0,0,0,0,0,0,0,0,0,0~
,0,0,0,0,BW34,0,0,0)';$S;
    'VSS_BW42':'(0,0,0,0,0,0,0,0,0,0,0,0,0,0,0,0,0,0,0,0,0,0,0,0,0,0,0,0,0,0,0,0~
,0,0,0,0,BW42,0,0,0)';$S;
    'VSS_BW45':'(0,0,0,0,0,0,0,0,0,0,0,0,0,0,0,0,0,0,0,0,0,0,0,0,0,0,0,0,0,0,0,0~
,0,0,0,0,BW45,0,0,0)';$S;
    'VSS_BW48':'(0,0,0,0,0,0,0,0,0,0,0,0,0,0,0,0,0,0,0,0,0,0,0,0,0,0,0,0,0,0,0,0~
,0,0,0,0,BW48,0,0,0)';$S;
    'VSS_BW51':'(0,0,0,0,0,0,0,0,0,0,0,0,0,0,0,0,0,0,0,0,0,0,0,0,0,0,0,0,0,0,0,0~
,0,0,0,0,BW51,0,0,0)';$S;
    'VSS_BW54':'(0,0,0,0,0,0,0,0,0,0,0,0,0,0,0,0,0,0,0,0,0,0,0,0,0,0,0,0,0,0,0,0~
,0,0,0,0,BW54,0,0,0)';$S;
    'VSS_BW56':'(0,0,0,0,0,0,0,0,0,0,0,0,0,0,0,0,0,0,0,0,0,0,0,0,0,0,0,0,0,0,0,0~
,0,0,0,0,BW56,0,0,0)';$S;
    'VSS_BW58':'(0,0,0,0,0,0,0,0,0,0,0,0,0,0,0,0,0,0,0,0,0,0,0,0,0,0,0,0,0,0,0,0~
,0,0,0,0,BW58,0,0,0)';$S;
    'VSS_BW61':'(0,0,0,0,0,0,0,0,0,0,0,0,0,0,0,0,0,0,0,0,0,0,0,0,0,0,0,0,0,0,0,0~
,0,0,0,0,BW61,0,0,0)';$S;
    'VSS_BW63':'(0,0,0,0,0,0,0,0,0,0,0,0,0,0,0,0,0,0,0,0,0,0,0,0,0,0,0,0,0,0,0,0~
,0,0,0,0,BW63,0,0,0)';$S;
    'VSS_BW65':'(0,0,0,0,0,0,0,0,0,0,0,0,0,0,0,0,0,0,0,0,0,0,0,0,0,0,0,0,0,0,0,0~
,0,0,0,0,BW65,0,0,0)';$S;
    'VSS_BW68':'(0,0,0,0,0,0,0,0,0,0,0,0,0,0,0,0,0,0,0,0,0,0,0,0,0,0,0,0,0,0,0,0~
,0,0,0,0,BW68,0,0,0)';$S;
    'VSS_BW70':'(0,0,0,0,0,0,0,0,0,0,0,0,0,0,0,0,0,0,0,0,0,0,0,0,0,0,0,0,0,0,0,0~
,0,0,0,0,BW70,0,0,0)';$S;
    'VSS_BW72':'(0,0,0,0,0,0,0,0,0,0,0,0,0,0,0,0,0,0,0,0,0,0,0,0,0,0,0,0,0,0,0,0~
,0,0,0,0,BW72,0,0,0)';$S;
    'VSS_BW75':'(0,0,0,0,0,0,0,0,0,0,0,0,0,0,0,0,0,0,0,0,0,0,0,0,0,0,0,0,0,0,0,0~
,0,0,0,0,BW75,0,0,0)';$S;
    'VSS_BY3':'(0,0,0,0,0,0,0,0,0,0,0,0,0,0,0,0,0,0,0,0,0,0,0,0,0,0,0,0,0,0,0,0,~
0,0,0,0,BY3,0,0,0)';$S;
    'VSS_BY5':'(0,0,0,0,0,0,0,0,0,0,0,0,0,0,0,0,0,0,0,0,0,0,0,0,0,0,0,0,0,0,0,0,~
0,0,0,0,BY5,0,0,0)';$S;
    'VSS_BY8':'(0,0,0,0,0,0,0,0,0,0,0,0,0,0,0,0,0,0,0,0,0,0,0,0,0,0,0,0,0,0,0,0,~
0,0,0,0,BY8,0,0,0)';$S;
    'VSS_BY10':'(0,0,0,0,0,0,0,0,0,0,0,0,0,0,0,0,0,0,0,0,0,0,0,0,0,0,0,0,0,0,0,0~
,0,0,0,0,BY10,0,0,0)';$S;
    'VSS_BY12':'(0,0,0,0,0,0,0,0,0,0,0,0,0,0,0,0,0,0,0,0,0,0,0,0,0,0,0,0,0,0,0,0~
,0,0,0,0,BY12,0,0,0)';$S;
    'VSS_BY15':'(0,0,0,0,0,0,0,0,0,0,0,0,0,0,0,0,0,0,0,0,0,0,0,0,0,0,0,0,0,0,0,0~
,0,0,0,0,BY15,0,0,0)';$S;
    'VSS_BY17':'(0,0,0,0,0,0,0,0,0,0,0,0,0,0,0,0,0,0,0,0,0,0,0,0,0,0,0,0,0,0,0,0~
,0,0,0,0,BY17,0,0,0)';$S;
    'VSS_BY19':'(0,0,0,0,0,0,0,0,0,0,0,0,0,0,0,0,0,0,0,0,0,0,0,0,0,0,0,0,0,0,0,0~
,0,0,0,0,BY19,0,0,0)';$S;
    'VSS_BY22':'(0,0,0,0,0,0,0,0,0,0,0,0,0,0,0,0,0,0,0,0,0,0,0,0,0,0,0,0,0,0,0,0~
,0,0,0,0,BY22,0,0,0)';$S;
    'VSS_BY25':'(0,0,0,0,0,0,0,0,0,0,0,0,0,0,0,0,0,0,0,0,0,0,0,0,0,0,0,0,0,0,0,0~
,0,0,0,0,BY25,0,0,0)';$S;
    'VSS_BY28':'(0,0,0,0,0,0,0,0,0,0,0,0,0,0,0,0,0,0,0,0,0,0,0,0,0,0,0,0,0,0,0,0~
,0,0,0,0,BY28,0,0,0)';$S;
    'VSS_BY31':'(0,0,0,0,0,0,0,0,0,0,0,0,0,0,0,0,0,0,0,0,0,0,0,0,0,0,0,0,0,0,0,0~
,0,0,0,0,BY31,0,0,0)';$S;
    'VSS_BY34':'(0,0,0,0,0,0,0,0,0,0,0,0,0,0,0,0,0,0,0,0,0,0,0,0,0,0,0,0,0,0,0,0~
,0,0,0,0,BY34,0,0,0)';$S;
    'VSS_BY37':'(0,0,0,0,0,0,0,0,0,0,0,0,0,0,0,0,0,0,0,0,0,0,0,0,0,0,0,0,0,0,0,0~
,0,0,0,0,BY37,0,0,0)';$S;
    'VSS_BY39':'(0,0,0,0,0,0,0,0,0,0,0,0,0,0,0,0,0,0,0,0,0,0,0,0,0,0,0,0,0,0,0,0~
,0,0,0,0,BY39,0,0,0)';$S;
    'VSS_BY42':'(0,0,0,0,0,0,0,0,0,0,0,0,0,0,0,0,0,0,0,0,0,0,0,0,0,0,0,0,0,0,0,0~
,0,0,0,0,BY42,0,0,0)';$S;
    'VSS_BY45':'(0,0,0,0,0,0,0,0,0,0,0,0,0,0,0,0,0,0,0,0,0,0,0,0,0,0,0,0,0,0,0,0~
,0,0,0,0,BY45,0,0,0)';$S;
    'VSS_BY48':'(0,0,0,0,0,0,0,0,0,0,0,0,0,0,0,0,0,0,0,0,0,0,0,0,0,0,0,0,0,0,0,0~
,0,0,0,0,BY48,0,0,0)';$S;
    'VSS_BY51':'(0,0,0,0,0,0,0,0,0,0,0,0,0,0,0,0,0,0,0,0,0,0,0,0,0,0,0,0,0,0,0,0~
,0,0,0,0,BY51,0,0,0)';$S;
    'VSS_BY54':'(0,0,0,0,0,0,0,0,0,0,0,0,0,0,0,0,0,0,0,0,0,0,0,0,0,0,0,0,0,0,0,0~
,0,0,0,0,BY54,0,0,0)';$S;
    'VSS_BY57':'(0,0,0,0,0,0,0,0,0,0,0,0,0,0,0,0,0,0,0,0,0,0,0,0,0,0,0,0,0,0,0,0~
,0,0,0,0,BY57,0,0,0)';$S;
    'VSS_BY59':'(0,0,0,0,0,0,0,0,0,0,0,0,0,0,0,0,0,0,0,0,0,0,0,0,0,0,0,0,0,0,0,0~
,0,0,0,0,BY59,0,0,0)';$S;
    'VSS_BY61':'(0,0,0,0,0,0,0,0,0,0,0,0,0,0,0,0,0,0,0,0,0,0,0,0,0,0,0,0,0,0,0,0~
,0,0,0,0,BY61,0,0,0)';$S;
    'VSS_BY64':'(0,0,0,0,0,0,0,0,0,0,0,0,0,0,0,0,0,0,0,0,0,0,0,0,0,0,0,0,0,0,0,0~
,0,0,0,0,BY64,0,0,0)';$S;
    'VSS_BY66':'(0,0,0,0,0,0,0,0,0,0,0,0,0,0,0,0,0,0,0,0,0,0,0,0,0,0,0,0,0,0,0,0~
,0,0,0,0,BY66,0,0,0)';$S;
    'VSS_BY68':'(0,0,0,0,0,0,0,0,0,0,0,0,0,0,0,0,0,0,0,0,0,0,0,0,0,0,0,0,0,0,0,0~
,0,0,0,0,BY68,0,0,0)';$S;
    'VSS_BY71':'(0,0,0,0,0,0,0,0,0,0,0,0,0,0,0,0,0,0,0,0,0,0,0,0,0,0,0,0,0,0,0,0~
,0,0,0,0,BY71,0,0,0)';$S;
    'VSS_BY73':'(0,0,0,0,0,0,0,0,0,0,0,0,0,0,0,0,0,0,0,0,0,0,0,0,0,0,0,0,0,0,0,0~
,0,0,0,0,BY73,0,0,0)';$S;
    'VSS_CA1':'(0,0,0,0,0,0,0,0,0,0,0,0,0,0,0,0,0,0,0,0,0,0,0,0,0,0,0,0,0,0,0,0,~
0,0,0,0,CA1,0,0,0)';$S;
    'VSS_CA6':'(0,0,0,0,0,0,0,0,0,0,0,0,0,0,0,0,0,0,0,0,0,0,0,0,0,0,0,0,0,0,0,0,~
0,0,0,0,CA6,0,0,0)';$S;
    'VSS_CA8':'(0,0,0,0,0,0,0,0,0,0,0,0,0,0,0,0,0,0,0,0,0,0,0,0,0,0,0,0,0,0,0,0,~
0,0,0,0,CA8,0,0,0)';$S;
    'VSS_CA13':'(0,0,0,0,0,0,0,0,0,0,0,0,0,0,0,0,0,0,0,0,0,0,0,0,0,0,0,0,0,0,0,0~
,0,0,0,0,CA13,0,0,0)';$S;
    'VSS_CA15':'(0,0,0,0,0,0,0,0,0,0,0,0,0,0,0,0,0,0,0,0,0,0,0,0,0,0,0,0,0,0,0,0~
,0,0,0,0,CA15,0,0,0)';$S;
    'VSS_CA20':'(0,0,0,0,0,0,0,0,0,0,0,0,0,0,0,0,0,0,0,0,0,0,0,0,0,0,0,0,0,0,0,0~
,0,0,0,0,CA20,0,0,0)';$S;
    'VSS_CA22':'(0,0,0,0,0,0,0,0,0,0,0,0,0,0,0,0,0,0,0,0,0,0,0,0,0,0,0,0,0,0,0,0~
,0,0,0,0,CA22,0,0,0)';$S;
    'VSS_CA25':'(0,0,0,0,0,0,0,0,0,0,0,0,0,0,0,0,0,0,0,0,0,0,0,0,0,0,0,0,0,0,0,0~
,0,0,0,0,CA25,0,0,0)';$S;
    'VSS_CA28':'(0,0,0,0,0,0,0,0,0,0,0,0,0,0,0,0,0,0,0,0,0,0,0,0,0,0,0,0,0,0,0,0~
,0,0,0,0,CA28,0,0,0)';$S;
    'VSS_CA31':'(0,0,0,0,0,0,0,0,0,0,0,0,0,0,0,0,0,0,0,0,0,0,0,0,0,0,0,0,0,0,0,0~
,0,0,0,0,CA31,0,0,0)';$S;
    'VSS_CA34':'(0,0,0,0,0,0,0,0,0,0,0,0,0,0,0,0,0,0,0,0,0,0,0,0,0,0,0,0,0,0,0,0~
,0,0,0,0,CA34,0,0,0)';$S;
    'VSS_CA35':'(0,0,0,0,0,0,0,0,0,0,0,0,0,0,0,0,0,0,0,0,0,0,0,0,0,0,0,0,0,0,0,0~
,0,0,0,0,CA35,0,0,0)';$S;
    'VSS_CA36':'(0,0,0,0,0,0,0,0,0,0,0,0,0,0,0,0,0,0,0,0,0,0,0,0,0,0,0,0,0,0,0,0~
,0,0,0,0,CA36,0,0,0)';$S;
    'VSS_CA40':'(0,0,0,0,0,0,0,0,0,0,0,0,0,0,0,0,0,0,0,0,0,0,0,0,0,0,0,0,0,0,0,0~
,0,0,0,0,CA40,0,0,0)';$S;
    'VSS_CA41':'(0,0,0,0,0,0,0,0,0,0,0,0,0,0,0,0,0,0,0,0,0,0,0,0,0,0,0,0,0,0,0,0~
,0,0,0,0,CA41,0,0,0)';$S;
    'VSS_CA42':'(0,0,0,0,0,0,0,0,0,0,0,0,0,0,0,0,0,0,0,0,0,0,0,0,0,0,0,0,0,0,0,0~
,0,0,0,0,CA42,0,0,0)';$S;
    'VSS_CA45':'(0,0,0,0,0,0,0,0,0,0,0,0,0,0,0,0,0,0,0,0,0,0,0,0,0,0,0,0,0,0,0,0~
,0,0,0,0,CA45,0,0,0)';$S;
    'VSS_CA48':'(0,0,0,0,0,0,0,0,0,0,0,0,0,0,0,0,0,0,0,0,0,0,0,0,0,0,0,0,0,0,0,0~
,0,0,0,0,CA48,0,0,0)';$S;
    'VSS_CA51':'(0,0,0,0,0,0,0,0,0,0,0,0,0,0,0,0,0,0,0,0,0,0,0,0,0,0,0,0,0,0,0,0~
,0,0,0,0,CA51,0,0,0)';$S;
    'VSS_CA54':'(0,0,0,0,0,0,0,0,0,0,0,0,0,0,0,0,0,0,0,0,0,0,0,0,0,0,0,0,0,0,0,0~
,0,0,0,0,CA54,0,0,0)';$S;
    'VSS_CA56':'(0,0,0,0,0,0,0,0,0,0,0,0,0,0,0,0,0,0,0,0,0,0,0,0,0,0,0,0,0,0,0,0~
,0,0,0,0,CA56,0,0,0)';$S;
    'VSS_CA61':'(0,0,0,0,0,0,0,0,0,0,0,0,0,0,0,0,0,0,0,0,0,0,0,0,0,0,0,0,0,0,0,0~
,0,0,0,0,CA61,0,0,0)';$S;
    'VSS_CA63':'(0,0,0,0,0,0,0,0,0,0,0,0,0,0,0,0,0,0,0,0,0,0,0,0,0,0,0,0,0,0,0,0~
,0,0,0,0,CA63,0,0,0)';$S;
    'VSS_CA68':'(0,0,0,0,0,0,0,0,0,0,0,0,0,0,0,0,0,0,0,0,0,0,0,0,0,0,0,0,0,0,0,0~
,0,0,0,0,CA68,0,0,0)';$S;
    'VSS_CA70':'(0,0,0,0,0,0,0,0,0,0,0,0,0,0,0,0,0,0,0,0,0,0,0,0,0,0,0,0,0,0,0,0~
,0,0,0,0,CA70,0,0,0)';$S;
    'VSS_CA75':'(0,0,0,0,0,0,0,0,0,0,0,0,0,0,0,0,0,0,0,0,0,0,0,0,0,0,0,0,0,0,0,0~
,0,0,0,0,CA75,0,0,0)';$S;
    'VSS_CB3':'(0,0,0,0,0,0,0,0,0,0,0,0,0,0,0,0,0,0,0,0,0,0,0,0,0,0,0,0,0,0,0,0,~
0,0,0,0,CB3,0,0,0)';$S;
    'VSS_CB5':'(0,0,0,0,0,0,0,0,0,0,0,0,0,0,0,0,0,0,0,0,0,0,0,0,0,0,0,0,0,0,0,0,~
0,0,0,0,CB5,0,0,0)';$S;
    'VSS_CB8':'(0,0,0,0,0,0,0,0,0,0,0,0,0,0,0,0,0,0,0,0,0,0,0,0,0,0,0,0,0,0,0,0,~
0,0,0,0,CB8,0,0,0)';$S;
    'VSS_CB10':'(0,0,0,0,0,0,0,0,0,0,0,0,0,0,0,0,0,0,0,0,0,0,0,0,0,0,0,0,0,0,0,0~
,0,0,0,0,CB10,0,0,0)';$S;
    'VSS_CB12':'(0,0,0,0,0,0,0,0,0,0,0,0,0,0,0,0,0,0,0,0,0,0,0,0,0,0,0,0,0,0,0,0~
,0,0,0,0,CB12,0,0,0)';$S;
    'VSS_CB15':'(0,0,0,0,0,0,0,0,0,0,0,0,0,0,0,0,0,0,0,0,0,0,0,0,0,0,0,0,0,0,0,0~
,0,0,0,0,CB15,0,0,0)';$S;
    'VSS_CB17':'(0,0,0,0,0,0,0,0,0,0,0,0,0,0,0,0,0,0,0,0,0,0,0,0,0,0,0,0,0,0,0,0~
,0,0,0,0,CB17,0,0,0)';$S;
    'VSS_CB19':'(0,0,0,0,0,0,0,0,0,0,0,0,0,0,0,0,0,0,0,0,0,0,0,0,0,0,0,0,0,0,0,0~
,0,0,0,0,CB19,0,0,0)';$S;
    'VSS_CB23':'(0,0,0,0,0,0,0,0,0,0,0,0,0,0,0,0,0,0,0,0,0,0,0,0,0,0,0,0,0,0,0,0~
,0,0,0,0,CB23,0,0,0)';$S;
    'VSS_CB24':'(0,0,0,0,0,0,0,0,0,0,0,0,0,0,0,0,0,0,0,0,0,0,0,0,0,0,0,0,0,0,0,0~
,0,0,0,0,CB24,0,0,0)';$S;
    'VSS_CB25':'(0,0,0,0,0,0,0,0,0,0,0,0,0,0,0,0,0,0,0,0,0,0,0,0,0,0,0,0,0,0,0,0~
,0,0,0,0,CB25,0,0,0)';$S;
    'VSS_CB26':'(0,0,0,0,0,0,0,0,0,0,0,0,0,0,0,0,0,0,0,0,0,0,0,0,0,0,0,0,0,0,0,0~
,0,0,0,0,CB26,0,0,0)';$S;
    'VSS_CB27':'(0,0,0,0,0,0,0,0,0,0,0,0,0,0,0,0,0,0,0,0,0,0,0,0,0,0,0,0,0,0,0,0~
,0,0,0,0,CB27,0,0,0)';$S;
    'VSS_CB28':'(0,0,0,0,0,0,0,0,0,0,0,0,0,0,0,0,0,0,0,0,0,0,0,0,0,0,0,0,0,0,0,0~
,0,0,0,0,CB28,0,0,0)';$S;
    'VSS_CB29':'(0,0,0,0,0,0,0,0,0,0,0,0,0,0,0,0,0,0,0,0,0,0,0,0,0,0,0,0,0,0,0,0~
,0,0,0,0,CB29,0,0,0)';$S;
    'VSS_CB30':'(0,0,0,0,0,0,0,0,0,0,0,0,0,0,0,0,0,0,0,0,0,0,0,0,0,0,0,0,0,0,0,0~
,0,0,0,0,CB30,0,0,0)';$S;
    'VSS_CB31':'(0,0,0,0,0,0,0,0,0,0,0,0,0,0,0,0,0,0,0,0,0,0,0,0,0,0,0,0,0,0,0,0~
,0,0,0,0,CB31,0,0,0)';$S;
    'VSS_CB32':'(0,0,0,0,0,0,0,0,0,0,0,0,0,0,0,0,0,0,0,0,0,0,0,0,0,0,0,0,0,0,0,0~
,0,0,0,0,CB32,0,0,0)';$S;
    'VSS_CB33':'(0,0,0,0,0,0,0,0,0,0,0,0,0,0,0,0,0,0,0,0,0,0,0,0,0,0,0,0,0,0,0,0~
,0,0,0,0,CB33,0,0,0)';$S;
    'VSS_CB34':'(0,0,0,0,0,0,0,0,0,0,0,0,0,0,0,0,0,0,0,0,0,0,0,0,0,0,0,0,0,0,0,0~
,0,0,0,0,CB34,0,0,0)';$S;
    'VSS_CB37':'(0,0,0,0,0,0,0,0,0,0,0,0,0,0,0,0,0,0,0,0,0,0,0,0,0,0,0,0,0,0,0,0~
,0,0,0,0,CB37,0,0,0)';$S;
    'VSS_CB39':'(0,0,0,0,0,0,0,0,0,0,0,0,0,0,0,0,0,0,0,0,0,0,0,0,0,0,0,0,0,0,0,0~
,0,0,0,0,CB39,0,0,0)';$S;
    'VSS_CB42':'(0,0,0,0,0,0,0,0,0,0,0,0,0,0,0,0,0,0,0,0,0,0,0,0,0,0,0,0,0,0,0,0~
,0,0,0,0,CB42,0,0,0)';$S;
    'VSS_CB43':'(0,0,0,0,0,0,0,0,0,0,0,0,0,0,0,0,0,0,0,0,0,0,0,0,0,0,0,0,0,0,0,0~
,0,0,0,0,CB43,0,0,0)';$S;
    'VSS_CB45':'(0,0,0,0,0,0,0,0,0,0,0,0,0,0,0,0,0,0,0,0,0,0,0,0,0,0,0,0,0,0,0,0~
,0,0,0,0,CB45,0,0,0)';$S;
    'VSS_CB46':'(0,0,0,0,0,0,0,0,0,0,0,0,0,0,0,0,0,0,0,0,0,0,0,0,0,0,0,0,0,0,0,0~
,0,0,0,0,CB46,0,0,0)';$S;
    'VSS_CB47':'(0,0,0,0,0,0,0,0,0,0,0,0,0,0,0,0,0,0,0,0,0,0,0,0,0,0,0,0,0,0,0,0~
,0,0,0,0,CB47,0,0,0)';$S;
    'VSS_CB48':'(0,0,0,0,0,0,0,0,0,0,0,0,0,0,0,0,0,0,0,0,0,0,0,0,0,0,0,0,0,0,0,0~
,0,0,0,0,CB48,0,0,0)';$S;
    'VSS_CB49':'(0,0,0,0,0,0,0,0,0,0,0,0,0,0,0,0,0,0,0,0,0,0,0,0,0,0,0,0,0,0,0,0~
,0,0,0,0,CB49,0,0,0)';$S;
    'VSS_CB50':'(0,0,0,0,0,0,0,0,0,0,0,0,0,0,0,0,0,0,0,0,0,0,0,0,0,0,0,0,0,0,0,0~
,0,0,0,0,CB50,0,0,0)';$S;
    'VSS_CB51':'(0,0,0,0,0,0,0,0,0,0,0,0,0,0,0,0,0,0,0,0,0,0,0,0,0,0,0,0,0,0,0,0~
,0,0,0,0,CB51,0,0,0)';$S;
    'VSS_CB52':'(0,0,0,0,0,0,0,0,0,0,0,0,0,0,0,0,0,0,0,0,0,0,0,0,0,0,0,0,0,0,0,0~
,0,0,0,0,CB52,0,0,0)';$S;
    'VSS_CB53':'(0,0,0,0,0,0,0,0,0,0,0,0,0,0,0,0,0,0,0,0,0,0,0,0,0,0,0,0,0,0,0,0~
,0,0,0,0,CB53,0,0,0)';$S;
    'VSS_CB57':'(0,0,0,0,0,0,0,0,0,0,0,0,0,0,0,0,0,0,0,0,0,0,0,0,0,0,0,0,0,0,0,0~
,0,0,0,0,CB57,0,0,0)';$S;
    'VSS_CB59':'(0,0,0,0,0,0,0,0,0,0,0,0,0,0,0,0,0,0,0,0,0,0,0,0,0,0,0,0,0,0,0,0~
,0,0,0,0,CB59,0,0,0)';$S;
    'VSS_CB61':'(0,0,0,0,0,0,0,0,0,0,0,0,0,0,0,0,0,0,0,0,0,0,0,0,0,0,0,0,0,0,0,0~
,0,0,0,0,CB61,0,0,0)';$S;
    'VSS_CB64':'(0,0,0,0,0,0,0,0,0,0,0,0,0,0,0,0,0,0,0,0,0,0,0,0,0,0,0,0,0,0,0,0~
,0,0,0,0,CB64,0,0,0)';$S;
    'VSS_CB66':'(0,0,0,0,0,0,0,0,0,0,0,0,0,0,0,0,0,0,0,0,0,0,0,0,0,0,0,0,0,0,0,0~
,0,0,0,0,CB66,0,0,0)';$S;
    'VSS_CB68':'(0,0,0,0,0,0,0,0,0,0,0,0,0,0,0,0,0,0,0,0,0,0,0,0,0,0,0,0,0,0,0,0~
,0,0,0,0,CB68,0,0,0)';$S;
    'VSS_CB71':'(0,0,0,0,0,0,0,0,0,0,0,0,0,0,0,0,0,0,0,0,0,0,0,0,0,0,0,0,0,0,0,0~
,0,0,0,0,CB71,0,0,0)';$S;
    'VSS_CB73':'(0,0,0,0,0,0,0,0,0,0,0,0,0,0,0,0,0,0,0,0,0,0,0,0,0,0,0,0,0,0,0,0~
,0,0,0,0,CB73,0,0,0)';$S;
    'VSS_CC1':'(0,0,0,0,0,0,0,0,0,0,0,0,0,0,0,0,0,0,0,0,0,0,0,0,0,0,0,0,0,0,0,0,~
0,0,0,0,CC1,0,0,0)';$S;
    'VSS_CC4':'(0,0,0,0,0,0,0,0,0,0,0,0,0,0,0,0,0,0,0,0,0,0,0,0,0,0,0,0,0,0,0,0,~
0,0,0,0,CC4,0,0,0)';$S;
    'VSS_CC6':'(0,0,0,0,0,0,0,0,0,0,0,0,0,0,0,0,0,0,0,0,0,0,0,0,0,0,0,0,0,0,0,0,~
0,0,0,0,CC6,0,0,0)';$S;
    'VSS_CC8':'(0,0,0,0,0,0,0,0,0,0,0,0,0,0,0,0,0,0,0,0,0,0,0,0,0,0,0,0,0,0,0,0,~
0,0,0,0,CC8,0,0,0)';$S;
    'VSS_CC11':'(0,0,0,0,0,0,0,0,0,0,0,0,0,0,0,0,0,0,0,0,0,0,0,0,0,0,0,0,0,0,0,0~
,0,0,0,0,CC11,0,0,0)';$S;
    'VSS_CC13':'(0,0,0,0,0,0,0,0,0,0,0,0,0,0,0,0,0,0,0,0,0,0,0,0,0,0,0,0,0,0,0,0~
,0,0,0,0,CC13,0,0,0)';$S;
    'VSS_CC15':'(0,0,0,0,0,0,0,0,0,0,0,0,0,0,0,0,0,0,0,0,0,0,0,0,0,0,0,0,0,0,0,0~
,0,0,0,0,CC15,0,0,0)';$S;
    'VSS_CC18':'(0,0,0,0,0,0,0,0,0,0,0,0,0,0,0,0,0,0,0,0,0,0,0,0,0,0,0,0,0,0,0,0~
,0,0,0,0,CC18,0,0,0)';$S;
    'VSS_CC20':'(0,0,0,0,0,0,0,0,0,0,0,0,0,0,0,0,0,0,0,0,0,0,0,0,0,0,0,0,0,0,0,0~
,0,0,0,0,CC20,0,0,0)';$S;
    'VSS_CC25':'(0,0,0,0,0,0,0,0,0,0,0,0,0,0,0,0,0,0,0,0,0,0,0,0,0,0,0,0,0,0,0,0~
,0,0,0,0,CC25,0,0,0)';$S;
    'VSS_CC28':'(0,0,0,0,0,0,0,0,0,0,0,0,0,0,0,0,0,0,0,0,0,0,0,0,0,0,0,0,0,0,0,0~
,0,0,0,0,CC28,0,0,0)';$S;
    'VSS_CC31':'(0,0,0,0,0,0,0,0,0,0,0,0,0,0,0,0,0,0,0,0,0,0,0,0,0,0,0,0,0,0,0,0~
,0,0,0,0,CC31,0,0,0)';$S;
    'VSS_CC34':'(0,0,0,0,0,0,0,0,0,0,0,0,0,0,0,0,0,0,0,0,0,0,0,0,0,0,0,0,0,0,0,0~
,0,0,0,0,CC34,0,0,0)';$S;
    'VSS_CC42':'(0,0,0,0,0,0,0,0,0,0,0,0,0,0,0,0,0,0,0,0,0,0,0,0,0,0,0,0,0,0,0,0~
,0,0,0,0,CC42,0,0,0)';$S;
    'VSS_CC45':'(0,0,0,0,0,0,0,0,0,0,0,0,0,0,0,0,0,0,0,0,0,0,0,0,0,0,0,0,0,0,0,0~
,0,0,0,0,CC45,0,0,0)';$S;
    'VSS_CC48':'(0,0,0,0,0,0,0,0,0,0,0,0,0,0,0,0,0,0,0,0,0,0,0,0,0,0,0,0,0,0,0,0~
,0,0,0,0,CC48,0,0,0)';$S;
    'VSS_CC51':'(0,0,0,0,0,0,0,0,0,0,0,0,0,0,0,0,0,0,0,0,0,0,0,0,0,0,0,0,0,0,0,0~
,0,0,0,0,CC51,0,0,0)';$S;
    'VSS_CC54':'(0,0,0,0,0,0,0,0,0,0,0,0,0,0,0,0,0,0,0,0,0,0,0,0,0,0,0,0,0,0,0,0~
,0,0,0,0,CC54,0,0,0)';$S;
    'VSS_CC56':'(0,0,0,0,0,0,0,0,0,0,0,0,0,0,0,0,0,0,0,0,0,0,0,0,0,0,0,0,0,0,0,0~
,0,0,0,0,CC56,0,0,0)';$S;
    'VSS_CC58':'(0,0,0,0,0,0,0,0,0,0,0,0,0,0,0,0,0,0,0,0,0,0,0,0,0,0,0,0,0,0,0,0~
,0,0,0,0,CC58,0,0,0)';$S;
    'VSS_CC61':'(0,0,0,0,0,0,0,0,0,0,0,0,0,0,0,0,0,0,0,0,0,0,0,0,0,0,0,0,0,0,0,0~
,0,0,0,0,CC61,0,0,0)';$S;
    'VSS_CC63':'(0,0,0,0,0,0,0,0,0,0,0,0,0,0,0,0,0,0,0,0,0,0,0,0,0,0,0,0,0,0,0,0~
,0,0,0,0,CC63,0,0,0)';$S;
    'VSS_CC65':'(0,0,0,0,0,0,0,0,0,0,0,0,0,0,0,0,0,0,0,0,0,0,0,0,0,0,0,0,0,0,0,0~
,0,0,0,0,CC65,0,0,0)';$S;
    'VSS_CC68':'(0,0,0,0,0,0,0,0,0,0,0,0,0,0,0,0,0,0,0,0,0,0,0,0,0,0,0,0,0,0,0,0~
,0,0,0,0,CC68,0,0,0)';$S;
    'VSS_CC70':'(0,0,0,0,0,0,0,0,0,0,0,0,0,0,0,0,0,0,0,0,0,0,0,0,0,0,0,0,0,0,0,0~
,0,0,0,0,CC70,0,0,0)';$S;
    'VSS_CC72':'(0,0,0,0,0,0,0,0,0,0,0,0,0,0,0,0,0,0,0,0,0,0,0,0,0,0,0,0,0,0,0,0~
,0,0,0,0,CC72,0,0,0)';$S;
    'VSS_CC75':'(0,0,0,0,0,0,0,0,0,0,0,0,0,0,0,0,0,0,0,0,0,0,0,0,0,0,0,0,0,0,0,0~
,0,0,0,0,CC75,0,0,0)';$S;
    'VSS_CD3':'(0,0,0,0,0,0,0,0,0,0,0,0,0,0,0,0,0,0,0,0,0,0,0,0,0,0,0,0,0,0,0,0,~
0,0,0,0,CD3,0,0,0)';$S;
    'VSS_CD8':'(0,0,0,0,0,0,0,0,0,0,0,0,0,0,0,0,0,0,0,0,0,0,0,0,0,0,0,0,0,0,0,0,~
0,0,0,0,CD8,0,0,0)';$S;
    'VSS_CD10':'(0,0,0,0,0,0,0,0,0,0,0,0,0,0,0,0,0,0,0,0,0,0,0,0,0,0,0,0,0,0,0,0~
,0,0,0,0,CD10,0,0,0)';$S;
    'VSS_CD15':'(0,0,0,0,0,0,0,0,0,0,0,0,0,0,0,0,0,0,0,0,0,0,0,0,0,0,0,0,0,0,0,0~
,0,0,0,0,CD15,0,0,0)';$S;
    'VSS_CD17':'(0,0,0,0,0,0,0,0,0,0,0,0,0,0,0,0,0,0,0,0,0,0,0,0,0,0,0,0,0,0,0,0~
,0,0,0,0,CD17,0,0,0)';$S;
    'VSS_CD22':'(0,0,0,0,0,0,0,0,0,0,0,0,0,0,0,0,0,0,0,0,0,0,0,0,0,0,0,0,0,0,0,0~
,0,0,0,0,CD22,0,0,0)';$S;
    'VSS_CD25':'(0,0,0,0,0,0,0,0,0,0,0,0,0,0,0,0,0,0,0,0,0,0,0,0,0,0,0,0,0,0,0,0~
,0,0,0,0,CD25,0,0,0)';$S;
    'VSS_CD28':'(0,0,0,0,0,0,0,0,0,0,0,0,0,0,0,0,0,0,0,0,0,0,0,0,0,0,0,0,0,0,0,0~
,0,0,0,0,CD28,0,0,0)';$S;
    'VSS_CD31':'(0,0,0,0,0,0,0,0,0,0,0,0,0,0,0,0,0,0,0,0,0,0,0,0,0,0,0,0,0,0,0,0~
,0,0,0,0,CD31,0,0,0)';$S;
    'VSS_CD34':'(0,0,0,0,0,0,0,0,0,0,0,0,0,0,0,0,0,0,0,0,0,0,0,0,0,0,0,0,0,0,0,0~
,0,0,0,0,CD34,0,0,0)';$S;
    'VSS_CD37':'(0,0,0,0,0,0,0,0,0,0,0,0,0,0,0,0,0,0,0,0,0,0,0,0,0,0,0,0,0,0,0,0~
,0,0,0,0,CD37,0,0,0)';$S;
    'VSS_CD39':'(0,0,0,0,0,0,0,0,0,0,0,0,0,0,0,0,0,0,0,0,0,0,0,0,0,0,0,0,0,0,0,0~
,0,0,0,0,CD39,0,0,0)';$S;
    'VSS_CD42':'(0,0,0,0,0,0,0,0,0,0,0,0,0,0,0,0,0,0,0,0,0,0,0,0,0,0,0,0,0,0,0,0~
,0,0,0,0,CD42,0,0,0)';$S;
    'VSS_CD45':'(0,0,0,0,0,0,0,0,0,0,0,0,0,0,0,0,0,0,0,0,0,0,0,0,0,0,0,0,0,0,0,0~
,0,0,0,0,CD45,0,0,0)';$S;
    'VSS_CD48':'(0,0,0,0,0,0,0,0,0,0,0,0,0,0,0,0,0,0,0,0,0,0,0,0,0,0,0,0,0,0,0,0~
,0,0,0,0,CD48,0,0,0)';$S;
    'VSS_CD51':'(0,0,0,0,0,0,0,0,0,0,0,0,0,0,0,0,0,0,0,0,0,0,0,0,0,0,0,0,0,0,0,0~
,0,0,0,0,CD51,0,0,0)';$S;
    'VSS_CD54':'(0,0,0,0,0,0,0,0,0,0,0,0,0,0,0,0,0,0,0,0,0,0,0,0,0,0,0,0,0,0,0,0~
,0,0,0,0,CD54,0,0,0)';$S;
    'VSS_CD59':'(0,0,0,0,0,0,0,0,0,0,0,0,0,0,0,0,0,0,0,0,0,0,0,0,0,0,0,0,0,0,0,0~
,0,0,0,0,CD59,0,0,0)';$S;
    'VSS_CD61':'(0,0,0,0,0,0,0,0,0,0,0,0,0,0,0,0,0,0,0,0,0,0,0,0,0,0,0,0,0,0,0,0~
,0,0,0,0,CD61,0,0,0)';$S;
    'VSS_CD66':'(0,0,0,0,0,0,0,0,0,0,0,0,0,0,0,0,0,0,0,0,0,0,0,0,0,0,0,0,0,0,0,0~
,0,0,0,0,CD66,0,0,0)';$S;
    'VSS_CD68':'(0,0,0,0,0,0,0,0,0,0,0,0,0,0,0,0,0,0,0,0,0,0,0,0,0,0,0,0,0,0,0,0~
,0,0,0,0,CD68,0,0,0)';$S;
    'VSS_CD73':'(0,0,0,0,0,0,0,0,0,0,0,0,0,0,0,0,0,0,0,0,0,0,0,0,0,0,0,0,0,0,0,0~
,0,0,0,0,CD73,0,0,0)';$S;
    'VSS_CE1':'(0,0,0,0,0,0,0,0,0,0,0,0,0,0,0,0,0,0,0,0,0,0,0,0,0,0,0,0,0,0,0,0,~
0,0,0,0,CE1,0,0,0)';$S;
    'VSS_CE4':'(0,0,0,0,0,0,0,0,0,0,0,0,0,0,0,0,0,0,0,0,0,0,0,0,0,0,0,0,0,0,0,0,~
0,0,0,0,CE4,0,0,0)';$S;
    'VSS_CE6':'(0,0,0,0,0,0,0,0,0,0,0,0,0,0,0,0,0,0,0,0,0,0,0,0,0,0,0,0,0,0,0,0,~
0,0,0,0,CE6,0,0,0)';$S;
    'VSS_CE8':'(0,0,0,0,0,0,0,0,0,0,0,0,0,0,0,0,0,0,0,0,0,0,0,0,0,0,0,0,0,0,0,0,~
0,0,0,0,CE8,0,0,0)';$S;
    'VSS_CE11':'(0,0,0,0,0,0,0,0,0,0,0,0,0,0,0,0,0,0,0,0,0,0,0,0,0,0,0,0,0,0,0,0~
,0,0,0,0,CE11,0,0,0)';$S;
    'VSS_CE13':'(0,0,0,0,0,0,0,0,0,0,0,0,0,0,0,0,0,0,0,0,0,0,0,0,0,0,0,0,0,0,0,0~
,0,0,0,0,CE13,0,0,0)';$S;
    'VSS_CE15':'(0,0,0,0,0,0,0,0,0,0,0,0,0,0,0,0,0,0,0,0,0,0,0,0,0,0,0,0,0,0,0,0~
,0,0,0,0,CE15,0,0,0)';$S;
    'VSS_CE18':'(0,0,0,0,0,0,0,0,0,0,0,0,0,0,0,0,0,0,0,0,0,0,0,0,0,0,0,0,0,0,0,0~
,0,0,0,0,CE18,0,0,0)';$S;
    'VSS_CE20':'(0,0,0,0,0,0,0,0,0,0,0,0,0,0,0,0,0,0,0,0,0,0,0,0,0,0,0,0,0,0,0,0~
,0,0,0,0,CE20,0,0,0)';$S;
    'VSS_CE22':'(0,0,0,0,0,0,0,0,0,0,0,0,0,0,0,0,0,0,0,0,0,0,0,0,0,0,0,0,0,0,0,0~
,0,0,0,0,CE22,0,0,0)';$S;
    'VSS_CE25':'(0,0,0,0,0,0,0,0,0,0,0,0,0,0,0,0,0,0,0,0,0,0,0,0,0,0,0,0,0,0,0,0~
,0,0,0,0,CE25,0,0,0)';$S;
    'VSS_CE28':'(0,0,0,0,0,0,0,0,0,0,0,0,0,0,0,0,0,0,0,0,0,0,0,0,0,0,0,0,0,0,0,0~
,0,0,0,0,CE28,0,0,0)';$S;
    'VSS_CE31':'(0,0,0,0,0,0,0,0,0,0,0,0,0,0,0,0,0,0,0,0,0,0,0,0,0,0,0,0,0,0,0,0~
,0,0,0,0,CE31,0,0,0)';$S;
    'VSS_CE34':'(0,0,0,0,0,0,0,0,0,0,0,0,0,0,0,0,0,0,0,0,0,0,0,0,0,0,0,0,0,0,0,0~
,0,0,0,0,CE34,0,0,0)';$S;
    'VSS_CE35':'(0,0,0,0,0,0,0,0,0,0,0,0,0,0,0,0,0,0,0,0,0,0,0,0,0,0,0,0,0,0,0,0~
,0,0,0,0,CE35,0,0,0)';$S;
    'VSS_CE36':'(0,0,0,0,0,0,0,0,0,0,0,0,0,0,0,0,0,0,0,0,0,0,0,0,0,0,0,0,0,0,0,0~
,0,0,0,0,CE36,0,0,0)';$S;
    'VSS_CE40':'(0,0,0,0,0,0,0,0,0,0,0,0,0,0,0,0,0,0,0,0,0,0,0,0,0,0,0,0,0,0,0,0~
,0,0,0,0,CE40,0,0,0)';$S;
    'VSS_CE41':'(0,0,0,0,0,0,0,0,0,0,0,0,0,0,0,0,0,0,0,0,0,0,0,0,0,0,0,0,0,0,0,0~
,0,0,0,0,CE41,0,0,0)';$S;
    'VSS_CE42':'(0,0,0,0,0,0,0,0,0,0,0,0,0,0,0,0,0,0,0,0,0,0,0,0,0,0,0,0,0,0,0,0~
,0,0,0,0,CE42,0,0,0)';$S;
    'VSS_CE45':'(0,0,0,0,0,0,0,0,0,0,0,0,0,0,0,0,0,0,0,0,0,0,0,0,0,0,0,0,0,0,0,0~
,0,0,0,0,CE45,0,0,0)';$S;
    'VSS_CE48':'(0,0,0,0,0,0,0,0,0,0,0,0,0,0,0,0,0,0,0,0,0,0,0,0,0,0,0,0,0,0,0,0~
,0,0,0,0,CE48,0,0,0)';$S;
    'VSS_CE51':'(0,0,0,0,0,0,0,0,0,0,0,0,0,0,0,0,0,0,0,0,0,0,0,0,0,0,0,0,0,0,0,0~
,0,0,0,0,CE51,0,0,0)';$S;
    'VSS_CE54':'(0,0,0,0,0,0,0,0,0,0,0,0,0,0,0,0,0,0,0,0,0,0,0,0,0,0,0,0,0,0,0,0~
,0,0,0,0,CE54,0,0,0)';$S;
    'VSS_CE56':'(0,0,0,0,0,0,0,0,0,0,0,0,0,0,0,0,0,0,0,0,0,0,0,0,0,0,0,0,0,0,0,0~
,0,0,0,0,CE56,0,0,0)';$S;
    'VSS_CE58':'(0,0,0,0,0,0,0,0,0,0,0,0,0,0,0,0,0,0,0,0,0,0,0,0,0,0,0,0,0,0,0,0~
,0,0,0,0,CE58,0,0,0)';$S;
    'VSS_CE61':'(0,0,0,0,0,0,0,0,0,0,0,0,0,0,0,0,0,0,0,0,0,0,0,0,0,0,0,0,0,0,0,0~
,0,0,0,0,CE61,0,0,0)';$S;
    'VSS_CE63':'(0,0,0,0,0,0,0,0,0,0,0,0,0,0,0,0,0,0,0,0,0,0,0,0,0,0,0,0,0,0,0,0~
,0,0,0,0,CE63,0,0,0)';$S;
    'VSS_CE65':'(0,0,0,0,0,0,0,0,0,0,0,0,0,0,0,0,0,0,0,0,0,0,0,0,0,0,0,0,0,0,0,0~
,0,0,0,0,CE65,0,0,0)';$S;
    'VSS_CE68':'(0,0,0,0,0,0,0,0,0,0,0,0,0,0,0,0,0,0,0,0,0,0,0,0,0,0,0,0,0,0,0,0~
,0,0,0,0,CE68,0,0,0)';$S;
    'VSS_CE70':'(0,0,0,0,0,0,0,0,0,0,0,0,0,0,0,0,0,0,0,0,0,0,0,0,0,0,0,0,0,0,0,0~
,0,0,0,0,CE70,0,0,0)';$S;
    'VSS_CE72':'(0,0,0,0,0,0,0,0,0,0,0,0,0,0,0,0,0,0,0,0,0,0,0,0,0,0,0,0,0,0,0,0~
,0,0,0,0,CE72,0,0,0)';$S;
    'VSS_CE75':'(0,0,0,0,0,0,0,0,0,0,0,0,0,0,0,0,0,0,0,0,0,0,0,0,0,0,0,0,0,0,0,0~
,0,0,0,0,CE75,0,0,0)';$S;
    'VSS_CF3':'(0,0,0,0,0,0,0,0,0,0,0,0,0,0,0,0,0,0,0,0,0,0,0,0,0,0,0,0,0,0,0,0,~
0,0,0,0,CF3,0,0,0)';$S;
    'VSS_CF5':'(0,0,0,0,0,0,0,0,0,0,0,0,0,0,0,0,0,0,0,0,0,0,0,0,0,0,0,0,0,0,0,0,~
0,0,0,0,CF5,0,0,0)';$S;
    'VSS_CF8':'(0,0,0,0,0,0,0,0,0,0,0,0,0,0,0,0,0,0,0,0,0,0,0,0,0,0,0,0,0,0,0,0,~
0,0,0,0,CF8,0,0,0)';$S;
    'VSS_CF10':'(0,0,0,0,0,0,0,0,0,0,0,0,0,0,0,0,0,0,0,0,0,0,0,0,0,0,0,0,0,0,0,0~
,0,0,0,0,CF10,0,0,0)';$S;
    'VSS_CF12':'(0,0,0,0,0,0,0,0,0,0,0,0,0,0,0,0,0,0,0,0,0,0,0,0,0,0,0,0,0,0,0,0~
,0,0,0,0,CF12,0,0,0)';$S;
    'VSS_CF15':'(0,0,0,0,0,0,0,0,0,0,0,0,0,0,0,0,0,0,0,0,0,0,0,0,0,0,0,0,0,0,0,0~
,0,0,0,0,CF15,0,0,0)';$S;
    'VSS_CF17':'(0,0,0,0,0,0,0,0,0,0,0,0,0,0,0,0,0,0,0,0,0,0,0,0,0,0,0,0,0,0,0,0~
,0,0,0,0,CF17,0,0,0)';$S;
    'VSS_CF19':'(0,0,0,0,0,0,0,0,0,0,0,0,0,0,0,0,0,0,0,0,0,0,0,0,0,0,0,0,0,0,0,0~
,0,0,0,0,CF19,0,0,0)';$S;
    'VSS_CF23':'(0,0,0,0,0,0,0,0,0,0,0,0,0,0,0,0,0,0,0,0,0,0,0,0,0,0,0,0,0,0,0,0~
,0,0,0,0,CF23,0,0,0)';$S;
    'VSS_CF24':'(0,0,0,0,0,0,0,0,0,0,0,0,0,0,0,0,0,0,0,0,0,0,0,0,0,0,0,0,0,0,0,0~
,0,0,0,0,CF24,0,0,0)';$S;
    'VSS_CF25':'(0,0,0,0,0,0,0,0,0,0,0,0,0,0,0,0,0,0,0,0,0,0,0,0,0,0,0,0,0,0,0,0~
,0,0,0,0,CF25,0,0,0)';$S;
    'VSS_CF26':'(0,0,0,0,0,0,0,0,0,0,0,0,0,0,0,0,0,0,0,0,0,0,0,0,0,0,0,0,0,0,0,0~
,0,0,0,0,CF26,0,0,0)';$S;
    'VSS_CF27':'(0,0,0,0,0,0,0,0,0,0,0,0,0,0,0,0,0,0,0,0,0,0,0,0,0,0,0,0,0,0,0,0~
,0,0,0,0,CF27,0,0,0)';$S;
    'VSS_CF28':'(0,0,0,0,0,0,0,0,0,0,0,0,0,0,0,0,0,0,0,0,0,0,0,0,0,0,0,0,0,0,0,0~
,0,0,0,0,CF28,0,0,0)';$S;
    'VSS_CF29':'(0,0,0,0,0,0,0,0,0,0,0,0,0,0,0,0,0,0,0,0,0,0,0,0,0,0,0,0,0,0,0,0~
,0,0,0,0,CF29,0,0,0)';$S;
    'VSS_CF30':'(0,0,0,0,0,0,0,0,0,0,0,0,0,0,0,0,0,0,0,0,0,0,0,0,0,0,0,0,0,0,0,0~
,0,0,0,0,CF30,0,0,0)';$S;
    'VSS_CF31':'(0,0,0,0,0,0,0,0,0,0,0,0,0,0,0,0,0,0,0,0,0,0,0,0,0,0,0,0,0,0,0,0~
,0,0,0,0,CF31,0,0,0)';$S;
    'VSS_CF32':'(0,0,0,0,0,0,0,0,0,0,0,0,0,0,0,0,0,0,0,0,0,0,0,0,0,0,0,0,0,0,0,0~
,0,0,0,0,CF32,0,0,0)';$S;
    'VSS_CF33':'(0,0,0,0,0,0,0,0,0,0,0,0,0,0,0,0,0,0,0,0,0,0,0,0,0,0,0,0,0,0,0,0~
,0,0,0,0,CF33,0,0,0)';$S;
    'VSS_CN56':'(0,0,0,0,0,0,0,0,0,0,0,0,0,0,0,0,0,0,0,0,0,0,0,0,0,0,0,0,0,0,0,0~
,0,0,0,0,0,CN56,0,0)';$S;
    'VSS_CN20':'(0,0,0,0,0,0,0,0,0,0,0,0,0,0,0,0,0,0,0,0,0,0,0,0,0,0,0,0,0,0,0,0~
,0,0,0,0,0,CN20,0,0)';$S;
    'VSS_CM61':'(0,0,0,0,0,0,0,0,0,0,0,0,0,0,0,0,0,0,0,0,0,0,0,0,0,0,0,0,0,0,0,0~
,0,0,0,0,0,CM61,0,0)';$S;
    'VSS_CM34':'(0,0,0,0,0,0,0,0,0,0,0,0,0,0,0,0,0,0,0,0,0,0,0,0,0,0,0,0,0,0,0,0~
,0,0,0,0,0,CM34,0,0)';$S;
    'VSS_CK33':'(0,0,0,0,0,0,0,0,0,0,0,0,0,0,0,0,0,0,0,0,0,0,0,0,0,0,0,0,0,0,0,0~
,0,0,0,0,0,CK33,0,0)';$S;
    'VSS_CK15':'(0,0,0,0,0,0,0,0,0,0,0,0,0,0,0,0,0,0,0,0,0,0,0,0,0,0,0,0,0,0,0,0~
,0,0,0,0,0,CK15,0,0)';$S;
    'VSS_CJ58':'(0,0,0,0,0,0,0,0,0,0,0,0,0,0,0,0,0,0,0,0,0,0,0,0,0,0,0,0,0,0,0,0~
,0,0,0,0,0,CJ58,0,0)';$S;
    'VSS_CJ20':'(0,0,0,0,0,0,0,0,0,0,0,0,0,0,0,0,0,0,0,0,0,0,0,0,0,0,0,0,0,0,0,0~
,0,0,0,0,0,CJ20,0,0)';$S;
    'VSS_CH68':'(0,0,0,0,0,0,0,0,0,0,0,0,0,0,0,0,0,0,0,0,0,0,0,0,0,0,0,0,0,0,0,0~
,0,0,0,0,0,CH68,0,0)';$S;
    'VSS_CH39':'(0,0,0,0,0,0,0,0,0,0,0,0,0,0,0,0,0,0,0,0,0,0,0,0,0,0,0,0,0,0,0,0~
,0,0,0,0,0,CH39,0,0)';$S;
    'VSS_CH10':'(0,0,0,0,0,0,0,0,0,0,0,0,0,0,0,0,0,0,0,0,0,0,0,0,0,0,0,0,0,0,0,0~
,0,0,0,0,0,CH10,0,0)';$S;
    'VSS_CN22':'(0,0,0,0,0,0,0,0,0,0,0,0,0,0,0,0,0,0,0,0,0,0,0,0,0,0,0,0,0,0,0,0~
,0,0,0,0,0,CN22,0,0)';$S;
    'VSS_CM64':'(0,0,0,0,0,0,0,0,0,0,0,0,0,0,0,0,0,0,0,0,0,0,0,0,0,0,0,0,0,0,0,0~
,0,0,0,0,0,CM64,0,0)';$S;
    'VSS_CM37':'(0,0,0,0,0,0,0,0,0,0,0,0,0,0,0,0,0,0,0,0,0,0,0,0,0,0,0,0,0,0,0,0~
,0,0,0,0,0,CM37,0,0)';$S;
    'VSS_CM24':'(0,0,0,0,0,0,0,0,0,0,0,0,0,0,0,0,0,0,0,0,0,0,0,0,0,0,0,0,0,0,0,0~
,0,0,0,0,0,CM24,0,0)';$S;
    'VSS_CK17':'(0,0,0,0,0,0,0,0,0,0,0,0,0,0,0,0,0,0,0,0,0,0,0,0,0,0,0,0,0,0,0,0~
,0,0,0,0,0,CK17,0,0)';$S;
    'VSS_CJ61':'(0,0,0,0,0,0,0,0,0,0,0,0,0,0,0,0,0,0,0,0,0,0,0,0,0,0,0,0,0,0,0,0~
,0,0,0,0,0,CJ61,0,0)';$S;
    'VSS_CJ23':'(0,0,0,0,0,0,0,0,0,0,0,0,0,0,0,0,0,0,0,0,0,0,0,0,0,0,0,0,0,0,0,0~
,0,0,0,0,0,CJ23,0,0)';$S;
    'VSS_CH71':'(0,0,0,0,0,0,0,0,0,0,0,0,0,0,0,0,0,0,0,0,0,0,0,0,0,0,0,0,0,0,0,0~
,0,0,0,0,0,CH71,0,0)';$S;
    'VSS_CH42':'(0,0,0,0,0,0,0,0,0,0,0,0,0,0,0,0,0,0,0,0,0,0,0,0,0,0,0,0,0,0,0,0~
,0,0,0,0,0,CH42,0,0)';$S;
    'VSS_CH12':'(0,0,0,0,0,0,0,0,0,0,0,0,0,0,0,0,0,0,0,0,0,0,0,0,0,0,0,0,0,0,0,0~
,0,0,0,0,0,CH12,0,0)';$S;
    'VSS_CM66':'(0,0,0,0,0,0,0,0,0,0,0,0,0,0,0,0,0,0,0,0,0,0,0,0,0,0,0,0,0,0,0,0~
,0,0,0,0,0,CM66,0,0)';$S;
    'VSS_CM39':'(0,0,0,0,0,0,0,0,0,0,0,0,0,0,0,0,0,0,0,0,0,0,0,0,0,0,0,0,0,0,0,0~
,0,0,0,0,0,CM39,0,0)';$S;
    'VSS_CM25':'(0,0,0,0,0,0,0,0,0,0,0,0,0,0,0,0,0,0,0,0,0,0,0,0,0,0,0,0,0,0,0,0~
,0,0,0,0,0,CM25,0,0)';$S;
    'VSS_CL75':'(0,0,0,0,0,0,0,0,0,0,0,0,0,0,0,0,0,0,0,0,0,0,0,0,0,0,0,0,0,0,0,0~
,0,0,0,0,0,CL75,0,0)';$S;
    'VSS_CJ63':'(0,0,0,0,0,0,0,0,0,0,0,0,0,0,0,0,0,0,0,0,0,0,0,0,0,0,0,0,0,0,0,0~
,0,0,0,0,0,CJ63,0,0)';$S;
    'VSS_CJ31':'(0,0,0,0,0,0,0,0,0,0,0,0,0,0,0,0,0,0,0,0,0,0,0,0,0,0,0,0,0,0,0,0~
,0,0,0,0,0,CJ31,0,0)';$S;
    'VSS_CH73':'(0,0,0,0,0,0,0,0,0,0,0,0,0,0,0,0,0,0,0,0,0,0,0,0,0,0,0,0,0,0,0,0~
,0,0,0,0,0,CH73,0,0)';$S;
    'VSS_CH45':'(0,0,0,0,0,0,0,0,0,0,0,0,0,0,0,0,0,0,0,0,0,0,0,0,0,0,0,0,0,0,0,0~
,0,0,0,0,0,CH45,0,0)';$S;
    'VSS_CH15':'(0,0,0,0,0,0,0,0,0,0,0,0,0,0,0,0,0,0,0,0,0,0,0,0,0,0,0,0,0,0,0,0~
,0,0,0,0,0,CH15,0,0)';$S;
    'VSS_CM42':'(0,0,0,0,0,0,0,0,0,0,0,0,0,0,0,0,0,0,0,0,0,0,0,0,0,0,0,0,0,0,0,0~
,0,0,0,0,0,CM42,0,0)';$S;
    'VSS_CM26':'(0,0,0,0,0,0,0,0,0,0,0,0,0,0,0,0,0,0,0,0,0,0,0,0,0,0,0,0,0,0,0,0~
,0,0,0,0,0,CM26,0,0)';$S;
    'VSS_CM3':'(0,0,0,0,0,0,0,0,0,0,0,0,0,0,0,0,0,0,0,0,0,0,0,0,0,0,0,0,0,0,0,0,~
0,0,0,0,0,CM3,0,0)';$S;
    'VSS_CL51':'(0,0,0,0,0,0,0,0,0,0,0,0,0,0,0,0,0,0,0,0,0,0,0,0,0,0,0,0,0,0,0,0~
,0,0,0,0,0,CL51,0,0)';$S;
    'VSS_CJ34':'(0,0,0,0,0,0,0,0,0,0,0,0,0,0,0,0,0,0,0,0,0,0,0,0,0,0,0,0,0,0,0,0~
,0,0,0,0,0,CJ34,0,0)';$S;
    'VSS_CJ1':'(0,0,0,0,0,0,0,0,0,0,0,0,0,0,0,0,0,0,0,0,0,0,0,0,0,0,0,0,0,0,0,0,~
0,0,0,0,0,CJ1,0,0)';$S;
    'VSS_CH48':'(0,0,0,0,0,0,0,0,0,0,0,0,0,0,0,0,0,0,0,0,0,0,0,0,0,0,0,0,0,0,0,0~
,0,0,0,0,0,CH48,0,0)';$S;
    'VSS_CH17':'(0,0,0,0,0,0,0,0,0,0,0,0,0,0,0,0,0,0,0,0,0,0,0,0,0,0,0,0,0,0,0,0~
,0,0,0,0,0,CH17,0,0)';$S;
    'VSS_CM43':'(0,0,0,0,0,0,0,0,0,0,0,0,0,0,0,0,0,0,0,0,0,0,0,0,0,0,0,0,0,0,0,0~
,0,0,0,0,0,CM43,0,0)';$S;
    'VSS_CM27':'(0,0,0,0,0,0,0,0,0,0,0,0,0,0,0,0,0,0,0,0,0,0,0,0,0,0,0,0,0,0,0,0~
,0,0,0,0,0,CM27,0,0)';$S;
    'VSS_CM5':'(0,0,0,0,0,0,0,0,0,0,0,0,0,0,0,0,0,0,0,0,0,0,0,0,0,0,0,0,0,0,0,0,~
0,0,0,0,0,CM5,0,0)';$S;
    'VSS_CL54':'(0,0,0,0,0,0,0,0,0,0,0,0,0,0,0,0,0,0,0,0,0,0,0,0,0,0,0,0,0,0,0,0~
,0,0,0,0,0,CL54,0,0)';$S;
    'VSS_CL28':'(0,0,0,0,0,0,0,0,0,0,0,0,0,0,0,0,0,0,0,0,0,0,0,0,0,0,0,0,0,0,0,0~
,0,0,0,0,0,CL28,0,0)';$S;
    'VSS_CJ4':'(0,0,0,0,0,0,0,0,0,0,0,0,0,0,0,0,0,0,0,0,0,0,0,0,0,0,0,0,0,0,0,0,~
0,0,0,0,0,CJ4,0,0)';$S;
    'VSS_CH51':'(0,0,0,0,0,0,0,0,0,0,0,0,0,0,0,0,0,0,0,0,0,0,0,0,0,0,0,0,0,0,0,0~
,0,0,0,0,0,CH51,0,0)';$S;
    'VSS_CH19':'(0,0,0,0,0,0,0,0,0,0,0,0,0,0,0,0,0,0,0,0,0,0,0,0,0,0,0,0,0,0,0,0~
,0,0,0,0,0,CH19,0,0)';$S;
    'VSS_CF34':'(0,0,0,0,0,0,0,0,0,0,0,0,0,0,0,0,0,0,0,0,0,0,0,0,0,0,0,0,0,0,0,0~
,0,0,0,0,0,CF34,0,0)';$S;
    'VSS_CF37':'(0,0,0,0,0,0,0,0,0,0,0,0,0,0,0,0,0,0,0,0,0,0,0,0,0,0,0,0,0,0,0,0~
,0,0,0,0,0,CF37,0,0)';$S;
    'VSS_CF39':'(0,0,0,0,0,0,0,0,0,0,0,0,0,0,0,0,0,0,0,0,0,0,0,0,0,0,0,0,0,0,0,0~
,0,0,0,0,0,CF39,0,0)';$S;
    'VSS_CF42':'(0,0,0,0,0,0,0,0,0,0,0,0,0,0,0,0,0,0,0,0,0,0,0,0,0,0,0,0,0,0,0,0~
,0,0,0,0,0,CF42,0,0)';$S;
    'VSS_CF43':'(0,0,0,0,0,0,0,0,0,0,0,0,0,0,0,0,0,0,0,0,0,0,0,0,0,0,0,0,0,0,0,0~
,0,0,0,0,0,CF43,0,0)';$S;
    'VSS_CF44':'(0,0,0,0,0,0,0,0,0,0,0,0,0,0,0,0,0,0,0,0,0,0,0,0,0,0,0,0,0,0,0,0~
,0,0,0,0,0,CF44,0,0)';$S;
    'VSS_CF45':'(0,0,0,0,0,0,0,0,0,0,0,0,0,0,0,0,0,0,0,0,0,0,0,0,0,0,0,0,0,0,0,0~
,0,0,0,0,0,CF45,0,0)';$S;
    'VSS_CF47':'(0,0,0,0,0,0,0,0,0,0,0,0,0,0,0,0,0,0,0,0,0,0,0,0,0,0,0,0,0,0,0,0~
,0,0,0,0,0,CF47,0,0)';$S;
    'VSS_CF48':'(0,0,0,0,0,0,0,0,0,0,0,0,0,0,0,0,0,0,0,0,0,0,0,0,0,0,0,0,0,0,0,0~
,0,0,0,0,0,CF48,0,0)';$S;
    'VSS_CF49':'(0,0,0,0,0,0,0,0,0,0,0,0,0,0,0,0,0,0,0,0,0,0,0,0,0,0,0,0,0,0,0,0~
,0,0,0,0,0,CF49,0,0)';$S;
    'VSS_CF50':'(0,0,0,0,0,0,0,0,0,0,0,0,0,0,0,0,0,0,0,0,0,0,0,0,0,0,0,0,0,0,0,0~
,0,0,0,0,0,CF50,0,0)';$S;
    'VSS_CF51':'(0,0,0,0,0,0,0,0,0,0,0,0,0,0,0,0,0,0,0,0,0,0,0,0,0,0,0,0,0,0,0,0~
,0,0,0,0,0,CF51,0,0)';$S;
    'VSS_CF52':'(0,0,0,0,0,0,0,0,0,0,0,0,0,0,0,0,0,0,0,0,0,0,0,0,0,0,0,0,0,0,0,0~
,0,0,0,0,0,CF52,0,0)';$S;
    'VSS_CF53':'(0,0,0,0,0,0,0,0,0,0,0,0,0,0,0,0,0,0,0,0,0,0,0,0,0,0,0,0,0,0,0,0~
,0,0,0,0,0,CF53,0,0)';$S;
    'VSS_CF57':'(0,0,0,0,0,0,0,0,0,0,0,0,0,0,0,0,0,0,0,0,0,0,0,0,0,0,0,0,0,0,0,0~
,0,0,0,0,0,CF57,0,0)';$S;
    'VSS_CF59':'(0,0,0,0,0,0,0,0,0,0,0,0,0,0,0,0,0,0,0,0,0,0,0,0,0,0,0,0,0,0,0,0~
,0,0,0,0,0,CF59,0,0)';$S;
    'VSS_CF61':'(0,0,0,0,0,0,0,0,0,0,0,0,0,0,0,0,0,0,0,0,0,0,0,0,0,0,0,0,0,0,0,0~
,0,0,0,0,0,CF61,0,0)';$S;
    'VSS_CF64':'(0,0,0,0,0,0,0,0,0,0,0,0,0,0,0,0,0,0,0,0,0,0,0,0,0,0,0,0,0,0,0,0~
,0,0,0,0,0,CF64,0,0)';$S;
    'VSS_CF66':'(0,0,0,0,0,0,0,0,0,0,0,0,0,0,0,0,0,0,0,0,0,0,0,0,0,0,0,0,0,0,0,0~
,0,0,0,0,0,CF66,0,0)';$S;
    'VSS_CF68':'(0,0,0,0,0,0,0,0,0,0,0,0,0,0,0,0,0,0,0,0,0,0,0,0,0,0,0,0,0,0,0,0~
,0,0,0,0,0,CF68,0,0)';$S;
    'VSS_CF71':'(0,0,0,0,0,0,0,0,0,0,0,0,0,0,0,0,0,0,0,0,0,0,0,0,0,0,0,0,0,0,0,0~
,0,0,0,0,0,CF71,0,0)';$S;
    'VSS_CF73':'(0,0,0,0,0,0,0,0,0,0,0,0,0,0,0,0,0,0,0,0,0,0,0,0,0,0,0,0,0,0,0,0~
,0,0,0,0,0,CF73,0,0)';$S;
    'VSS_CG1':'(0,0,0,0,0,0,0,0,0,0,0,0,0,0,0,0,0,0,0,0,0,0,0,0,0,0,0,0,0,0,0,0,~
0,0,0,0,0,CG1,0,0)';$S;
    'VSS_CG6':'(0,0,0,0,0,0,0,0,0,0,0,0,0,0,0,0,0,0,0,0,0,0,0,0,0,0,0,0,0,0,0,0,~
0,0,0,0,0,CG6,0,0)';$S;
    'VSS_CG8':'(0,0,0,0,0,0,0,0,0,0,0,0,0,0,0,0,0,0,0,0,0,0,0,0,0,0,0,0,0,0,0,0,~
0,0,0,0,0,CG8,0,0)';$S;
    'VSS_CG13':'(0,0,0,0,0,0,0,0,0,0,0,0,0,0,0,0,0,0,0,0,0,0,0,0,0,0,0,0,0,0,0,0~
,0,0,0,0,0,CG13,0,0)';$S;
    'VSS_CG15':'(0,0,0,0,0,0,0,0,0,0,0,0,0,0,0,0,0,0,0,0,0,0,0,0,0,0,0,0,0,0,0,0~
,0,0,0,0,0,CG15,0,0)';$S;
    'VSS_CG20':'(0,0,0,0,0,0,0,0,0,0,0,0,0,0,0,0,0,0,0,0,0,0,0,0,0,0,0,0,0,0,0,0~
,0,0,0,0,0,CG20,0,0)';$S;
    'VSS_CG22':'(0,0,0,0,0,0,0,0,0,0,0,0,0,0,0,0,0,0,0,0,0,0,0,0,0,0,0,0,0,0,0,0~
,0,0,0,0,0,CG22,0,0)';$S;
    'VSS_CG25':'(0,0,0,0,0,0,0,0,0,0,0,0,0,0,0,0,0,0,0,0,0,0,0,0,0,0,0,0,0,0,0,0~
,0,0,0,0,0,CG25,0,0)';$S;
    'VSS_CG28':'(0,0,0,0,0,0,0,0,0,0,0,0,0,0,0,0,0,0,0,0,0,0,0,0,0,0,0,0,0,0,0,0~
,0,0,0,0,0,CG28,0,0)';$S;
    'VSS_CG31':'(0,0,0,0,0,0,0,0,0,0,0,0,0,0,0,0,0,0,0,0,0,0,0,0,0,0,0,0,0,0,0,0~
,0,0,0,0,0,CG31,0,0)';$S;
    'VSS_CG34':'(0,0,0,0,0,0,0,0,0,0,0,0,0,0,0,0,0,0,0,0,0,0,0,0,0,0,0,0,0,0,0,0~
,0,0,0,0,0,CG34,0,0)';$S;
    'VSS_CG45':'(0,0,0,0,0,0,0,0,0,0,0,0,0,0,0,0,0,0,0,0,0,0,0,0,0,0,0,0,0,0,0,0~
,0,0,0,0,0,CG45,0,0)';$S;
    'VSS_CG48':'(0,0,0,0,0,0,0,0,0,0,0,0,0,0,0,0,0,0,0,0,0,0,0,0,0,0,0,0,0,0,0,0~
,0,0,0,0,0,CG48,0,0)';$S;
    'VSS_CG51':'(0,0,0,0,0,0,0,0,0,0,0,0,0,0,0,0,0,0,0,0,0,0,0,0,0,0,0,0,0,0,0,0~
,0,0,0,0,0,CG51,0,0)';$S;
    'VSS_CG54':'(0,0,0,0,0,0,0,0,0,0,0,0,0,0,0,0,0,0,0,0,0,0,0,0,0,0,0,0,0,0,0,0~
,0,0,0,0,0,CG54,0,0)';$S;
    'VSS_CG56':'(0,0,0,0,0,0,0,0,0,0,0,0,0,0,0,0,0,0,0,0,0,0,0,0,0,0,0,0,0,0,0,0~
,0,0,0,0,0,CG56,0,0)';$S;
    'VSS_CG61':'(0,0,0,0,0,0,0,0,0,0,0,0,0,0,0,0,0,0,0,0,0,0,0,0,0,0,0,0,0,0,0,0~
,0,0,0,0,0,CG61,0,0)';$S;
    'VSS_CG63':'(0,0,0,0,0,0,0,0,0,0,0,0,0,0,0,0,0,0,0,0,0,0,0,0,0,0,0,0,0,0,0,0~
,0,0,0,0,0,CG63,0,0)';$S;
    'VSS_CG68':'(0,0,0,0,0,0,0,0,0,0,0,0,0,0,0,0,0,0,0,0,0,0,0,0,0,0,0,0,0,0,0,0~
,0,0,0,0,0,CG68,0,0)';$S;
    'VSS_CG70':'(0,0,0,0,0,0,0,0,0,0,0,0,0,0,0,0,0,0,0,0,0,0,0,0,0,0,0,0,0,0,0,0~
,0,0,0,0,0,CG70,0,0)';$S;
    'VSS_CG75':'(0,0,0,0,0,0,0,0,0,0,0,0,0,0,0,0,0,0,0,0,0,0,0,0,0,0,0,0,0,0,0,0~
,0,0,0,0,0,CG75,0,0)';$S;
    'VSS_CH3':'(0,0,0,0,0,0,0,0,0,0,0,0,0,0,0,0,0,0,0,0,0,0,0,0,0,0,0,0,0,0,0,0,~
0,0,0,0,0,CH3,0,0)';$S;
    'VSS_CH5':'(0,0,0,0,0,0,0,0,0,0,0,0,0,0,0,0,0,0,0,0,0,0,0,0,0,0,0,0,0,0,0,0,~
0,0,0,0,0,CH5,0,0)';$S;
    'VSS_CH8':'(0,0,0,0,0,0,0,0,0,0,0,0,0,0,0,0,0,0,0,0,0,0,0,0,0,0,0,0,0,0,0,0,~
0,0,0,0,0,CH8,0,0)';$S;
    'VSS_CH22':'(0,0,0,0,0,0,0,0,0,0,0,0,0,0,0,0,0,0,0,0,0,0,0,0,0,0,0,0,0,0,0,0~
,0,0,0,0,0,CH22,0,0)';$S;
    'VSS_CH25':'(0,0,0,0,0,0,0,0,0,0,0,0,0,0,0,0,0,0,0,0,0,0,0,0,0,0,0,0,0,0,0,0~
,0,0,0,0,0,CH25,0,0)';$S;
    'VSS_CH28':'(0,0,0,0,0,0,0,0,0,0,0,0,0,0,0,0,0,0,0,0,0,0,0,0,0,0,0,0,0,0,0,0~
,0,0,0,0,0,CH28,0,0)';$S;
    'VSS_CH31':'(0,0,0,0,0,0,0,0,0,0,0,0,0,0,0,0,0,0,0,0,0,0,0,0,0,0,0,0,0,0,0,0~
,0,0,0,0,0,CH31,0,0)';$S;
    'VSS_CH34':'(0,0,0,0,0,0,0,0,0,0,0,0,0,0,0,0,0,0,0,0,0,0,0,0,0,0,0,0,0,0,0,0~
,0,0,0,0,0,CH34,0,0)';$S;
    'VSS_CH37':'(0,0,0,0,0,0,0,0,0,0,0,0,0,0,0,0,0,0,0,0,0,0,0,0,0,0,0,0,0,0,0,0~
,0,0,0,0,0,CH37,0,0)';$S;
    'VSS_CH54':'(0,0,0,0,0,0,0,0,0,0,0,0,0,0,0,0,0,0,0,0,0,0,0,0,0,0,0,0,0,0,0,0~
,0,0,0,0,0,CH54,0,0)';$S;
    'VSS_CH57':'(0,0,0,0,0,0,0,0,0,0,0,0,0,0,0,0,0,0,0,0,0,0,0,0,0,0,0,0,0,0,0,0~
,0,0,0,0,0,CH57,0,0)';$S;
    'VSS_CH59':'(0,0,0,0,0,0,0,0,0,0,0,0,0,0,0,0,0,0,0,0,0,0,0,0,0,0,0,0,0,0,0,0~
,0,0,0,0,0,CH59,0,0)';$S;
    'VSS_CH61':'(0,0,0,0,0,0,0,0,0,0,0,0,0,0,0,0,0,0,0,0,0,0,0,0,0,0,0,0,0,0,0,0~
,0,0,0,0,0,CH61,0,0)';$S;
    'VSS_CH64':'(0,0,0,0,0,0,0,0,0,0,0,0,0,0,0,0,0,0,0,0,0,0,0,0,0,0,0,0,0,0,0,0~
,0,0,0,0,0,CH64,0,0)';$S;
    'VSS_CH66':'(0,0,0,0,0,0,0,0,0,0,0,0,0,0,0,0,0,0,0,0,0,0,0,0,0,0,0,0,0,0,0,0~
,0,0,0,0,0,CH66,0,0)';$S;
    'VSS_CJ6':'(0,0,0,0,0,0,0,0,0,0,0,0,0,0,0,0,0,0,0,0,0,0,0,0,0,0,0,0,0,0,0,0,~
0,0,0,0,0,CJ6,0,0)';$S;
    'VSS_CJ8':'(0,0,0,0,0,0,0,0,0,0,0,0,0,0,0,0,0,0,0,0,0,0,0,0,0,0,0,0,0,0,0,0,~
0,0,0,0,0,CJ8,0,0)';$S;
    'VSS_CJ11':'(0,0,0,0,0,0,0,0,0,0,0,0,0,0,0,0,0,0,0,0,0,0,0,0,0,0,0,0,0,0,0,0~
,0,0,0,0,0,CJ11,0,0)';$S;
    'VSS_CJ13':'(0,0,0,0,0,0,0,0,0,0,0,0,0,0,0,0,0,0,0,0,0,0,0,0,0,0,0,0,0,0,0,0~
,0,0,0,0,0,CJ13,0,0)';$S;
    'VSS_CJ15':'(0,0,0,0,0,0,0,0,0,0,0,0,0,0,0,0,0,0,0,0,0,0,0,0,0,0,0,0,0,0,0,0~
,0,0,0,0,0,CJ15,0,0)';$S;
    'VSS_CJ18':'(0,0,0,0,0,0,0,0,0,0,0,0,0,0,0,0,0,0,0,0,0,0,0,0,0,0,0,0,0,0,0,0~
,0,0,0,0,0,CJ18,0,0)';$S;
    'VSS_CJ35':'(0,0,0,0,0,0,0,0,0,0,0,0,0,0,0,0,0,0,0,0,0,0,0,0,0,0,0,0,0,0,0,0~
,0,0,0,0,0,CJ35,0,0)';$S;
    'VSS_CJ36':'(0,0,0,0,0,0,0,0,0,0,0,0,0,0,0,0,0,0,0,0,0,0,0,0,0,0,0,0,0,0,0,0~
,0,0,0,0,0,CJ36,0,0)';$S;
    'VSS_CJ40':'(0,0,0,0,0,0,0,0,0,0,0,0,0,0,0,0,0,0,0,0,0,0,0,0,0,0,0,0,0,0,0,0~
,0,0,0,0,0,CJ40,0,0)';$S;
    'VSS_CJ41':'(0,0,0,0,0,0,0,0,0,0,0,0,0,0,0,0,0,0,0,0,0,0,0,0,0,0,0,0,0,0,0,0~
,0,0,0,0,0,CJ41,0,0)';$S;
    'VSS_CJ42':'(0,0,0,0,0,0,0,0,0,0,0,0,0,0,0,0,0,0,0,0,0,0,0,0,0,0,0,0,0,0,0,0~
,0,0,0,0,0,CJ42,0,0)';$S;
    'VSS_CJ45':'(0,0,0,0,0,0,0,0,0,0,0,0,0,0,0,0,0,0,0,0,0,0,0,0,0,0,0,0,0,0,0,0~
,0,0,0,0,0,CJ45,0,0)';$S;
    'VSS_CJ56':'(0,0,0,0,0,0,0,0,0,0,0,0,0,0,0,0,0,0,0,0,0,0,0,0,0,0,0,0,0,0,0,0~
,0,0,0,0,0,CJ56,0,0)';$S;
    'VSS_CJ65':'(0,0,0,0,0,0,0,0,0,0,0,0,0,0,0,0,0,0,0,0,0,0,0,0,0,0,0,0,0,0,0,0~
,0,0,0,0,0,CJ65,0,0)';$S;
    'VSS_CJ68':'(0,0,0,0,0,0,0,0,0,0,0,0,0,0,0,0,0,0,0,0,0,0,0,0,0,0,0,0,0,0,0,0~
,0,0,0,0,0,CJ68,0,0)';$S;
    'VSS_CJ70':'(0,0,0,0,0,0,0,0,0,0,0,0,0,0,0,0,0,0,0,0,0,0,0,0,0,0,0,0,0,0,0,0~
,0,0,0,0,0,CJ70,0,0)';$S;
    'VSS_CJ72':'(0,0,0,0,0,0,0,0,0,0,0,0,0,0,0,0,0,0,0,0,0,0,0,0,0,0,0,0,0,0,0,0~
,0,0,0,0,0,CJ72,0,0)';$S;
    'VSS_CJ75':'(0,0,0,0,0,0,0,0,0,0,0,0,0,0,0,0,0,0,0,0,0,0,0,0,0,0,0,0,0,0,0,0~
,0,0,0,0,0,CJ75,0,0)';$S;
    'VSS_CK3':'(0,0,0,0,0,0,0,0,0,0,0,0,0,0,0,0,0,0,0,0,0,0,0,0,0,0,0,0,0,0,0,0,~
0,0,0,0,0,CK3,0,0)';$S;
    'VSS_CK8':'(0,0,0,0,0,0,0,0,0,0,0,0,0,0,0,0,0,0,0,0,0,0,0,0,0,0,0,0,0,0,0,0,~
0,0,0,0,0,CK8,0,0)';$S;
    'VSS_CK22':'(0,0,0,0,0,0,0,0,0,0,0,0,0,0,0,0,0,0,0,0,0,0,0,0,0,0,0,0,0,0,0,0~
,0,0,0,0,0,CK22,0,0)';$S;
    'VSS_CK23':'(0,0,0,0,0,0,0,0,0,0,0,0,0,0,0,0,0,0,0,0,0,0,0,0,0,0,0,0,0,0,0,0~
,0,0,0,0,0,CK23,0,0)';$S;
    'VSS_CK24':'(0,0,0,0,0,0,0,0,0,0,0,0,0,0,0,0,0,0,0,0,0,0,0,0,0,0,0,0,0,0,0,0~
,0,0,0,0,0,CK24,0,0)';$S;
    'VSS_CK25':'(0,0,0,0,0,0,0,0,0,0,0,0,0,0,0,0,0,0,0,0,0,0,0,0,0,0,0,0,0,0,0,0~
,0,0,0,0,0,CK25,0,0)';$S;
    'VSS_CK26':'(0,0,0,0,0,0,0,0,0,0,0,0,0,0,0,0,0,0,0,0,0,0,0,0,0,0,0,0,0,0,0,0~
,0,0,0,0,0,CK26,0,0)';$S;
    'VSS_CK27':'(0,0,0,0,0,0,0,0,0,0,0,0,0,0,0,0,0,0,0,0,0,0,0,0,0,0,0,0,0,0,0,0~
,0,0,0,0,0,CK27,0,0)';$S;
    'VSS_CK28':'(0,0,0,0,0,0,0,0,0,0,0,0,0,0,0,0,0,0,0,0,0,0,0,0,0,0,0,0,0,0,0,0~
,0,0,0,0,0,CK28,0,0)';$S;
    'VSS_CK32':'(0,0,0,0,0,0,0,0,0,0,0,0,0,0,0,0,0,0,0,0,0,0,0,0,0,0,0,0,0,0,0,0~
,0,0,0,0,0,CK32,0,0)';$S;
    'VSS_CK34':'(0,0,0,0,0,0,0,0,0,0,0,0,0,0,0,0,0,0,0,0,0,0,0,0,0,0,0,0,0,0,0,0~
,0,0,0,0,0,CK34,0,0)';$S;
    'VSS_CK37':'(0,0,0,0,0,0,0,0,0,0,0,0,0,0,0,0,0,0,0,0,0,0,0,0,0,0,0,0,0,0,0,0~
,0,0,0,0,0,CK37,0,0)';$S;
    'VSS_CK39':'(0,0,0,0,0,0,0,0,0,0,0,0,0,0,0,0,0,0,0,0,0,0,0,0,0,0,0,0,0,0,0,0~
,0,0,0,0,0,CK39,0,0)';$S;
    'VSS_CK42':'(0,0,0,0,0,0,0,0,0,0,0,0,0,0,0,0,0,0,0,0,0,0,0,0,0,0,0,0,0,0,0,0~
,0,0,0,0,0,CK42,0,0)';$S;
    'VSS_CK43':'(0,0,0,0,0,0,0,0,0,0,0,0,0,0,0,0,0,0,0,0,0,0,0,0,0,0,0,0,0,0,0,0~
,0,0,0,0,0,CK43,0,0)';$S;
    'VSS_CK44':'(0,0,0,0,0,0,0,0,0,0,0,0,0,0,0,0,0,0,0,0,0,0,0,0,0,0,0,0,0,0,0,0~
,0,0,0,0,0,CK44,0,0)';$S;
    'VSS_CK45':'(0,0,0,0,0,0,0,0,0,0,0,0,0,0,0,0,0,0,0,0,0,0,0,0,0,0,0,0,0,0,0,0~
,0,0,0,0,0,CK45,0,0)';$S;
    'VSS_CK48':'(0,0,0,0,0,0,0,0,0,0,0,0,0,0,0,0,0,0,0,0,0,0,0,0,0,0,0,0,0,0,0,0~
,0,0,0,0,0,CK48,0,0)';$S;
    'VSS_CK49':'(0,0,0,0,0,0,0,0,0,0,0,0,0,0,0,0,0,0,0,0,0,0,0,0,0,0,0,0,0,0,0,0~
,0,0,0,0,0,CK49,0,0)';$S;
    'VSS_CK50':'(0,0,0,0,0,0,0,0,0,0,0,0,0,0,0,0,0,0,0,0,0,0,0,0,0,0,0,0,0,0,0,0~
,0,0,0,0,0,CK50,0,0)';$S;
    'VSS_CK51':'(0,0,0,0,0,0,0,0,0,0,0,0,0,0,0,0,0,0,0,0,0,0,0,0,0,0,0,0,0,0,0,0~
,0,0,0,0,0,CK51,0,0)';$S;
    'VSS_CK52':'(0,0,0,0,0,0,0,0,0,0,0,0,0,0,0,0,0,0,0,0,0,0,0,0,0,0,0,0,0,0,0,0~
,0,0,0,0,0,CK52,0,0)';$S;
    'VSS_CK53':'(0,0,0,0,0,0,0,0,0,0,0,0,0,0,0,0,0,0,0,0,0,0,0,0,0,0,0,0,0,0,0,0~
,0,0,0,0,0,CK53,0,0)';$S;
    'VSS_CK54':'(0,0,0,0,0,0,0,0,0,0,0,0,0,0,0,0,0,0,0,0,0,0,0,0,0,0,0,0,0,0,0,0~
,0,0,0,0,0,CK54,0,0)';$S;
    'VSS_CK59':'(0,0,0,0,0,0,0,0,0,0,0,0,0,0,0,0,0,0,0,0,0,0,0,0,0,0,0,0,0,0,0,0~
,0,0,0,0,0,CK59,0,0)';$S;
    'VSS_CK61':'(0,0,0,0,0,0,0,0,0,0,0,0,0,0,0,0,0,0,0,0,0,0,0,0,0,0,0,0,0,0,0,0~
,0,0,0,0,0,CK61,0,0)';$S;
    'VSS_CK66':'(0,0,0,0,0,0,0,0,0,0,0,0,0,0,0,0,0,0,0,0,0,0,0,0,0,0,0,0,0,0,0,0~
,0,0,0,0,0,CK66,0,0)';$S;
    'VSS_CK68':'(0,0,0,0,0,0,0,0,0,0,0,0,0,0,0,0,0,0,0,0,0,0,0,0,0,0,0,0,0,0,0,0~
,0,0,0,0,0,CK68,0,0)';$S;
    'VSS_CK73':'(0,0,0,0,0,0,0,0,0,0,0,0,0,0,0,0,0,0,0,0,0,0,0,0,0,0,0,0,0,0,0,0~
,0,0,0,0,0,CK73,0,0)';$S;
    'VSS_CL1':'(0,0,0,0,0,0,0,0,0,0,0,0,0,0,0,0,0,0,0,0,0,0,0,0,0,0,0,0,0,0,0,0,~
0,0,0,0,0,CL1,0,0)';$S;
    'VSS_CL4':'(0,0,0,0,0,0,0,0,0,0,0,0,0,0,0,0,0,0,0,0,0,0,0,0,0,0,0,0,0,0,0,0,~
0,0,0,0,0,CL4,0,0)';$S;
    'VSS_CL6':'(0,0,0,0,0,0,0,0,0,0,0,0,0,0,0,0,0,0,0,0,0,0,0,0,0,0,0,0,0,0,0,0,~
0,0,0,0,0,CL6,0,0)';$S;
    'VSS_CL8':'(0,0,0,0,0,0,0,0,0,0,0,0,0,0,0,0,0,0,0,0,0,0,0,0,0,0,0,0,0,0,0,0,~
0,0,0,0,0,CL8,0,0)';$S;
    'VSS_CL11':'(0,0,0,0,0,0,0,0,0,0,0,0,0,0,0,0,0,0,0,0,0,0,0,0,0,0,0,0,0,0,0,0~
,0,0,0,0,0,CL11,0,0)';$S;
    'VSS_CL13':'(0,0,0,0,0,0,0,0,0,0,0,0,0,0,0,0,0,0,0,0,0,0,0,0,0,0,0,0,0,0,0,0~
,0,0,0,0,0,CL13,0,0)';$S;
    'VSS_CL15':'(0,0,0,0,0,0,0,0,0,0,0,0,0,0,0,0,0,0,0,0,0,0,0,0,0,0,0,0,0,0,0,0~
,0,0,0,0,0,CL15,0,0)';$S;
    'VSS_CL18':'(0,0,0,0,0,0,0,0,0,0,0,0,0,0,0,0,0,0,0,0,0,0,0,0,0,0,0,0,0,0,0,0~
,0,0,0,0,0,CL18,0,0)';$S;
    'VSS_CL20':'(0,0,0,0,0,0,0,0,0,0,0,0,0,0,0,0,0,0,0,0,0,0,0,0,0,0,0,0,0,0,0,0~
,0,0,0,0,0,CL20,0,0)';$S;
    'VSS_CL22':'(0,0,0,0,0,0,0,0,0,0,0,0,0,0,0,0,0,0,0,0,0,0,0,0,0,0,0,0,0,0,0,0~
,0,0,0,0,0,CL22,0,0)';$S;
    'VSS_CL25':'(0,0,0,0,0,0,0,0,0,0,0,0,0,0,0,0,0,0,0,0,0,0,0,0,0,0,0,0,0,0,0,0~
,0,0,0,0,0,CL25,0,0)';$S;
    'VSS_CL31':'(0,0,0,0,0,0,0,0,0,0,0,0,0,0,0,0,0,0,0,0,0,0,0,0,0,0,0,0,0,0,0,0~
,0,0,0,0,0,CL31,0,0)';$S;
    'VSS_CL34':'(0,0,0,0,0,0,0,0,0,0,0,0,0,0,0,0,0,0,0,0,0,0,0,0,0,0,0,0,0,0,0,0~
,0,0,0,0,0,CL34,0,0)';$S;
    'VSS_CL35':'(0,0,0,0,0,0,0,0,0,0,0,0,0,0,0,0,0,0,0,0,0,0,0,0,0,0,0,0,0,0,0,0~
,0,0,0,0,0,CL35,0,0)';$S;
    'VSS_CL36':'(0,0,0,0,0,0,0,0,0,0,0,0,0,0,0,0,0,0,0,0,0,0,0,0,0,0,0,0,0,0,0,0~
,0,0,0,0,0,CL36,0,0)';$S;
    'VSS_CL40':'(0,0,0,0,0,0,0,0,0,0,0,0,0,0,0,0,0,0,0,0,0,0,0,0,0,0,0,0,0,0,0,0~
,0,0,0,0,0,CL40,0,0)';$S;
    'VSS_CL41':'(0,0,0,0,0,0,0,0,0,0,0,0,0,0,0,0,0,0,0,0,0,0,0,0,0,0,0,0,0,0,0,0~
,0,0,0,0,0,CL41,0,0)';$S;
    'VSS_CL42':'(0,0,0,0,0,0,0,0,0,0,0,0,0,0,0,0,0,0,0,0,0,0,0,0,0,0,0,0,0,0,0,0~
,0,0,0,0,0,CL42,0,0)';$S;
    'VSS_CL45':'(0,0,0,0,0,0,0,0,0,0,0,0,0,0,0,0,0,0,0,0,0,0,0,0,0,0,0,0,0,0,0,0~
,0,0,0,0,0,CL45,0,0)';$S;
    'VSS_CL48':'(0,0,0,0,0,0,0,0,0,0,0,0,0,0,0,0,0,0,0,0,0,0,0,0,0,0,0,0,0,0,0,0~
,0,0,0,0,0,CL48,0,0)';$S;
    'VSS_CL56':'(0,0,0,0,0,0,0,0,0,0,0,0,0,0,0,0,0,0,0,0,0,0,0,0,0,0,0,0,0,0,0,0~
,0,0,0,0,0,CL56,0,0)';$S;
    'VSS_CL58':'(0,0,0,0,0,0,0,0,0,0,0,0,0,0,0,0,0,0,0,0,0,0,0,0,0,0,0,0,0,0,0,0~
,0,0,0,0,0,CL58,0,0)';$S;
    'VSS_CL61':'(0,0,0,0,0,0,0,0,0,0,0,0,0,0,0,0,0,0,0,0,0,0,0,0,0,0,0,0,0,0,0,0~
,0,0,0,0,0,CL61,0,0)';$S;
    'VSS_CL63':'(0,0,0,0,0,0,0,0,0,0,0,0,0,0,0,0,0,0,0,0,0,0,0,0,0,0,0,0,0,0,0,0~
,0,0,0,0,0,CL63,0,0)';$S;
    'VSS_CL65':'(0,0,0,0,0,0,0,0,0,0,0,0,0,0,0,0,0,0,0,0,0,0,0,0,0,0,0,0,0,0,0,0~
,0,0,0,0,0,CL65,0,0)';$S;
    'VSS_CL68':'(0,0,0,0,0,0,0,0,0,0,0,0,0,0,0,0,0,0,0,0,0,0,0,0,0,0,0,0,0,0,0,0~
,0,0,0,0,0,CL68,0,0)';$S;
    'VSS_CL70':'(0,0,0,0,0,0,0,0,0,0,0,0,0,0,0,0,0,0,0,0,0,0,0,0,0,0,0,0,0,0,0,0~
,0,0,0,0,0,CL70,0,0)';$S;
    'VSS_CL72':'(0,0,0,0,0,0,0,0,0,0,0,0,0,0,0,0,0,0,0,0,0,0,0,0,0,0,0,0,0,0,0,0~
,0,0,0,0,0,CL72,0,0)';$S;
    'VSS_CM8':'(0,0,0,0,0,0,0,0,0,0,0,0,0,0,0,0,0,0,0,0,0,0,0,0,0,0,0,0,0,0,0,0,~
0,0,0,0,0,CM8,0,0)';$S;
    'VSS_CM10':'(0,0,0,0,0,0,0,0,0,0,0,0,0,0,0,0,0,0,0,0,0,0,0,0,0,0,0,0,0,0,0,0~
,0,0,0,0,0,CM10,0,0)';$S;
    'VSS_CM12':'(0,0,0,0,0,0,0,0,0,0,0,0,0,0,0,0,0,0,0,0,0,0,0,0,0,0,0,0,0,0,0,0~
,0,0,0,0,0,CM12,0,0)';$S;
    'VSS_CM15':'(0,0,0,0,0,0,0,0,0,0,0,0,0,0,0,0,0,0,0,0,0,0,0,0,0,0,0,0,0,0,0,0~
,0,0,0,0,0,CM15,0,0)';$S;
    'VSS_CM17':'(0,0,0,0,0,0,0,0,0,0,0,0,0,0,0,0,0,0,0,0,0,0,0,0,0,0,0,0,0,0,0,0~
,0,0,0,0,0,CM17,0,0)';$S;
    'VSS_CM19':'(0,0,0,0,0,0,0,0,0,0,0,0,0,0,0,0,0,0,0,0,0,0,0,0,0,0,0,0,0,0,0,0~
,0,0,0,0,0,CM19,0,0)';$S;
    'VSS_CM23':'(0,0,0,0,0,0,0,0,0,0,0,0,0,0,0,0,0,0,0,0,0,0,0,0,0,0,0,0,0,0,0,0~
,0,0,0,0,0,CM23,0,0)';$S;
    'VSS_CM28':'(0,0,0,0,0,0,0,0,0,0,0,0,0,0,0,0,0,0,0,0,0,0,0,0,0,0,0,0,0,0,0,0~
,0,0,0,0,0,CM28,0,0)';$S;
    'VSS_CM29':'(0,0,0,0,0,0,0,0,0,0,0,0,0,0,0,0,0,0,0,0,0,0,0,0,0,0,0,0,0,0,0,0~
,0,0,0,0,0,CM29,0,0)';$S;
    'VSS_CM30':'(0,0,0,0,0,0,0,0,0,0,0,0,0,0,0,0,0,0,0,0,0,0,0,0,0,0,0,0,0,0,0,0~
,0,0,0,0,0,CM30,0,0)';$S;
    'VSS_CM31':'(0,0,0,0,0,0,0,0,0,0,0,0,0,0,0,0,0,0,0,0,0,0,0,0,0,0,0,0,0,0,0,0~
,0,0,0,0,0,CM31,0,0)';$S;
    'VSS_CM32':'(0,0,0,0,0,0,0,0,0,0,0,0,0,0,0,0,0,0,0,0,0,0,0,0,0,0,0,0,0,0,0,0~
,0,0,0,0,0,CM32,0,0)';$S;
    'VSS_CM33':'(0,0,0,0,0,0,0,0,0,0,0,0,0,0,0,0,0,0,0,0,0,0,0,0,0,0,0,0,0,0,0,0~
,0,0,0,0,0,CM33,0,0)';$S;
    'VSS_CM44':'(0,0,0,0,0,0,0,0,0,0,0,0,0,0,0,0,0,0,0,0,0,0,0,0,0,0,0,0,0,0,0,0~
,0,0,0,0,0,CM44,0,0)';$S;
    'VSS_CM45':'(0,0,0,0,0,0,0,0,0,0,0,0,0,0,0,0,0,0,0,0,0,0,0,0,0,0,0,0,0,0,0,0~
,0,0,0,0,0,CM45,0,0)';$S;
    'VSS_CM46':'(0,0,0,0,0,0,0,0,0,0,0,0,0,0,0,0,0,0,0,0,0,0,0,0,0,0,0,0,0,0,0,0~
,0,0,0,0,0,CM46,0,0)';$S;
    'VSS_CM47':'(0,0,0,0,0,0,0,0,0,0,0,0,0,0,0,0,0,0,0,0,0,0,0,0,0,0,0,0,0,0,0,0~
,0,0,0,0,0,CM47,0,0)';$S;
    'VSS_CM48':'(0,0,0,0,0,0,0,0,0,0,0,0,0,0,0,0,0,0,0,0,0,0,0,0,0,0,0,0,0,0,0,0~
,0,0,0,0,0,CM48,0,0)';$S;
    'VSS_CM49':'(0,0,0,0,0,0,0,0,0,0,0,0,0,0,0,0,0,0,0,0,0,0,0,0,0,0,0,0,0,0,0,0~
,0,0,0,0,0,CM49,0,0)';$S;
    'VSS_CM51':'(0,0,0,0,0,0,0,0,0,0,0,0,0,0,0,0,0,0,0,0,0,0,0,0,0,0,0,0,0,0,0,0~
,0,0,0,0,0,CM51,0,0)';$S;
    'VSS_CM52':'(0,0,0,0,0,0,0,0,0,0,0,0,0,0,0,0,0,0,0,0,0,0,0,0,0,0,0,0,0,0,0,0~
,0,0,0,0,0,CM52,0,0)';$S;
    'VSS_CM53':'(0,0,0,0,0,0,0,0,0,0,0,0,0,0,0,0,0,0,0,0,0,0,0,0,0,0,0,0,0,0,0,0~
,0,0,0,0,0,CM53,0,0)';$S;
    'VSS_CM57':'(0,0,0,0,0,0,0,0,0,0,0,0,0,0,0,0,0,0,0,0,0,0,0,0,0,0,0,0,0,0,0,0~
,0,0,0,0,0,CM57,0,0)';$S;
    'VSS_CM59':'(0,0,0,0,0,0,0,0,0,0,0,0,0,0,0,0,0,0,0,0,0,0,0,0,0,0,0,0,0,0,0,0~
,0,0,0,0,0,CM59,0,0)';$S;
    'VSS_CM68':'(0,0,0,0,0,0,0,0,0,0,0,0,0,0,0,0,0,0,0,0,0,0,0,0,0,0,0,0,0,0,0,0~
,0,0,0,0,0,CM68,0,0)';$S;
    'VSS_CM71':'(0,0,0,0,0,0,0,0,0,0,0,0,0,0,0,0,0,0,0,0,0,0,0,0,0,0,0,0,0,0,0,0~
,0,0,0,0,0,CM71,0,0)';$S;
    'VSS_CM73':'(0,0,0,0,0,0,0,0,0,0,0,0,0,0,0,0,0,0,0,0,0,0,0,0,0,0,0,0,0,0,0,0~
,0,0,0,0,0,CM73,0,0)';$S;
    'VSS_CN1':'(0,0,0,0,0,0,0,0,0,0,0,0,0,0,0,0,0,0,0,0,0,0,0,0,0,0,0,0,0,0,0,0,~
0,0,0,0,0,CN1,0,0)';$S;
    'VSS_CN6':'(0,0,0,0,0,0,0,0,0,0,0,0,0,0,0,0,0,0,0,0,0,0,0,0,0,0,0,0,0,0,0,0,~
0,0,0,0,0,CN6,0,0)';$S;
    'VSS_CN8':'(0,0,0,0,0,0,0,0,0,0,0,0,0,0,0,0,0,0,0,0,0,0,0,0,0,0,0,0,0,0,0,0,~
0,0,0,0,0,CN8,0,0)';$S;
    'VSS_CN13':'(0,0,0,0,0,0,0,0,0,0,0,0,0,0,0,0,0,0,0,0,0,0,0,0,0,0,0,0,0,0,0,0~
,0,0,0,0,0,CN13,0,0)';$S;
    'VSS_CN15':'(0,0,0,0,0,0,0,0,0,0,0,0,0,0,0,0,0,0,0,0,0,0,0,0,0,0,0,0,0,0,0,0~
,0,0,0,0,0,CN15,0,0)';$S;
    'VSS_CN25':'(0,0,0,0,0,0,0,0,0,0,0,0,0,0,0,0,0,0,0,0,0,0,0,0,0,0,0,0,0,0,0,0~
,0,0,0,0,0,CN25,0,0)';$S;
    'VSS_CN28':'(0,0,0,0,0,0,0,0,0,0,0,0,0,0,0,0,0,0,0,0,0,0,0,0,0,0,0,0,0,0,0,0~
,0,0,0,0,0,CN28,0,0)';$S;
    'VSS_CN31':'(0,0,0,0,0,0,0,0,0,0,0,0,0,0,0,0,0,0,0,0,0,0,0,0,0,0,0,0,0,0,0,0~
,0,0,0,0,0,CN31,0,0)';$S;
    'VSS_CN34':'(0,0,0,0,0,0,0,0,0,0,0,0,0,0,0,0,0,0,0,0,0,0,0,0,0,0,0,0,0,0,0,0~
,0,0,0,0,0,CN34,0,0)';$S;
    'VSS_CN42':'(0,0,0,0,0,0,0,0,0,0,0,0,0,0,0,0,0,0,0,0,0,0,0,0,0,0,0,0,0,0,0,0~
,0,0,0,0,0,CN42,0,0)';$S;
    'VSS_CN45':'(0,0,0,0,0,0,0,0,0,0,0,0,0,0,0,0,0,0,0,0,0,0,0,0,0,0,0,0,0,0,0,0~
,0,0,0,0,0,CN45,0,0)';$S;
    'VSS_CN48':'(0,0,0,0,0,0,0,0,0,0,0,0,0,0,0,0,0,0,0,0,0,0,0,0,0,0,0,0,0,0,0,0~
,0,0,0,0,0,CN48,0,0)';$S;
    'VSS_CN51':'(0,0,0,0,0,0,0,0,0,0,0,0,0,0,0,0,0,0,0,0,0,0,0,0,0,0,0,0,0,0,0,0~
,0,0,0,0,0,CN51,0,0)';$S;
    'VSS_CN61':'(0,0,0,0,0,0,0,0,0,0,0,0,0,0,0,0,0,0,0,0,0,0,0,0,0,0,0,0,0,0,0,0~
,0,0,0,0,0,CN61,0,0)';$S;
    'VSS_CN63':'(0,0,0,0,0,0,0,0,0,0,0,0,0,0,0,0,0,0,0,0,0,0,0,0,0,0,0,0,0,0,0,0~
,0,0,0,0,0,CN63,0,0)';$S;
    'VSS_CN68':'(0,0,0,0,0,0,0,0,0,0,0,0,0,0,0,0,0,0,0,0,0,0,0,0,0,0,0,0,0,0,0,0~
,0,0,0,0,0,CN68,0,0)';$S;
    'VSS_CN70':'(0,0,0,0,0,0,0,0,0,0,0,0,0,0,0,0,0,0,0,0,0,0,0,0,0,0,0,0,0,0,0,0~
,0,0,0,0,0,CN70,0,0)';$S;
    'VSS_CN75':'(0,0,0,0,0,0,0,0,0,0,0,0,0,0,0,0,0,0,0,0,0,0,0,0,0,0,0,0,0,0,0,0~
,0,0,0,0,0,CN75,0,0)';$S;
    'VSS_CP3':'(0,0,0,0,0,0,0,0,0,0,0,0,0,0,0,0,0,0,0,0,0,0,0,0,0,0,0,0,0,0,0,0,~
0,0,0,0,0,CP3,0,0)';$S;
    'VSS_CP5':'(0,0,0,0,0,0,0,0,0,0,0,0,0,0,0,0,0,0,0,0,0,0,0,0,0,0,0,0,0,0,0,0,~
0,0,0,0,0,CP5,0,0)';$S;
    'VSS_CP8':'(0,0,0,0,0,0,0,0,0,0,0,0,0,0,0,0,0,0,0,0,0,0,0,0,0,0,0,0,0,0,0,0,~
0,0,0,0,0,CP8,0,0)';$S;
    'VSS_CP10':'(0,0,0,0,0,0,0,0,0,0,0,0,0,0,0,0,0,0,0,0,0,0,0,0,0,0,0,0,0,0,0,0~
,0,0,0,0,0,CP10,0,0)';$S;
    'VSS_CP12':'(0,0,0,0,0,0,0,0,0,0,0,0,0,0,0,0,0,0,0,0,0,0,0,0,0,0,0,0,0,0,0,0~
,0,0,0,0,0,CP12,0,0)';$S;
    'VSS_CP15':'(0,0,0,0,0,0,0,0,0,0,0,0,0,0,0,0,0,0,0,0,0,0,0,0,0,0,0,0,0,0,0,0~
,0,0,0,0,0,CP15,0,0)';$S;
    'VSS_CP17':'(0,0,0,0,0,0,0,0,0,0,0,0,0,0,0,0,0,0,0,0,0,0,0,0,0,0,0,0,0,0,0,0~
,0,0,0,0,0,CP17,0,0)';$S;
    'VSS_CP19':'(0,0,0,0,0,0,0,0,0,0,0,0,0,0,0,0,0,0,0,0,0,0,0,0,0,0,0,0,0,0,0,0~
,0,0,0,0,0,CP19,0,0)';$S;
    'VSS_CP22':'(0,0,0,0,0,0,0,0,0,0,0,0,0,0,0,0,0,0,0,0,0,0,0,0,0,0,0,0,0,0,0,0~
,0,0,0,0,0,0,CP22,0)';$S;
    'VSS_CP42':'(0,0,0,0,0,0,0,0,0,0,0,0,0,0,0,0,0,0,0,0,0,0,0,0,0,0,0,0,0,0,0,0~
,0,0,0,0,0,0,CP42,0)';$S;
    'VSS_CP45':'(0,0,0,0,0,0,0,0,0,0,0,0,0,0,0,0,0,0,0,0,0,0,0,0,0,0,0,0,0,0,0,0~
,0,0,0,0,0,0,CP45,0)';$S;
    'VSS_CP48':'(0,0,0,0,0,0,0,0,0,0,0,0,0,0,0,0,0,0,0,0,0,0,0,0,0,0,0,0,0,0,0,0~
,0,0,0,0,0,0,CP48,0)';$S;
    'VSS_CP51':'(0,0,0,0,0,0,0,0,0,0,0,0,0,0,0,0,0,0,0,0,0,0,0,0,0,0,0,0,0,0,0,0~
,0,0,0,0,0,0,CP51,0)';$S;
    'VSS_CP54':'(0,0,0,0,0,0,0,0,0,0,0,0,0,0,0,0,0,0,0,0,0,0,0,0,0,0,0,0,0,0,0,0~
,0,0,0,0,0,0,CP54,0)';$S;
    'VSS_CP71':'(0,0,0,0,0,0,0,0,0,0,0,0,0,0,0,0,0,0,0,0,0,0,0,0,0,0,0,0,0,0,0,0~
,0,0,0,0,0,0,CP71,0)';$S;
    'VSS_CP73':'(0,0,0,0,0,0,0,0,0,0,0,0,0,0,0,0,0,0,0,0,0,0,0,0,0,0,0,0,0,0,0,0~
,0,0,0,0,0,0,CP73,0)';$S;
    'VSS_CR1':'(0,0,0,0,0,0,0,0,0,0,0,0,0,0,0,0,0,0,0,0,0,0,0,0,0,0,0,0,0,0,0,0,~
0,0,0,0,0,0,CR1,0)';$S;
    'VSS_CR4':'(0,0,0,0,0,0,0,0,0,0,0,0,0,0,0,0,0,0,0,0,0,0,0,0,0,0,0,0,0,0,0,0,~
0,0,0,0,0,0,CR4,0)';$S;
    'VSS_CR6':'(0,0,0,0,0,0,0,0,0,0,0,0,0,0,0,0,0,0,0,0,0,0,0,0,0,0,0,0,0,0,0,0,~
0,0,0,0,0,0,CR6,0)';$S;
    'VSS_CR22':'(0,0,0,0,0,0,0,0,0,0,0,0,0,0,0,0,0,0,0,0,0,0,0,0,0,0,0,0,0,0,0,0~
,0,0,0,0,0,0,CR22,0)';$S;
    'VSS_CR25':'(0,0,0,0,0,0,0,0,0,0,0,0,0,0,0,0,0,0,0,0,0,0,0,0,0,0,0,0,0,0,0,0~
,0,0,0,0,0,0,CR25,0)';$S;
    'VSS_CR28':'(0,0,0,0,0,0,0,0,0,0,0,0,0,0,0,0,0,0,0,0,0,0,0,0,0,0,0,0,0,0,0,0~
,0,0,0,0,0,0,CR28,0)';$S;
    'VSS_CR31':'(0,0,0,0,0,0,0,0,0,0,0,0,0,0,0,0,0,0,0,0,0,0,0,0,0,0,0,0,0,0,0,0~
,0,0,0,0,0,0,CR31,0)';$S;
    'VSS_CR34':'(0,0,0,0,0,0,0,0,0,0,0,0,0,0,0,0,0,0,0,0,0,0,0,0,0,0,0,0,0,0,0,0~
,0,0,0,0,0,0,CR34,0)';$S;
    'VSS_CR48':'(0,0,0,0,0,0,0,0,0,0,0,0,0,0,0,0,0,0,0,0,0,0,0,0,0,0,0,0,0,0,0,0~
,0,0,0,0,0,0,CR48,0)';$S;
    'VSS_CR51':'(0,0,0,0,0,0,0,0,0,0,0,0,0,0,0,0,0,0,0,0,0,0,0,0,0,0,0,0,0,0,0,0~
,0,0,0,0,0,0,CR51,0)';$S;
    'VSS_CR54':'(0,0,0,0,0,0,0,0,0,0,0,0,0,0,0,0,0,0,0,0,0,0,0,0,0,0,0,0,0,0,0,0~
,0,0,0,0,0,0,CR54,0)';$S;
    'VSS_CR56':'(0,0,0,0,0,0,0,0,0,0,0,0,0,0,0,0,0,0,0,0,0,0,0,0,0,0,0,0,0,0,0,0~
,0,0,0,0,0,0,CR56,0)';$S;
    'VSS_CR58':'(0,0,0,0,0,0,0,0,0,0,0,0,0,0,0,0,0,0,0,0,0,0,0,0,0,0,0,0,0,0,0,0~
,0,0,0,0,0,0,CR58,0)';$S;
    'VSS_CR75':'(0,0,0,0,0,0,0,0,0,0,0,0,0,0,0,0,0,0,0,0,0,0,0,0,0,0,0,0,0,0,0,0~
,0,0,0,0,0,0,CR75,0)';$S;
    'VSS_CT3':'(0,0,0,0,0,0,0,0,0,0,0,0,0,0,0,0,0,0,0,0,0,0,0,0,0,0,0,0,0,0,0,0,~
0,0,0,0,0,0,CT3,0)';$S;
    'VSS_CT8':'(0,0,0,0,0,0,0,0,0,0,0,0,0,0,0,0,0,0,0,0,0,0,0,0,0,0,0,0,0,0,0,0,~
0,0,0,0,0,0,CT8,0)';$S;
    'VSS_CT10':'(0,0,0,0,0,0,0,0,0,0,0,0,0,0,0,0,0,0,0,0,0,0,0,0,0,0,0,0,0,0,0,0~
,0,0,0,0,0,0,CT10,0)';$S;
    'VSS_CT15':'(0,0,0,0,0,0,0,0,0,0,0,0,0,0,0,0,0,0,0,0,0,0,0,0,0,0,0,0,0,0,0,0~
,0,0,0,0,0,0,CT15,0)';$S;
    'VSS_CT48':'(0,0,0,0,0,0,0,0,0,0,0,0,0,0,0,0,0,0,0,0,0,0,0,0,0,0,0,0,0,0,0,0~
,0,0,0,0,0,0,CT48,0)';$S;
    'VSS_CT73':'(0,0,0,0,0,0,0,0,0,0,0,0,0,0,0,0,0,0,0,0,0,0,0,0,0,0,0,0,0,0,0,0~
,0,0,0,0,0,0,CT73,0)';$S;
    'VSS_CU1':'(0,0,0,0,0,0,0,0,0,0,0,0,0,0,0,0,0,0,0,0,0,0,0,0,0,0,0,0,0,0,0,0,~
0,0,0,0,0,0,CU1,0)';$S;
    'VSS_CU22':'(0,0,0,0,0,0,0,0,0,0,0,0,0,0,0,0,0,0,0,0,0,0,0,0,0,0,0,0,0,0,0,0~
,0,0,0,0,0,0,CU22,0)';$S;
    'VSS_CU25':'(0,0,0,0,0,0,0,0,0,0,0,0,0,0,0,0,0,0,0,0,0,0,0,0,0,0,0,0,0,0,0,0~
,0,0,0,0,0,0,CU25,0)';$S;
    'VSS_CU28':'(0,0,0,0,0,0,0,0,0,0,0,0,0,0,0,0,0,0,0,0,0,0,0,0,0,0,0,0,0,0,0,0~
,0,0,0,0,0,0,CU28,0)';$S;
    'VSS_CU56':'(0,0,0,0,0,0,0,0,0,0,0,0,0,0,0,0,0,0,0,0,0,0,0,0,0,0,0,0,0,0,0,0~
,0,0,0,0,0,0,CU56,0)';$S;
    'VSS_CU61':'(0,0,0,0,0,0,0,0,0,0,0,0,0,0,0,0,0,0,0,0,0,0,0,0,0,0,0,0,0,0,0,0~
,0,0,0,0,0,0,CU61,0)';$S;
    'VSS_CU63':'(0,0,0,0,0,0,0,0,0,0,0,0,0,0,0,0,0,0,0,0,0,0,0,0,0,0,0,0,0,0,0,0~
,0,0,0,0,0,0,CU63,0)';$S;
    'VSS_CV5':'(0,0,0,0,0,0,0,0,0,0,0,0,0,0,0,0,0,0,0,0,0,0,0,0,0,0,0,0,0,0,0,0,~
0,0,0,0,0,0,CV5,0)';$S;
    'VSS_CV8':'(0,0,0,0,0,0,0,0,0,0,0,0,0,0,0,0,0,0,0,0,0,0,0,0,0,0,0,0,0,0,0,0,~
0,0,0,0,0,0,CV8,0)';$S;
    'VSS_CV10':'(0,0,0,0,0,0,0,0,0,0,0,0,0,0,0,0,0,0,0,0,0,0,0,0,0,0,0,0,0,0,0,0~
,0,0,0,0,0,0,CV10,0)';$S;
    'VSS_CV12':'(0,0,0,0,0,0,0,0,0,0,0,0,0,0,0,0,0,0,0,0,0,0,0,0,0,0,0,0,0,0,0,0~
,0,0,0,0,0,0,CV12,0)';$S;
    'VSS_CV15':'(0,0,0,0,0,0,0,0,0,0,0,0,0,0,0,0,0,0,0,0,0,0,0,0,0,0,0,0,0,0,0,0~
,0,0,0,0,0,0,CV15,0)';$S;
    'VSS_CV34':'(0,0,0,0,0,0,0,0,0,0,0,0,0,0,0,0,0,0,0,0,0,0,0,0,0,0,0,0,0,0,0,0~
,0,0,0,0,0,0,CV34,0)';$S;
    'VSS_CV37':'(0,0,0,0,0,0,0,0,0,0,0,0,0,0,0,0,0,0,0,0,0,0,0,0,0,0,0,0,0,0,0,0~
,0,0,0,0,0,0,CV37,0)';$S;
    'VSS_CV39':'(0,0,0,0,0,0,0,0,0,0,0,0,0,0,0,0,0,0,0,0,0,0,0,0,0,0,0,0,0,0,0,0~
,0,0,0,0,0,0,CV39,0)';$S;
    'VSS_CV42':'(0,0,0,0,0,0,0,0,0,0,0,0,0,0,0,0,0,0,0,0,0,0,0,0,0,0,0,0,0,0,0,0~
,0,0,0,0,0,0,CV42,0)';$S;
    'VSS_CV45':'(0,0,0,0,0,0,0,0,0,0,0,0,0,0,0,0,0,0,0,0,0,0,0,0,0,0,0,0,0,0,0,0~
,0,0,0,0,0,0,CV45,0)';$S;
    'VSS_CV64':'(0,0,0,0,0,0,0,0,0,0,0,0,0,0,0,0,0,0,0,0,0,0,0,0,0,0,0,0,0,0,0,0~
,0,0,0,0,0,0,CV64,0)';$S;
    'VSS_CV66':'(0,0,0,0,0,0,0,0,0,0,0,0,0,0,0,0,0,0,0,0,0,0,0,0,0,0,0,0,0,0,0,0~
,0,0,0,0,0,0,CV66,0)';$S;
    'VSS_CV68':'(0,0,0,0,0,0,0,0,0,0,0,0,0,0,0,0,0,0,0,0,0,0,0,0,0,0,0,0,0,0,0,0~
,0,0,0,0,0,0,CV68,0)';$S;
    'VSS_CV71':'(0,0,0,0,0,0,0,0,0,0,0,0,0,0,0,0,0,0,0,0,0,0,0,0,0,0,0,0,0,0,0,0~
,0,0,0,0,0,0,CV71,0)';$S;
    'VSS_CV73':'(0,0,0,0,0,0,0,0,0,0,0,0,0,0,0,0,0,0,0,0,0,0,0,0,0,0,0,0,0,0,0,0~
,0,0,0,0,0,0,CV73,0)';$S;
    'VSS_CW22':'(0,0,0,0,0,0,0,0,0,0,0,0,0,0,0,0,0,0,0,0,0,0,0,0,0,0,0,0,0,0,0,0~
,0,0,0,0,0,0,CW22,0)';$S;
    'VSS_CW25':'(0,0,0,0,0,0,0,0,0,0,0,0,0,0,0,0,0,0,0,0,0,0,0,0,0,0,0,0,0,0,0,0~
,0,0,0,0,0,0,CW25,0)';$S;
    'VSS_CW28':'(0,0,0,0,0,0,0,0,0,0,0,0,0,0,0,0,0,0,0,0,0,0,0,0,0,0,0,0,0,0,0,0~
,0,0,0,0,0,0,CW28,0)';$S;
    'VSS_CW31':'(0,0,0,0,0,0,0,0,0,0,0,0,0,0,0,0,0,0,0,0,0,0,0,0,0,0,0,0,0,0,0,0~
,0,0,0,0,0,0,CW31,0)';$S;
    'VSS_CW34':'(0,0,0,0,0,0,0,0,0,0,0,0,0,0,0,0,0,0,0,0,0,0,0,0,0,0,0,0,0,0,0,0~
,0,0,0,0,0,0,CW34,0)';$S;
    'VSS_CY32':'(0,0,0,0,0,0,0,0,0,0,0,0,0,0,0,0,0,0,0,0,0,0,0,0,0,0,0,0,0,0,0,0~
,0,0,0,0,0,0,CY32,0)';$S;
    'VSS_CY47':'(0,0,0,0,0,0,0,0,0,0,0,0,0,0,0,0,0,0,0,0,0,0,0,0,0,0,0,0,0,0,0,0~
,0,0,0,0,0,0,CY47,0)';$S;
    'VSS_CY48':'(0,0,0,0,0,0,0,0,0,0,0,0,0,0,0,0,0,0,0,0,0,0,0,0,0,0,0,0,0,0,0,0~
,0,0,0,0,0,0,CY48,0)';$S;
    'VSS_CY64':'(0,0,0,0,0,0,0,0,0,0,0,0,0,0,0,0,0,0,0,0,0,0,0,0,0,0,0,0,0,0,0,0~
,0,0,0,0,0,0,CY64,0)';$S;
    'VSS_CY66':'(0,0,0,0,0,0,0,0,0,0,0,0,0,0,0,0,0,0,0,0,0,0,0,0,0,0,0,0,0,0,0,0~
,0,0,0,0,0,0,CY66,0)';$S;
    'VSS_CY68':'(0,0,0,0,0,0,0,0,0,0,0,0,0,0,0,0,0,0,0,0,0,0,0,0,0,0,0,0,0,0,0,0~
,0,0,0,0,0,0,CY68,0)';$S;
    'VSS_DA13':'(0,0,0,0,0,0,0,0,0,0,0,0,0,0,0,0,0,0,0,0,0,0,0,0,0,0,0,0,0,0,0,0~
,0,0,0,0,0,0,DA13,0)';$S;
    'VSS_DA15':'(0,0,0,0,0,0,0,0,0,0,0,0,0,0,0,0,0,0,0,0,0,0,0,0,0,0,0,0,0,0,0,0~
,0,0,0,0,0,0,DA15,0)';$S;
    'VSS_DA18':'(0,0,0,0,0,0,0,0,0,0,0,0,0,0,0,0,0,0,0,0,0,0,0,0,0,0,0,0,0,0,0,0~
,0,0,0,0,0,0,DA18,0)';$S;
    'VSS_DA20':'(0,0,0,0,0,0,0,0,0,0,0,0,0,0,0,0,0,0,0,0,0,0,0,0,0,0,0,0,0,0,0,0~
,0,0,0,0,0,0,DA20,0)';$S;
    'VSS_DA45':'(0,0,0,0,0,0,0,0,0,0,0,0,0,0,0,0,0,0,0,0,0,0,0,0,0,0,0,0,0,0,0,0~
,0,0,0,0,0,0,DA45,0)';$S;
    'VSS_DA48':'(0,0,0,0,0,0,0,0,0,0,0,0,0,0,0,0,0,0,0,0,0,0,0,0,0,0,0,0,0,0,0,0~
,0,0,0,0,0,0,DA48,0)';$S;
    'VSS_DA51':'(0,0,0,0,0,0,0,0,0,0,0,0,0,0,0,0,0,0,0,0,0,0,0,0,0,0,0,0,0,0,0,0~
,0,0,0,0,0,0,DA51,0)';$S;
    'VSS_DA54':'(0,0,0,0,0,0,0,0,0,0,0,0,0,0,0,0,0,0,0,0,0,0,0,0,0,0,0,0,0,0,0,0~
,0,0,0,0,0,0,DA54,0)';$S;
    'VSS_CP25':'(0,0,0,0,0,0,0,0,0,0,0,0,0,0,0,0,0,0,0,0,0,0,0,0,0,0,0,0,0,0,0,0~
,0,0,0,0,0,0,CP25,0)';$S;
    'VSS_CP28':'(0,0,0,0,0,0,0,0,0,0,0,0,0,0,0,0,0,0,0,0,0,0,0,0,0,0,0,0,0,0,0,0~
,0,0,0,0,0,0,CP28,0)';$S;
    'VSS_CP31':'(0,0,0,0,0,0,0,0,0,0,0,0,0,0,0,0,0,0,0,0,0,0,0,0,0,0,0,0,0,0,0,0~
,0,0,0,0,0,0,CP31,0)';$S;
    'VSS_CP34':'(0,0,0,0,0,0,0,0,0,0,0,0,0,0,0,0,0,0,0,0,0,0,0,0,0,0,0,0,0,0,0,0~
,0,0,0,0,0,0,CP34,0)';$S;
    'VSS_CP37':'(0,0,0,0,0,0,0,0,0,0,0,0,0,0,0,0,0,0,0,0,0,0,0,0,0,0,0,0,0,0,0,0~
,0,0,0,0,0,0,CP37,0)';$S;
    'VSS_CP39':'(0,0,0,0,0,0,0,0,0,0,0,0,0,0,0,0,0,0,0,0,0,0,0,0,0,0,0,0,0,0,0,0~
,0,0,0,0,0,0,CP39,0)';$S;
    'VSS_CP57':'(0,0,0,0,0,0,0,0,0,0,0,0,0,0,0,0,0,0,0,0,0,0,0,0,0,0,0,0,0,0,0,0~
,0,0,0,0,0,0,CP57,0)';$S;
    'VSS_CP59':'(0,0,0,0,0,0,0,0,0,0,0,0,0,0,0,0,0,0,0,0,0,0,0,0,0,0,0,0,0,0,0,0~
,0,0,0,0,0,0,CP59,0)';$S;
    'VSS_CP61':'(0,0,0,0,0,0,0,0,0,0,0,0,0,0,0,0,0,0,0,0,0,0,0,0,0,0,0,0,0,0,0,0~
,0,0,0,0,0,0,CP61,0)';$S;
    'VSS_CP64':'(0,0,0,0,0,0,0,0,0,0,0,0,0,0,0,0,0,0,0,0,0,0,0,0,0,0,0,0,0,0,0,0~
,0,0,0,0,0,0,CP64,0)';$S;
    'VSS_CP66':'(0,0,0,0,0,0,0,0,0,0,0,0,0,0,0,0,0,0,0,0,0,0,0,0,0,0,0,0,0,0,0,0~
,0,0,0,0,0,0,CP66,0)';$S;
    'VSS_CP68':'(0,0,0,0,0,0,0,0,0,0,0,0,0,0,0,0,0,0,0,0,0,0,0,0,0,0,0,0,0,0,0,0~
,0,0,0,0,0,0,CP68,0)';$S;
    'VSS_CR8':'(0,0,0,0,0,0,0,0,0,0,0,0,0,0,0,0,0,0,0,0,0,0,0,0,0,0,0,0,0,0,0,0,~
0,0,0,0,0,0,CR8,0)';$S;
    'VSS_CR11':'(0,0,0,0,0,0,0,0,0,0,0,0,0,0,0,0,0,0,0,0,0,0,0,0,0,0,0,0,0,0,0,0~
,0,0,0,0,0,0,CR11,0)';$S;
    'VSS_CR13':'(0,0,0,0,0,0,0,0,0,0,0,0,0,0,0,0,0,0,0,0,0,0,0,0,0,0,0,0,0,0,0,0~
,0,0,0,0,0,0,CR13,0)';$S;
    'VSS_CR15':'(0,0,0,0,0,0,0,0,0,0,0,0,0,0,0,0,0,0,0,0,0,0,0,0,0,0,0,0,0,0,0,0~
,0,0,0,0,0,0,CR15,0)';$S;
    'VSS_CR18':'(0,0,0,0,0,0,0,0,0,0,0,0,0,0,0,0,0,0,0,0,0,0,0,0,0,0,0,0,0,0,0,0~
,0,0,0,0,0,0,CR18,0)';$S;
    'VSS_CR20':'(0,0,0,0,0,0,0,0,0,0,0,0,0,0,0,0,0,0,0,0,0,0,0,0,0,0,0,0,0,0,0,0~
,0,0,0,0,0,0,CR20,0)';$S;
    'VSS_CR35':'(0,0,0,0,0,0,0,0,0,0,0,0,0,0,0,0,0,0,0,0,0,0,0,0,0,0,0,0,0,0,0,0~
,0,0,0,0,0,0,CR35,0)';$S;
    'VSS_CR36':'(0,0,0,0,0,0,0,0,0,0,0,0,0,0,0,0,0,0,0,0,0,0,0,0,0,0,0,0,0,0,0,0~
,0,0,0,0,0,0,CR36,0)';$S;
    'VSS_CR40':'(0,0,0,0,0,0,0,0,0,0,0,0,0,0,0,0,0,0,0,0,0,0,0,0,0,0,0,0,0,0,0,0~
,0,0,0,0,0,0,CR40,0)';$S;
    'VSS_CR41':'(0,0,0,0,0,0,0,0,0,0,0,0,0,0,0,0,0,0,0,0,0,0,0,0,0,0,0,0,0,0,0,0~
,0,0,0,0,0,0,CR41,0)';$S;
    'VSS_CR42':'(0,0,0,0,0,0,0,0,0,0,0,0,0,0,0,0,0,0,0,0,0,0,0,0,0,0,0,0,0,0,0,0~
,0,0,0,0,0,0,CR42,0)';$S;
    'VSS_CR45':'(0,0,0,0,0,0,0,0,0,0,0,0,0,0,0,0,0,0,0,0,0,0,0,0,0,0,0,0,0,0,0,0~
,0,0,0,0,0,0,CR45,0)';$S;
    'VSS_CR61':'(0,0,0,0,0,0,0,0,0,0,0,0,0,0,0,0,0,0,0,0,0,0,0,0,0,0,0,0,0,0,0,0~
,0,0,0,0,0,0,CR61,0)';$S;
    'VSS_CR63':'(0,0,0,0,0,0,0,0,0,0,0,0,0,0,0,0,0,0,0,0,0,0,0,0,0,0,0,0,0,0,0,0~
,0,0,0,0,0,0,CR63,0)';$S;
    'VSS_CR65':'(0,0,0,0,0,0,0,0,0,0,0,0,0,0,0,0,0,0,0,0,0,0,0,0,0,0,0,0,0,0,0,0~
,0,0,0,0,0,0,CR65,0)';$S;
    'VSS_CR68':'(0,0,0,0,0,0,0,0,0,0,0,0,0,0,0,0,0,0,0,0,0,0,0,0,0,0,0,0,0,0,0,0~
,0,0,0,0,0,0,CR68,0)';$S;
    'VSS_CR70':'(0,0,0,0,0,0,0,0,0,0,0,0,0,0,0,0,0,0,0,0,0,0,0,0,0,0,0,0,0,0,0,0~
,0,0,0,0,0,0,CR70,0)';$S;
    'VSS_CR72':'(0,0,0,0,0,0,0,0,0,0,0,0,0,0,0,0,0,0,0,0,0,0,0,0,0,0,0,0,0,0,0,0~
,0,0,0,0,0,0,CR72,0)';$S;
    'VSS_CT17':'(0,0,0,0,0,0,0,0,0,0,0,0,0,0,0,0,0,0,0,0,0,0,0,0,0,0,0,0,0,0,0,0~
,0,0,0,0,0,0,CT17,0)';$S;
    'VSS_CT23':'(0,0,0,0,0,0,0,0,0,0,0,0,0,0,0,0,0,0,0,0,0,0,0,0,0,0,0,0,0,0,0,0~
,0,0,0,0,0,0,CT23,0)';$S;
    'VSS_CT24':'(0,0,0,0,0,0,0,0,0,0,0,0,0,0,0,0,0,0,0,0,0,0,0,0,0,0,0,0,0,0,0,0~
,0,0,0,0,0,0,CT24,0)';$S;
    'VSS_CT25':'(0,0,0,0,0,0,0,0,0,0,0,0,0,0,0,0,0,0,0,0,0,0,0,0,0,0,0,0,0,0,0,0~
,0,0,0,0,0,0,CT25,0)';$S;
    'VSS_CT26':'(0,0,0,0,0,0,0,0,0,0,0,0,0,0,0,0,0,0,0,0,0,0,0,0,0,0,0,0,0,0,0,0~
,0,0,0,0,0,0,CT26,0)';$S;
    'VSS_CT27':'(0,0,0,0,0,0,0,0,0,0,0,0,0,0,0,0,0,0,0,0,0,0,0,0,0,0,0,0,0,0,0,0~
,0,0,0,0,0,0,CT27,0)';$S;
    'VSS_CT28':'(0,0,0,0,0,0,0,0,0,0,0,0,0,0,0,0,0,0,0,0,0,0,0,0,0,0,0,0,0,0,0,0~
,0,0,0,0,0,0,CT28,0)';$S;
    'VSS_CT29':'(0,0,0,0,0,0,0,0,0,0,0,0,0,0,0,0,0,0,0,0,0,0,0,0,0,0,0,0,0,0,0,0~
,0,0,0,0,0,0,CT29,0)';$S;
    'VSS_CT30':'(0,0,0,0,0,0,0,0,0,0,0,0,0,0,0,0,0,0,0,0,0,0,0,0,0,0,0,0,0,0,0,0~
,0,0,0,0,0,0,CT30,0)';$S;
    'VSS_CT31':'(0,0,0,0,0,0,0,0,0,0,0,0,0,0,0,0,0,0,0,0,0,0,0,0,0,0,0,0,0,0,0,0~
,0,0,0,0,0,0,CT31,0)';$S;
    'VSS_CT32':'(0,0,0,0,0,0,0,0,0,0,0,0,0,0,0,0,0,0,0,0,0,0,0,0,0,0,0,0,0,0,0,0~
,0,0,0,0,0,0,CT32,0)';$S;
    'VSS_CT33':'(0,0,0,0,0,0,0,0,0,0,0,0,0,0,0,0,0,0,0,0,0,0,0,0,0,0,0,0,0,0,0,0~
,0,0,0,0,0,0,CT33,0)';$S;
    'VSS_CT34':'(0,0,0,0,0,0,0,0,0,0,0,0,0,0,0,0,0,0,0,0,0,0,0,0,0,0,0,0,0,0,0,0~
,0,0,0,0,0,0,CT34,0)';$S;
    'VSS_CT37':'(0,0,0,0,0,0,0,0,0,0,0,0,0,0,0,0,0,0,0,0,0,0,0,0,0,0,0,0,0,0,0,0~
,0,0,0,0,0,0,CT37,0)';$S;
    'VSS_CT39':'(0,0,0,0,0,0,0,0,0,0,0,0,0,0,0,0,0,0,0,0,0,0,0,0,0,0,0,0,0,0,0,0~
,0,0,0,0,0,0,CT39,0)';$S;
    'VSS_CT42':'(0,0,0,0,0,0,0,0,0,0,0,0,0,0,0,0,0,0,0,0,0,0,0,0,0,0,0,0,0,0,0,0~
,0,0,0,0,0,0,CT42,0)';$S;
    'VSS_CT43':'(0,0,0,0,0,0,0,0,0,0,0,0,0,0,0,0,0,0,0,0,0,0,0,0,0,0,0,0,0,0,0,0~
,0,0,0,0,0,0,CT43,0)';$S;
    'VSS_CT44':'(0,0,0,0,0,0,0,0,0,0,0,0,0,0,0,0,0,0,0,0,0,0,0,0,0,0,0,0,0,0,0,0~
,0,0,0,0,0,0,CT44,0)';$S;
    'VSS_CT45':'(0,0,0,0,0,0,0,0,0,0,0,0,0,0,0,0,0,0,0,0,0,0,0,0,0,0,0,0,0,0,0,0~
,0,0,0,0,0,0,CT45,0)';$S;
    'VSS_CT46':'(0,0,0,0,0,0,0,0,0,0,0,0,0,0,0,0,0,0,0,0,0,0,0,0,0,0,0,0,0,0,0,0~
,0,0,0,0,0,0,CT46,0)';$S;
    'VSS_CT47':'(0,0,0,0,0,0,0,0,0,0,0,0,0,0,0,0,0,0,0,0,0,0,0,0,0,0,0,0,0,0,0,0~
,0,0,0,0,0,0,CT47,0)';$S;
    'VSS_CT49':'(0,0,0,0,0,0,0,0,0,0,0,0,0,0,0,0,0,0,0,0,0,0,0,0,0,0,0,0,0,0,0,0~
,0,0,0,0,0,0,CT49,0)';$S;
    'VSS_CT50':'(0,0,0,0,0,0,0,0,0,0,0,0,0,0,0,0,0,0,0,0,0,0,0,0,0,0,0,0,0,0,0,0~
,0,0,0,0,0,0,CT50,0)';$S;
    'VSS_CT51':'(0,0,0,0,0,0,0,0,0,0,0,0,0,0,0,0,0,0,0,0,0,0,0,0,0,0,0,0,0,0,0,0~
,0,0,0,0,0,0,CT51,0)';$S;
    'VSS_CT53':'(0,0,0,0,0,0,0,0,0,0,0,0,0,0,0,0,0,0,0,0,0,0,0,0,0,0,0,0,0,0,0,0~
,0,0,0,0,0,0,CT53,0)';$S;
    'VSS_CT59':'(0,0,0,0,0,0,0,0,0,0,0,0,0,0,0,0,0,0,0,0,0,0,0,0,0,0,0,0,0,0,0,0~
,0,0,0,0,0,0,CT59,0)';$S;
    'VSS_CT61':'(0,0,0,0,0,0,0,0,0,0,0,0,0,0,0,0,0,0,0,0,0,0,0,0,0,0,0,0,0,0,0,0~
,0,0,0,0,0,0,CT61,0)';$S;
    'VSS_CT66':'(0,0,0,0,0,0,0,0,0,0,0,0,0,0,0,0,0,0,0,0,0,0,0,0,0,0,0,0,0,0,0,0~
,0,0,0,0,0,0,CT66,0)';$S;
    'VSS_CT68':'(0,0,0,0,0,0,0,0,0,0,0,0,0,0,0,0,0,0,0,0,0,0,0,0,0,0,0,0,0,0,0,0~
,0,0,0,0,0,0,CT68,0)';$S;
    'VSS_CU4':'(0,0,0,0,0,0,0,0,0,0,0,0,0,0,0,0,0,0,0,0,0,0,0,0,0,0,0,0,0,0,0,0,~
0,0,0,0,0,0,CU4,0)';$S;
    'VSS_CU6':'(0,0,0,0,0,0,0,0,0,0,0,0,0,0,0,0,0,0,0,0,0,0,0,0,0,0,0,0,0,0,0,0,~
0,0,0,0,0,0,CU6,0)';$S;
    'VSS_CU8':'(0,0,0,0,0,0,0,0,0,0,0,0,0,0,0,0,0,0,0,0,0,0,0,0,0,0,0,0,0,0,0,0,~
0,0,0,0,0,0,CU8,0)';$S;
    'VSS_CU11':'(0,0,0,0,0,0,0,0,0,0,0,0,0,0,0,0,0,0,0,0,0,0,0,0,0,0,0,0,0,0,0,0~
,0,0,0,0,0,0,CU11,0)';$S;
    'VSS_CU13':'(0,0,0,0,0,0,0,0,0,0,0,0,0,0,0,0,0,0,0,0,0,0,0,0,0,0,0,0,0,0,0,0~
,0,0,0,0,0,0,CU13,0)';$S;
    'VSS_CU15':'(0,0,0,0,0,0,0,0,0,0,0,0,0,0,0,0,0,0,0,0,0,0,0,0,0,0,0,0,0,0,0,0~
,0,0,0,0,0,0,CU15,0)';$S;
    'VSS_CU18':'(0,0,0,0,0,0,0,0,0,0,0,0,0,0,0,0,0,0,0,0,0,0,0,0,0,0,0,0,0,0,0,0~
,0,0,0,0,0,0,CU18,0)';$S;
    'VSS_CU20':'(0,0,0,0,0,0,0,0,0,0,0,0,0,0,0,0,0,0,0,0,0,0,0,0,0,0,0,0,0,0,0,0~
,0,0,0,0,0,0,CU20,0)';$S;
    'VSS_CU31':'(0,0,0,0,0,0,0,0,0,0,0,0,0,0,0,0,0,0,0,0,0,0,0,0,0,0,0,0,0,0,0,0~
,0,0,0,0,0,0,CU31,0)';$S;
    'VSS_CU34':'(0,0,0,0,0,0,0,0,0,0,0,0,0,0,0,0,0,0,0,0,0,0,0,0,0,0,0,0,0,0,0,0~
,0,0,0,0,0,0,CU34,0)';$S;
    'VSS_CU42':'(0,0,0,0,0,0,0,0,0,0,0,0,0,0,0,0,0,0,0,0,0,0,0,0,0,0,0,0,0,0,0,0~
,0,0,0,0,0,0,CU42,0)';$S;
    'VSS_CU45':'(0,0,0,0,0,0,0,0,0,0,0,0,0,0,0,0,0,0,0,0,0,0,0,0,0,0,0,0,0,0,0,0~
,0,0,0,0,0,0,CU45,0)';$S;
    'VSS_CU48':'(0,0,0,0,0,0,0,0,0,0,0,0,0,0,0,0,0,0,0,0,0,0,0,0,0,0,0,0,0,0,0,0~
,0,0,0,0,0,0,CU48,0)';$S;
    'VSS_CU51':'(0,0,0,0,0,0,0,0,0,0,0,0,0,0,0,0,0,0,0,0,0,0,0,0,0,0,0,0,0,0,0,0~
,0,0,0,0,0,0,CU51,0)';$S;
    'VSS_CU54':'(0,0,0,0,0,0,0,0,0,0,0,0,0,0,0,0,0,0,0,0,0,0,0,0,0,0,0,0,0,0,0,0~
,0,0,0,0,0,0,CU54,0)';$S;
    'VSS_CU65':'(0,0,0,0,0,0,0,0,0,0,0,0,0,0,0,0,0,0,0,0,0,0,0,0,0,0,0,0,0,0,0,0~
,0,0,0,0,0,0,CU65,0)';$S;
    'VSS_CU68':'(0,0,0,0,0,0,0,0,0,0,0,0,0,0,0,0,0,0,0,0,0,0,0,0,0,0,0,0,0,0,0,0~
,0,0,0,0,0,0,CU68,0)';$S;
    'VSS_CU70':'(0,0,0,0,0,0,0,0,0,0,0,0,0,0,0,0,0,0,0,0,0,0,0,0,0,0,0,0,0,0,0,0~
,0,0,0,0,0,0,CU70,0)';$S;
    'VSS_CU72':'(0,0,0,0,0,0,0,0,0,0,0,0,0,0,0,0,0,0,0,0,0,0,0,0,0,0,0,0,0,0,0,0~
,0,0,0,0,0,0,CU72,0)';$S;
    'VSS_CU75':'(0,0,0,0,0,0,0,0,0,0,0,0,0,0,0,0,0,0,0,0,0,0,0,0,0,0,0,0,0,0,0,0~
,0,0,0,0,0,0,CU75,0)';$S;
    'VSS_CV3':'(0,0,0,0,0,0,0,0,0,0,0,0,0,0,0,0,0,0,0,0,0,0,0,0,0,0,0,0,0,0,0,0,~
0,0,0,0,0,0,CV3,0)';$S;
    'VSS_CV17':'(0,0,0,0,0,0,0,0,0,0,0,0,0,0,0,0,0,0,0,0,0,0,0,0,0,0,0,0,0,0,0,0~
,0,0,0,0,0,0,CV17,0)';$S;
    'VSS_CV19':'(0,0,0,0,0,0,0,0,0,0,0,0,0,0,0,0,0,0,0,0,0,0,0,0,0,0,0,0,0,0,0,0~
,0,0,0,0,0,0,CV19,0)';$S;
    'VSS_CV22':'(0,0,0,0,0,0,0,0,0,0,0,0,0,0,0,0,0,0,0,0,0,0,0,0,0,0,0,0,0,0,0,0~
,0,0,0,0,0,0,CV22,0)';$S;
    'VSS_CV25':'(0,0,0,0,0,0,0,0,0,0,0,0,0,0,0,0,0,0,0,0,0,0,0,0,0,0,0,0,0,0,0,0~
,0,0,0,0,0,0,CV25,0)';$S;
    'VSS_CV28':'(0,0,0,0,0,0,0,0,0,0,0,0,0,0,0,0,0,0,0,0,0,0,0,0,0,0,0,0,0,0,0,0~
,0,0,0,0,0,0,CV28,0)';$S;
    'VSS_CV31':'(0,0,0,0,0,0,0,0,0,0,0,0,0,0,0,0,0,0,0,0,0,0,0,0,0,0,0,0,0,0,0,0~
,0,0,0,0,0,0,CV31,0)';$S;
    'VSS_CV48':'(0,0,0,0,0,0,0,0,0,0,0,0,0,0,0,0,0,0,0,0,0,0,0,0,0,0,0,0,0,0,0,0~
,0,0,0,0,0,0,CV48,0)';$S;
    'VSS_CV51':'(0,0,0,0,0,0,0,0,0,0,0,0,0,0,0,0,0,0,0,0,0,0,0,0,0,0,0,0,0,0,0,0~
,0,0,0,0,0,0,CV51,0)';$S;
    'VSS_CV54':'(0,0,0,0,0,0,0,0,0,0,0,0,0,0,0,0,0,0,0,0,0,0,0,0,0,0,0,0,0,0,0,0~
,0,0,0,0,0,0,CV54,0)';$S;
    'VSS_CV57':'(0,0,0,0,0,0,0,0,0,0,0,0,0,0,0,0,0,0,0,0,0,0,0,0,0,0,0,0,0,0,0,0~
,0,0,0,0,0,0,CV57,0)';$S;
    'VSS_CV59':'(0,0,0,0,0,0,0,0,0,0,0,0,0,0,0,0,0,0,0,0,0,0,0,0,0,0,0,0,0,0,0,0~
,0,0,0,0,0,0,CV59,0)';$S;
    'VSS_CV61':'(0,0,0,0,0,0,0,0,0,0,0,0,0,0,0,0,0,0,0,0,0,0,0,0,0,0,0,0,0,0,0,0~
,0,0,0,0,0,0,CV61,0)';$S;
    'VSS_CW1':'(0,0,0,0,0,0,0,0,0,0,0,0,0,0,0,0,0,0,0,0,0,0,0,0,0,0,0,0,0,0,0,0,~
0,0,0,0,0,0,CW1,0)';$S;
    'VSS_CW6':'(0,0,0,0,0,0,0,0,0,0,0,0,0,0,0,0,0,0,0,0,0,0,0,0,0,0,0,0,0,0,0,0,~
0,0,0,0,0,0,CW6,0)';$S;
    'VSS_CW8':'(0,0,0,0,0,0,0,0,0,0,0,0,0,0,0,0,0,0,0,0,0,0,0,0,0,0,0,0,0,0,0,0,~
0,0,0,0,0,0,CW8,0)';$S;
    'VSS_CW13':'(0,0,0,0,0,0,0,0,0,0,0,0,0,0,0,0,0,0,0,0,0,0,0,0,0,0,0,0,0,0,0,0~
,0,0,0,0,0,0,CW13,0)';$S;
    'VSS_CW15':'(0,0,0,0,0,0,0,0,0,0,0,0,0,0,0,0,0,0,0,0,0,0,0,0,0,0,0,0,0,0,0,0~
,0,0,0,0,0,0,CW15,0)';$S;
    'VSS_CW20':'(0,0,0,0,0,0,0,0,0,0,0,0,0,0,0,0,0,0,0,0,0,0,0,0,0,0,0,0,0,0,0,0~
,0,0,0,0,0,0,CW20,0)';$S;
    'VSS_CW35':'(0,0,0,0,0,0,0,0,0,0,0,0,0,0,0,0,0,0,0,0,0,0,0,0,0,0,0,0,0,0,0,0~
,0,0,0,0,0,0,CW35,0)';$S;
    'VSS_CW36':'(0,0,0,0,0,0,0,0,0,0,0,0,0,0,0,0,0,0,0,0,0,0,0,0,0,0,0,0,0,0,0,0~
,0,0,0,0,0,0,CW36,0)';$S;
    'VSS_CW40':'(0,0,0,0,0,0,0,0,0,0,0,0,0,0,0,0,0,0,0,0,0,0,0,0,0,0,0,0,0,0,0,0~
,0,0,0,0,0,0,CW40,0)';$S;
    'VSS_CW41':'(0,0,0,0,0,0,0,0,0,0,0,0,0,0,0,0,0,0,0,0,0,0,0,0,0,0,0,0,0,0,0,0~
,0,0,0,0,0,0,CW41,0)';$S;
    'VSS_CW42':'(0,0,0,0,0,0,0,0,0,0,0,0,0,0,0,0,0,0,0,0,0,0,0,0,0,0,0,0,0,0,0,0~
,0,0,0,0,0,0,CW42,0)';$S;
    'VSS_CW45':'(0,0,0,0,0,0,0,0,0,0,0,0,0,0,0,0,0,0,0,0,0,0,0,0,0,0,0,0,0,0,0,0~
,0,0,0,0,0,0,CW45,0)';$S;
    'VSS_CW48':'(0,0,0,0,0,0,0,0,0,0,0,0,0,0,0,0,0,0,0,0,0,0,0,0,0,0,0,0,0,0,0,0~
,0,0,0,0,0,0,CW48,0)';$S;
    'VSS_CW51':'(0,0,0,0,0,0,0,0,0,0,0,0,0,0,0,0,0,0,0,0,0,0,0,0,0,0,0,0,0,0,0,0~
,0,0,0,0,0,0,CW51,0)';$S;
    'VSS_CW54':'(0,0,0,0,0,0,0,0,0,0,0,0,0,0,0,0,0,0,0,0,0,0,0,0,0,0,0,0,0,0,0,0~
,0,0,0,0,0,0,CW54,0)';$S;
    'VSS_CW56':'(0,0,0,0,0,0,0,0,0,0,0,0,0,0,0,0,0,0,0,0,0,0,0,0,0,0,0,0,0,0,0,0~
,0,0,0,0,0,0,CW56,0)';$S;
    'VSS_CW61':'(0,0,0,0,0,0,0,0,0,0,0,0,0,0,0,0,0,0,0,0,0,0,0,0,0,0,0,0,0,0,0,0~
,0,0,0,0,0,0,CW61,0)';$S;
    'VSS_CW63':'(0,0,0,0,0,0,0,0,0,0,0,0,0,0,0,0,0,0,0,0,0,0,0,0,0,0,0,0,0,0,0,0~
,0,0,0,0,0,0,CW63,0)';$S;
    'VSS_CW68':'(0,0,0,0,0,0,0,0,0,0,0,0,0,0,0,0,0,0,0,0,0,0,0,0,0,0,0,0,0,0,0,0~
,0,0,0,0,0,0,CW68,0)';$S;
    'VSS_CW70':'(0,0,0,0,0,0,0,0,0,0,0,0,0,0,0,0,0,0,0,0,0,0,0,0,0,0,0,0,0,0,0,0~
,0,0,0,0,0,0,CW70,0)';$S;
    'VSS_CW75':'(0,0,0,0,0,0,0,0,0,0,0,0,0,0,0,0,0,0,0,0,0,0,0,0,0,0,0,0,0,0,0,0~
,0,0,0,0,0,0,CW75,0)';$S;
    'VSS_CY3':'(0,0,0,0,0,0,0,0,0,0,0,0,0,0,0,0,0,0,0,0,0,0,0,0,0,0,0,0,0,0,0,0,~
0,0,0,0,0,0,CY3,0)';$S;
    'VSS_CY5':'(0,0,0,0,0,0,0,0,0,0,0,0,0,0,0,0,0,0,0,0,0,0,0,0,0,0,0,0,0,0,0,0,~
0,0,0,0,0,0,CY5,0)';$S;
    'VSS_CY8':'(0,0,0,0,0,0,0,0,0,0,0,0,0,0,0,0,0,0,0,0,0,0,0,0,0,0,0,0,0,0,0,0,~
0,0,0,0,0,0,CY8,0)';$S;
    'VSS_CY10':'(0,0,0,0,0,0,0,0,0,0,0,0,0,0,0,0,0,0,0,0,0,0,0,0,0,0,0,0,0,0,0,0~
,0,0,0,0,0,0,CY10,0)';$S;
    'VSS_CY12':'(0,0,0,0,0,0,0,0,0,0,0,0,0,0,0,0,0,0,0,0,0,0,0,0,0,0,0,0,0,0,0,0~
,0,0,0,0,0,0,CY12,0)';$S;
    'VSS_CY15':'(0,0,0,0,0,0,0,0,0,0,0,0,0,0,0,0,0,0,0,0,0,0,0,0,0,0,0,0,0,0,0,0~
,0,0,0,0,0,0,CY15,0)';$S;
    'VSS_CY17':'(0,0,0,0,0,0,0,0,0,0,0,0,0,0,0,0,0,0,0,0,0,0,0,0,0,0,0,0,0,0,0,0~
,0,0,0,0,0,0,CY17,0)';$S;
    'VSS_CY19':'(0,0,0,0,0,0,0,0,0,0,0,0,0,0,0,0,0,0,0,0,0,0,0,0,0,0,0,0,0,0,0,0~
,0,0,0,0,0,0,CY19,0)';$S;
    'VSS_CY23':'(0,0,0,0,0,0,0,0,0,0,0,0,0,0,0,0,0,0,0,0,0,0,0,0,0,0,0,0,0,0,0,0~
,0,0,0,0,0,0,CY23,0)';$S;
    'VSS_CY24':'(0,0,0,0,0,0,0,0,0,0,0,0,0,0,0,0,0,0,0,0,0,0,0,0,0,0,0,0,0,0,0,0~
,0,0,0,0,0,0,CY24,0)';$S;
    'VSS_CY25':'(0,0,0,0,0,0,0,0,0,0,0,0,0,0,0,0,0,0,0,0,0,0,0,0,0,0,0,0,0,0,0,0~
,0,0,0,0,0,0,CY25,0)';$S;
    'VSS_CY26':'(0,0,0,0,0,0,0,0,0,0,0,0,0,0,0,0,0,0,0,0,0,0,0,0,0,0,0,0,0,0,0,0~
,0,0,0,0,0,0,CY26,0)';$S;
    'VSS_CY27':'(0,0,0,0,0,0,0,0,0,0,0,0,0,0,0,0,0,0,0,0,0,0,0,0,0,0,0,0,0,0,0,0~
,0,0,0,0,0,0,CY27,0)';$S;
    'VSS_CY28':'(0,0,0,0,0,0,0,0,0,0,0,0,0,0,0,0,0,0,0,0,0,0,0,0,0,0,0,0,0,0,0,0~
,0,0,0,0,0,0,CY28,0)';$S;
    'VSS_CY29':'(0,0,0,0,0,0,0,0,0,0,0,0,0,0,0,0,0,0,0,0,0,0,0,0,0,0,0,0,0,0,0,0~
,0,0,0,0,0,0,CY29,0)';$S;
    'VSS_CY30':'(0,0,0,0,0,0,0,0,0,0,0,0,0,0,0,0,0,0,0,0,0,0,0,0,0,0,0,0,0,0,0,0~
,0,0,0,0,0,0,CY30,0)';$S;
    'VSS_CY31':'(0,0,0,0,0,0,0,0,0,0,0,0,0,0,0,0,0,0,0,0,0,0,0,0,0,0,0,0,0,0,0,0~
,0,0,0,0,0,0,CY31,0)';$S;
    'VSS_CY33':'(0,0,0,0,0,0,0,0,0,0,0,0,0,0,0,0,0,0,0,0,0,0,0,0,0,0,0,0,0,0,0,0~
,0,0,0,0,0,0,CY33,0)';$S;
    'VSS_CY34':'(0,0,0,0,0,0,0,0,0,0,0,0,0,0,0,0,0,0,0,0,0,0,0,0,0,0,0,0,0,0,0,0~
,0,0,0,0,0,0,CY34,0)';$S;
    'VSS_CY37':'(0,0,0,0,0,0,0,0,0,0,0,0,0,0,0,0,0,0,0,0,0,0,0,0,0,0,0,0,0,0,0,0~
,0,0,0,0,0,0,CY37,0)';$S;
    'VSS_CY39':'(0,0,0,0,0,0,0,0,0,0,0,0,0,0,0,0,0,0,0,0,0,0,0,0,0,0,0,0,0,0,0,0~
,0,0,0,0,0,0,CY39,0)';$S;
    'VSS_CY42':'(0,0,0,0,0,0,0,0,0,0,0,0,0,0,0,0,0,0,0,0,0,0,0,0,0,0,0,0,0,0,0,0~
,0,0,0,0,0,0,CY42,0)';$S;
    'VSS_CY43':'(0,0,0,0,0,0,0,0,0,0,0,0,0,0,0,0,0,0,0,0,0,0,0,0,0,0,0,0,0,0,0,0~
,0,0,0,0,0,0,CY43,0)';$S;
    'VSS_CY44':'(0,0,0,0,0,0,0,0,0,0,0,0,0,0,0,0,0,0,0,0,0,0,0,0,0,0,0,0,0,0,0,0~
,0,0,0,0,0,0,CY44,0)';$S;
    'VSS_CY45':'(0,0,0,0,0,0,0,0,0,0,0,0,0,0,0,0,0,0,0,0,0,0,0,0,0,0,0,0,0,0,0,0~
,0,0,0,0,0,0,CY45,0)';$S;
    'VSS_CY46':'(0,0,0,0,0,0,0,0,0,0,0,0,0,0,0,0,0,0,0,0,0,0,0,0,0,0,0,0,0,0,0,0~
,0,0,0,0,0,0,CY46,0)';$S;
    'VSS_CY49':'(0,0,0,0,0,0,0,0,0,0,0,0,0,0,0,0,0,0,0,0,0,0,0,0,0,0,0,0,0,0,0,0~
,0,0,0,0,0,0,CY49,0)';$S;
    'VSS_CY50':'(0,0,0,0,0,0,0,0,0,0,0,0,0,0,0,0,0,0,0,0,0,0,0,0,0,0,0,0,0,0,0,0~
,0,0,0,0,0,0,CY50,0)';$S;
    'VSS_CY51':'(0,0,0,0,0,0,0,0,0,0,0,0,0,0,0,0,0,0,0,0,0,0,0,0,0,0,0,0,0,0,0,0~
,0,0,0,0,0,0,CY51,0)';$S;
    'VSS_CY52':'(0,0,0,0,0,0,0,0,0,0,0,0,0,0,0,0,0,0,0,0,0,0,0,0,0,0,0,0,0,0,0,0~
,0,0,0,0,0,0,CY52,0)';$S;
    'VSS_CY53':'(0,0,0,0,0,0,0,0,0,0,0,0,0,0,0,0,0,0,0,0,0,0,0,0,0,0,0,0,0,0,0,0~
,0,0,0,0,0,0,CY53,0)';$S;
    'VSS_CY59':'(0,0,0,0,0,0,0,0,0,0,0,0,0,0,0,0,0,0,0,0,0,0,0,0,0,0,0,0,0,0,0,0~
,0,0,0,0,0,0,CY59,0)';$S;
    'VSS_CY61':'(0,0,0,0,0,0,0,0,0,0,0,0,0,0,0,0,0,0,0,0,0,0,0,0,0,0,0,0,0,0,0,0~
,0,0,0,0,0,0,CY61,0)';$S;
    'VSS_CY71':'(0,0,0,0,0,0,0,0,0,0,0,0,0,0,0,0,0,0,0,0,0,0,0,0,0,0,0,0,0,0,0,0~
,0,0,0,0,0,0,CY71,0)';$S;
    'VSS_CY73':'(0,0,0,0,0,0,0,0,0,0,0,0,0,0,0,0,0,0,0,0,0,0,0,0,0,0,0,0,0,0,0,0~
,0,0,0,0,0,0,CY73,0)';$S;
    'VSS_DA1':'(0,0,0,0,0,0,0,0,0,0,0,0,0,0,0,0,0,0,0,0,0,0,0,0,0,0,0,0,0,0,0,0,~
0,0,0,0,0,0,DA1,0)';$S;
    'VSS_DA4':'(0,0,0,0,0,0,0,0,0,0,0,0,0,0,0,0,0,0,0,0,0,0,0,0,0,0,0,0,0,0,0,0,~
0,0,0,0,0,0,DA4,0)';$S;
    'VSS_DA6':'(0,0,0,0,0,0,0,0,0,0,0,0,0,0,0,0,0,0,0,0,0,0,0,0,0,0,0,0,0,0,0,0,~
0,0,0,0,0,0,DA6,0)';$S;
    'VSS_DA8':'(0,0,0,0,0,0,0,0,0,0,0,0,0,0,0,0,0,0,0,0,0,0,0,0,0,0,0,0,0,0,0,0,~
0,0,0,0,0,0,DA8,0)';$S;
    'VSS_DA11':'(0,0,0,0,0,0,0,0,0,0,0,0,0,0,0,0,0,0,0,0,0,0,0,0,0,0,0,0,0,0,0,0~
,0,0,0,0,0,0,DA11,0)';$S;
    'VSS_DA22':'(0,0,0,0,0,0,0,0,0,0,0,0,0,0,0,0,0,0,0,0,0,0,0,0,0,0,0,0,0,0,0,0~
,0,0,0,0,0,0,DA22,0)';$S;
    'VSS_DA25':'(0,0,0,0,0,0,0,0,0,0,0,0,0,0,0,0,0,0,0,0,0,0,0,0,0,0,0,0,0,0,0,0~
,0,0,0,0,0,0,DA25,0)';$S;
    'VSS_DA28':'(0,0,0,0,0,0,0,0,0,0,0,0,0,0,0,0,0,0,0,0,0,0,0,0,0,0,0,0,0,0,0,0~
,0,0,0,0,0,0,DA28,0)';$S;
    'VSS_DA31':'(0,0,0,0,0,0,0,0,0,0,0,0,0,0,0,0,0,0,0,0,0,0,0,0,0,0,0,0,0,0,0,0~
,0,0,0,0,0,0,DA31,0)';$S;
    'VSS_DA34':'(0,0,0,0,0,0,0,0,0,0,0,0,0,0,0,0,0,0,0,0,0,0,0,0,0,0,0,0,0,0,0,0~
,0,0,0,0,0,0,DA34,0)';$S;
    'VSS_DA42':'(0,0,0,0,0,0,0,0,0,0,0,0,0,0,0,0,0,0,0,0,0,0,0,0,0,0,0,0,0,0,0,0~
,0,0,0,0,0,0,DA42,0)';$S;
    'VSS_DA58':'(0,0,0,0,0,0,0,0,0,0,0,0,0,0,0,0,0,0,0,0,0,0,0,0,0,0,0,0,0,0,0,0~
,0,0,0,0,0,0,DA58,0)';$S;
    'VSS_DA61':'(0,0,0,0,0,0,0,0,0,0,0,0,0,0,0,0,0,0,0,0,0,0,0,0,0,0,0,0,0,0,0,0~
,0,0,0,0,0,0,DA61,0)';$S;
    'VSS_DA63':'(0,0,0,0,0,0,0,0,0,0,0,0,0,0,0,0,0,0,0,0,0,0,0,0,0,0,0,0,0,0,0,0~
,0,0,0,0,0,0,DA63,0)';$S;
    'VSS_DA65':'(0,0,0,0,0,0,0,0,0,0,0,0,0,0,0,0,0,0,0,0,0,0,0,0,0,0,0,0,0,0,0,0~
,0,0,0,0,0,0,DA65,0)';$S;
    'VSS_DA68':'(0,0,0,0,0,0,0,0,0,0,0,0,0,0,0,0,0,0,0,0,0,0,0,0,0,0,0,0,0,0,0,0~
,0,0,0,0,0,0,DA68,0)';$S;
    'VSS_DA70':'(0,0,0,0,0,0,0,0,0,0,0,0,0,0,0,0,0,0,0,0,0,0,0,0,0,0,0,0,0,0,0,0~
,0,0,0,0,0,0,DA70,0)';$S;
    'VSS_DB15':'(0,0,0,0,0,0,0,0,0,0,0,0,0,0,0,0,0,0,0,0,0,0,0,0,0,0,0,0,0,0,0,0~
,0,0,0,0,0,0,0,DB15)';$S;
    'VSS_DB17':'(0,0,0,0,0,0,0,0,0,0,0,0,0,0,0,0,0,0,0,0,0,0,0,0,0,0,0,0,0,0,0,0~
,0,0,0,0,0,0,0,DB17)';$S;
    'VSS_DB22':'(0,0,0,0,0,0,0,0,0,0,0,0,0,0,0,0,0,0,0,0,0,0,0,0,0,0,0,0,0,0,0,0~
,0,0,0,0,0,0,0,DB22)';$S;
    'VSS_DB25':'(0,0,0,0,0,0,0,0,0,0,0,0,0,0,0,0,0,0,0,0,0,0,0,0,0,0,0,0,0,0,0,0~
,0,0,0,0,0,0,0,DB25)';$S;
    'VSS_DB48':'(0,0,0,0,0,0,0,0,0,0,0,0,0,0,0,0,0,0,0,0,0,0,0,0,0,0,0,0,0,0,0,0~
,0,0,0,0,0,0,0,DB48)';$S;
    'VSS_DB51':'(0,0,0,0,0,0,0,0,0,0,0,0,0,0,0,0,0,0,0,0,0,0,0,0,0,0,0,0,0,0,0,0~
,0,0,0,0,0,0,0,DB51)';$S;
    'VSS_DB54':'(0,0,0,0,0,0,0,0,0,0,0,0,0,0,0,0,0,0,0,0,0,0,0,0,0,0,0,0,0,0,0,0~
,0,0,0,0,0,0,0,DB54)';$S;
    'VSS_DB59':'(0,0,0,0,0,0,0,0,0,0,0,0,0,0,0,0,0,0,0,0,0,0,0,0,0,0,0,0,0,0,0,0~
,0,0,0,0,0,0,0,DB59)';$S;
    'VSS_DC13':'(0,0,0,0,0,0,0,0,0,0,0,0,0,0,0,0,0,0,0,0,0,0,0,0,0,0,0,0,0,0,0,0~
,0,0,0,0,0,0,0,DC13)';$S;
    'VSS_DC15':'(0,0,0,0,0,0,0,0,0,0,0,0,0,0,0,0,0,0,0,0,0,0,0,0,0,0,0,0,0,0,0,0~
,0,0,0,0,0,0,0,DC15)';$S;
    'VSS_DC45':'(0,0,0,0,0,0,0,0,0,0,0,0,0,0,0,0,0,0,0,0,0,0,0,0,0,0,0,0,0,0,0,0~
,0,0,0,0,0,0,0,DC45)';$S;
    'VSS_DC48':'(0,0,0,0,0,0,0,0,0,0,0,0,0,0,0,0,0,0,0,0,0,0,0,0,0,0,0,0,0,0,0,0~
,0,0,0,0,0,0,0,DC48)';$S;
    'VSS_DC51':'(0,0,0,0,0,0,0,0,0,0,0,0,0,0,0,0,0,0,0,0,0,0,0,0,0,0,0,0,0,0,0,0~
,0,0,0,0,0,0,0,DC51)';$S;
    'VSS_DC70':'(0,0,0,0,0,0,0,0,0,0,0,0,0,0,0,0,0,0,0,0,0,0,0,0,0,0,0,0,0,0,0,0~
,0,0,0,0,0,0,0,DC70)';$S;
    'VSS_DC72':'(0,0,0,0,0,0,0,0,0,0,0,0,0,0,0,0,0,0,0,0,0,0,0,0,0,0,0,0,0,0,0,0~
,0,0,0,0,0,0,0,DC72)';$S;
    'VSS_DC75':'(0,0,0,0,0,0,0,0,0,0,0,0,0,0,0,0,0,0,0,0,0,0,0,0,0,0,0,0,0,0,0,0~
,0,0,0,0,0,0,0,DC75)';$S;
    'VSS_DD3':'(0,0,0,0,0,0,0,0,0,0,0,0,0,0,0,0,0,0,0,0,0,0,0,0,0,0,0,0,0,0,0,0,~
0,0,0,0,0,0,0,DD3)';$S;
    'VSS_DD23':'(0,0,0,0,0,0,0,0,0,0,0,0,0,0,0,0,0,0,0,0,0,0,0,0,0,0,0,0,0,0,0,0~
,0,0,0,0,0,0,0,DD23)';$S;
    'VSS_DD24':'(0,0,0,0,0,0,0,0,0,0,0,0,0,0,0,0,0,0,0,0,0,0,0,0,0,0,0,0,0,0,0,0~
,0,0,0,0,0,0,0,DD24)';$S;
    'VSS_DD26':'(0,0,0,0,0,0,0,0,0,0,0,0,0,0,0,0,0,0,0,0,0,0,0,0,0,0,0,0,0,0,0,0~
,0,0,0,0,0,0,0,DD26)';$S;
    'VSS_DD27':'(0,0,0,0,0,0,0,0,0,0,0,0,0,0,0,0,0,0,0,0,0,0,0,0,0,0,0,0,0,0,0,0~
,0,0,0,0,0,0,0,DD27)';$S;
    'VSS_DD39':'(0,0,0,0,0,0,0,0,0,0,0,0,0,0,0,0,0,0,0,0,0,0,0,0,0,0,0,0,0,0,0,0~
,0,0,0,0,0,0,0,DD39)';$S;
    'VSS_DD40':'(0,0,0,0,0,0,0,0,0,0,0,0,0,0,0,0,0,0,0,0,0,0,0,0,0,0,0,0,0,0,0,0~
,0,0,0,0,0,0,0,DD40)';$S;
    'VSS_DD41':'(0,0,0,0,0,0,0,0,0,0,0,0,0,0,0,0,0,0,0,0,0,0,0,0,0,0,0,0,0,0,0,0~
,0,0,0,0,0,0,0,DD41)';$S;
    'VSS_DD43':'(0,0,0,0,0,0,0,0,0,0,0,0,0,0,0,0,0,0,0,0,0,0,0,0,0,0,0,0,0,0,0,0~
,0,0,0,0,0,0,0,DD43)';$S;
    'VSS_DD57':'(0,0,0,0,0,0,0,0,0,0,0,0,0,0,0,0,0,0,0,0,0,0,0,0,0,0,0,0,0,0,0,0~
,0,0,0,0,0,0,0,DD57)';$S;
    'VSS_DD59':'(0,0,0,0,0,0,0,0,0,0,0,0,0,0,0,0,0,0,0,0,0,0,0,0,0,0,0,0,0,0,0,0~
,0,0,0,0,0,0,0,DD59)';$S;
    'VSS_DD61':'(0,0,0,0,0,0,0,0,0,0,0,0,0,0,0,0,0,0,0,0,0,0,0,0,0,0,0,0,0,0,0,0~
,0,0,0,0,0,0,0,DD61)';$S;
    'VSS_DD64':'(0,0,0,0,0,0,0,0,0,0,0,0,0,0,0,0,0,0,0,0,0,0,0,0,0,0,0,0,0,0,0,0~
,0,0,0,0,0,0,0,DD64)';$S;
    'VSS_DE13':'(0,0,0,0,0,0,0,0,0,0,0,0,0,0,0,0,0,0,0,0,0,0,0,0,0,0,0,0,0,0,0,0~
,0,0,0,0,0,0,0,DE13)';$S;
    'VSS_DE15':'(0,0,0,0,0,0,0,0,0,0,0,0,0,0,0,0,0,0,0,0,0,0,0,0,0,0,0,0,0,0,0,0~
,0,0,0,0,0,0,0,DE15)';$S;
    'VSS_DE20':'(0,0,0,0,0,0,0,0,0,0,0,0,0,0,0,0,0,0,0,0,0,0,0,0,0,0,0,0,0,0,0,0~
,0,0,0,0,0,0,0,DE20)';$S;
    'VSS_DE23':'(0,0,0,0,0,0,0,0,0,0,0,0,0,0,0,0,0,0,0,0,0,0,0,0,0,0,0,0,0,0,0,0~
,0,0,0,0,0,0,0,DE23)';$S;
    'VSS_DE70':'(0,0,0,0,0,0,0,0,0,0,0,0,0,0,0,0,0,0,0,0,0,0,0,0,0,0,0,0,0,0,0,0~
,0,0,0,0,0,0,0,DE70)';$S;
    'VSS_DE75':'(0,0,0,0,0,0,0,0,0,0,0,0,0,0,0,0,0,0,0,0,0,0,0,0,0,0,0,0,0,0,0,0~
,0,0,0,0,0,0,0,DE75)';$S;
    'VSS_DF3':'(0,0,0,0,0,0,0,0,0,0,0,0,0,0,0,0,0,0,0,0,0,0,0,0,0,0,0,0,0,0,0,0,~
0,0,0,0,0,0,0,DF3)';$S;
    'VSS_DF4':'(0,0,0,0,0,0,0,0,0,0,0,0,0,0,0,0,0,0,0,0,0,0,0,0,0,0,0,0,0,0,0,0,~
0,0,0,0,0,0,0,DF4)';$S;
    'VSS_DF15':'(0,0,0,0,0,0,0,0,0,0,0,0,0,0,0,0,0,0,0,0,0,0,0,0,0,0,0,0,0,0,0,0~
,0,0,0,0,0,0,0,DF15)';$S;
    'VSS_DF17':'(0,0,0,0,0,0,0,0,0,0,0,0,0,0,0,0,0,0,0,0,0,0,0,0,0,0,0,0,0,0,0,0~
,0,0,0,0,0,0,0,DF17)';$S;
    'VSS_DF18':'(0,0,0,0,0,0,0,0,0,0,0,0,0,0,0,0,0,0,0,0,0,0,0,0,0,0,0,0,0,0,0,0~
,0,0,0,0,0,0,0,DF18)';$S;
    'VSS_DF19':'(0,0,0,0,0,0,0,0,0,0,0,0,0,0,0,0,0,0,0,0,0,0,0,0,0,0,0,0,0,0,0,0~
,0,0,0,0,0,0,0,DF19)';$S;
    'VSS_DF43':'(0,0,0,0,0,0,0,0,0,0,0,0,0,0,0,0,0,0,0,0,0,0,0,0,0,0,0,0,0,0,0,0~
,0,0,0,0,0,0,0,DF43)';$S;
    'VSS_DF53':'(0,0,0,0,0,0,0,0,0,0,0,0,0,0,0,0,0,0,0,0,0,0,0,0,0,0,0,0,0,0,0,0~
,0,0,0,0,0,0,0,DF53)';$S;
    'VSS_DF54':'(0,0,0,0,0,0,0,0,0,0,0,0,0,0,0,0,0,0,0,0,0,0,0,0,0,0,0,0,0,0,0,0~
,0,0,0,0,0,0,0,DF54)';$S;
    'VSS_DF66':'(0,0,0,0,0,0,0,0,0,0,0,0,0,0,0,0,0,0,0,0,0,0,0,0,0,0,0,0,0,0,0,0~
,0,0,0,0,0,0,0,DF66)';$S;
    'VSS_DF68':'(0,0,0,0,0,0,0,0,0,0,0,0,0,0,0,0,0,0,0,0,0,0,0,0,0,0,0,0,0,0,0,0~
,0,0,0,0,0,0,0,DF68)';$S;
    'VSS_DF70':'(0,0,0,0,0,0,0,0,0,0,0,0,0,0,0,0,0,0,0,0,0,0,0,0,0,0,0,0,0,0,0,0~
,0,0,0,0,0,0,0,DF70)';$S;
    'VSS_DG8':'(0,0,0,0,0,0,0,0,0,0,0,0,0,0,0,0,0,0,0,0,0,0,0,0,0,0,0,0,0,0,0,0,~
0,0,0,0,0,0,0,DG8)';$S;
    'VSS_DG9':'(0,0,0,0,0,0,0,0,0,0,0,0,0,0,0,0,0,0,0,0,0,0,0,0,0,0,0,0,0,0,0,0,~
0,0,0,0,0,0,0,DG9)';$S;
    'VSS_DG13':'(0,0,0,0,0,0,0,0,0,0,0,0,0,0,0,0,0,0,0,0,0,0,0,0,0,0,0,0,0,0,0,0~
,0,0,0,0,0,0,0,DG13)';$S;
    'VSS_DG14':'(0,0,0,0,0,0,0,0,0,0,0,0,0,0,0,0,0,0,0,0,0,0,0,0,0,0,0,0,0,0,0,0~
,0,0,0,0,0,0,0,DG14)';$S;
    'VSS_DG30':'(0,0,0,0,0,0,0,0,0,0,0,0,0,0,0,0,0,0,0,0,0,0,0,0,0,0,0,0,0,0,0,0~
,0,0,0,0,0,0,0,DG30)';$S;
    'VSS_DG33':'(0,0,0,0,0,0,0,0,0,0,0,0,0,0,0,0,0,0,0,0,0,0,0,0,0,0,0,0,0,0,0,0~
,0,0,0,0,0,0,0,DG33)';$S;
    'VSS_DG41':'(0,0,0,0,0,0,0,0,0,0,0,0,0,0,0,0,0,0,0,0,0,0,0,0,0,0,0,0,0,0,0,0~
,0,0,0,0,0,0,0,DG41)';$S;
    'VSS_DG43':'(0,0,0,0,0,0,0,0,0,0,0,0,0,0,0,0,0,0,0,0,0,0,0,0,0,0,0,0,0,0,0,0~
,0,0,0,0,0,0,0,DG43)';$S;
    'VSS_DG61':'(0,0,0,0,0,0,0,0,0,0,0,0,0,0,0,0,0,0,0,0,0,0,0,0,0,0,0,0,0,0,0,0~
,0,0,0,0,0,0,0,DG61)';$S;
    'VSS_DG62':'(0,0,0,0,0,0,0,0,0,0,0,0,0,0,0,0,0,0,0,0,0,0,0,0,0,0,0,0,0,0,0,0~
,0,0,0,0,0,0,0,DG62)';$S;
    'VSS_DG63':'(0,0,0,0,0,0,0,0,0,0,0,0,0,0,0,0,0,0,0,0,0,0,0,0,0,0,0,0,0,0,0,0~
,0,0,0,0,0,0,0,DG63)';$S;
    'VSS_DG65':'(0,0,0,0,0,0,0,0,0,0,0,0,0,0,0,0,0,0,0,0,0,0,0,0,0,0,0,0,0,0,0,0~
,0,0,0,0,0,0,0,DG65)';$S;
    'VSS_DH5':'(0,0,0,0,0,0,0,0,0,0,0,0,0,0,0,0,0,0,0,0,0,0,0,0,0,0,0,0,0,0,0,0,~
0,0,0,0,0,0,0,DH5)';$S;
    'VSS_DH11':'(0,0,0,0,0,0,0,0,0,0,0,0,0,0,0,0,0,0,0,0,0,0,0,0,0,0,0,0,0,0,0,0~
,0,0,0,0,0,0,0,DH11)';$S;
    'VSS_DH18':'(0,0,0,0,0,0,0,0,0,0,0,0,0,0,0,0,0,0,0,0,0,0,0,0,0,0,0,0,0,0,0,0~
,0,0,0,0,0,0,0,DH18)';$S;
    'VSS_DH37':'(0,0,0,0,0,0,0,0,0,0,0,0,0,0,0,0,0,0,0,0,0,0,0,0,0,0,0,0,0,0,0,0~
,0,0,0,0,0,0,0,DH37)';$S;
    'VSS_DH61':'(0,0,0,0,0,0,0,0,0,0,0,0,0,0,0,0,0,0,0,0,0,0,0,0,0,0,0,0,0,0,0,0~
,0,0,0,0,0,0,0,DH61)';$S;
    'VSS_DH63':'(0,0,0,0,0,0,0,0,0,0,0,0,0,0,0,0,0,0,0,0,0,0,0,0,0,0,0,0,0,0,0,0~
,0,0,0,0,0,0,0,DH63)';$S;
    'VSS_DH64':'(0,0,0,0,0,0,0,0,0,0,0,0,0,0,0,0,0,0,0,0,0,0,0,0,0,0,0,0,0,0,0,0~
,0,0,0,0,0,0,0,DH64)';$S;
    'VSS_DH66':'(0,0,0,0,0,0,0,0,0,0,0,0,0,0,0,0,0,0,0,0,0,0,0,0,0,0,0,0,0,0,0,0~
,0,0,0,0,0,0,0,DH66)';$S;
    'VSS_DA72':'(0,0,0,0,0,0,0,0,0,0,0,0,0,0,0,0,0,0,0,0,0,0,0,0,0,0,0,0,0,0,0,0~
,0,0,0,0,0,0,0,DA72)';$S;
    'VSS_DA75':'(0,0,0,0,0,0,0,0,0,0,0,0,0,0,0,0,0,0,0,0,0,0,0,0,0,0,0,0,0,0,0,0~
,0,0,0,0,0,0,0,DA75)';$S;
    'VSS_DB3':'(0,0,0,0,0,0,0,0,0,0,0,0,0,0,0,0,0,0,0,0,0,0,0,0,0,0,0,0,0,0,0,0,~
0,0,0,0,0,0,0,DB3)';$S;
    'VSS_DB8':'(0,0,0,0,0,0,0,0,0,0,0,0,0,0,0,0,0,0,0,0,0,0,0,0,0,0,0,0,0,0,0,0,~
0,0,0,0,0,0,0,DB8)';$S;
    'VSS_DB10':'(0,0,0,0,0,0,0,0,0,0,0,0,0,0,0,0,0,0,0,0,0,0,0,0,0,0,0,0,0,0,0,0~
,0,0,0,0,0,0,0,DB10)';$S;
    'VSS_DB28':'(0,0,0,0,0,0,0,0,0,0,0,0,0,0,0,0,0,0,0,0,0,0,0,0,0,0,0,0,0,0,0,0~
,0,0,0,0,0,0,0,DB28)';$S;
    'VSS_DB31':'(0,0,0,0,0,0,0,0,0,0,0,0,0,0,0,0,0,0,0,0,0,0,0,0,0,0,0,0,0,0,0,0~
,0,0,0,0,0,0,0,DB31)';$S;
    'VSS_DB34':'(0,0,0,0,0,0,0,0,0,0,0,0,0,0,0,0,0,0,0,0,0,0,0,0,0,0,0,0,0,0,0,0~
,0,0,0,0,0,0,0,DB34)';$S;
    'VSS_DB37':'(0,0,0,0,0,0,0,0,0,0,0,0,0,0,0,0,0,0,0,0,0,0,0,0,0,0,0,0,0,0,0,0~
,0,0,0,0,0,0,0,DB37)';$S;
    'VSS_DB39':'(0,0,0,0,0,0,0,0,0,0,0,0,0,0,0,0,0,0,0,0,0,0,0,0,0,0,0,0,0,0,0,0~
,0,0,0,0,0,0,0,DB39)';$S;
    'VSS_DB42':'(0,0,0,0,0,0,0,0,0,0,0,0,0,0,0,0,0,0,0,0,0,0,0,0,0,0,0,0,0,0,0,0~
,0,0,0,0,0,0,0,DB42)';$S;
    'VSS_DB45':'(0,0,0,0,0,0,0,0,0,0,0,0,0,0,0,0,0,0,0,0,0,0,0,0,0,0,0,0,0,0,0,0~
,0,0,0,0,0,0,0,DB45)';$S;
    'VSS_DB61':'(0,0,0,0,0,0,0,0,0,0,0,0,0,0,0,0,0,0,0,0,0,0,0,0,0,0,0,0,0,0,0,0~
,0,0,0,0,0,0,0,DB61)';$S;
    'VSS_DB66':'(0,0,0,0,0,0,0,0,0,0,0,0,0,0,0,0,0,0,0,0,0,0,0,0,0,0,0,0,0,0,0,0~
,0,0,0,0,0,0,0,DB66)';$S;
    'VSS_DB68':'(0,0,0,0,0,0,0,0,0,0,0,0,0,0,0,0,0,0,0,0,0,0,0,0,0,0,0,0,0,0,0,0~
,0,0,0,0,0,0,0,DB68)';$S;
    'VSS_DB73':'(0,0,0,0,0,0,0,0,0,0,0,0,0,0,0,0,0,0,0,0,0,0,0,0,0,0,0,0,0,0,0,0~
,0,0,0,0,0,0,0,DB73)';$S;
    'VSS_DC1':'(0,0,0,0,0,0,0,0,0,0,0,0,0,0,0,0,0,0,0,0,0,0,0,0,0,0,0,0,0,0,0,0,~
0,0,0,0,0,0,0,DC1)';$S;
    'VSS_DC4':'(0,0,0,0,0,0,0,0,0,0,0,0,0,0,0,0,0,0,0,0,0,0,0,0,0,0,0,0,0,0,0,0,~
0,0,0,0,0,0,0,DC4)';$S;
    'VSS_DC6':'(0,0,0,0,0,0,0,0,0,0,0,0,0,0,0,0,0,0,0,0,0,0,0,0,0,0,0,0,0,0,0,0,~
0,0,0,0,0,0,0,DC6)';$S;
    'VSS_DC8':'(0,0,0,0,0,0,0,0,0,0,0,0,0,0,0,0,0,0,0,0,0,0,0,0,0,0,0,0,0,0,0,0,~
0,0,0,0,0,0,0,DC8)';$S;
    'VSS_DC11':'(0,0,0,0,0,0,0,0,0,0,0,0,0,0,0,0,0,0,0,0,0,0,0,0,0,0,0,0,0,0,0,0~
,0,0,0,0,0,0,0,DC11)';$S;
    'VSS_DC18':'(0,0,0,0,0,0,0,0,0,0,0,0,0,0,0,0,0,0,0,0,0,0,0,0,0,0,0,0,0,0,0,0~
,0,0,0,0,0,0,0,DC18)';$S;
    'VSS_DC20':'(0,0,0,0,0,0,0,0,0,0,0,0,0,0,0,0,0,0,0,0,0,0,0,0,0,0,0,0,0,0,0,0~
,0,0,0,0,0,0,0,DC20)';$S;
    'VSS_DC22':'(0,0,0,0,0,0,0,0,0,0,0,0,0,0,0,0,0,0,0,0,0,0,0,0,0,0,0,0,0,0,0,0~
,0,0,0,0,0,0,0,DC22)';$S;
    'VSS_DC25':'(0,0,0,0,0,0,0,0,0,0,0,0,0,0,0,0,0,0,0,0,0,0,0,0,0,0,0,0,0,0,0,0~
,0,0,0,0,0,0,0,DC25)';$S;
    'VSS_DC28':'(0,0,0,0,0,0,0,0,0,0,0,0,0,0,0,0,0,0,0,0,0,0,0,0,0,0,0,0,0,0,0,0~
,0,0,0,0,0,0,0,DC28)';$S;
    'VSS_DC31':'(0,0,0,0,0,0,0,0,0,0,0,0,0,0,0,0,0,0,0,0,0,0,0,0,0,0,0,0,0,0,0,0~
,0,0,0,0,0,0,0,DC31)';$S;
    'VSS_DC34':'(0,0,0,0,0,0,0,0,0,0,0,0,0,0,0,0,0,0,0,0,0,0,0,0,0,0,0,0,0,0,0,0~
,0,0,0,0,0,0,0,DC34)';$S;
    'VSS_DC42':'(0,0,0,0,0,0,0,0,0,0,0,0,0,0,0,0,0,0,0,0,0,0,0,0,0,0,0,0,0,0,0,0~
,0,0,0,0,0,0,0,DC42)';$S;
    'VSS_DC54':'(0,0,0,0,0,0,0,0,0,0,0,0,0,0,0,0,0,0,0,0,0,0,0,0,0,0,0,0,0,0,0,0~
,0,0,0,0,0,0,0,DC54)';$S;
    'VSS_DC56':'(0,0,0,0,0,0,0,0,0,0,0,0,0,0,0,0,0,0,0,0,0,0,0,0,0,0,0,0,0,0,0,0~
,0,0,0,0,0,0,0,DC56)';$S;
    'VSS_DC58':'(0,0,0,0,0,0,0,0,0,0,0,0,0,0,0,0,0,0,0,0,0,0,0,0,0,0,0,0,0,0,0,0~
,0,0,0,0,0,0,0,DC58)';$S;
    'VSS_DC61':'(0,0,0,0,0,0,0,0,0,0,0,0,0,0,0,0,0,0,0,0,0,0,0,0,0,0,0,0,0,0,0,0~
,0,0,0,0,0,0,0,DC61)';$S;
    'VSS_DC63':'(0,0,0,0,0,0,0,0,0,0,0,0,0,0,0,0,0,0,0,0,0,0,0,0,0,0,0,0,0,0,0,0~
,0,0,0,0,0,0,0,DC63)';$S;
    'VSS_DC65':'(0,0,0,0,0,0,0,0,0,0,0,0,0,0,0,0,0,0,0,0,0,0,0,0,0,0,0,0,0,0,0,0~
,0,0,0,0,0,0,0,DC65)';$S;
    'VSS_DC68':'(0,0,0,0,0,0,0,0,0,0,0,0,0,0,0,0,0,0,0,0,0,0,0,0,0,0,0,0,0,0,0,0~
,0,0,0,0,0,0,0,DC68)';$S;
    'VSS_DD5':'(0,0,0,0,0,0,0,0,0,0,0,0,0,0,0,0,0,0,0,0,0,0,0,0,0,0,0,0,0,0,0,0,~
0,0,0,0,0,0,0,DD5)';$S;
    'VSS_DD8':'(0,0,0,0,0,0,0,0,0,0,0,0,0,0,0,0,0,0,0,0,0,0,0,0,0,0,0,0,0,0,0,0,~
0,0,0,0,0,0,0,DD8)';$S;
    'VSS_DD10':'(0,0,0,0,0,0,0,0,0,0,0,0,0,0,0,0,0,0,0,0,0,0,0,0,0,0,0,0,0,0,0,0~
,0,0,0,0,0,0,0,DD10)';$S;
    'VSS_DD12':'(0,0,0,0,0,0,0,0,0,0,0,0,0,0,0,0,0,0,0,0,0,0,0,0,0,0,0,0,0,0,0,0~
,0,0,0,0,0,0,0,DD12)';$S;
    'VSS_DD15':'(0,0,0,0,0,0,0,0,0,0,0,0,0,0,0,0,0,0,0,0,0,0,0,0,0,0,0,0,0,0,0,0~
,0,0,0,0,0,0,0,DD15)';$S;
    'VSS_DD17':'(0,0,0,0,0,0,0,0,0,0,0,0,0,0,0,0,0,0,0,0,0,0,0,0,0,0,0,0,0,0,0,0~
,0,0,0,0,0,0,0,DD17)';$S;
    'VSS_DD19':'(0,0,0,0,0,0,0,0,0,0,0,0,0,0,0,0,0,0,0,0,0,0,0,0,0,0,0,0,0,0,0,0~
,0,0,0,0,0,0,0,DD19)';$S;
    'VSS_DD29':'(0,0,0,0,0,0,0,0,0,0,0,0,0,0,0,0,0,0,0,0,0,0,0,0,0,0,0,0,0,0,0,0~
,0,0,0,0,0,0,0,DD29)';$S;
    'VSS_DD30':'(0,0,0,0,0,0,0,0,0,0,0,0,0,0,0,0,0,0,0,0,0,0,0,0,0,0,0,0,0,0,0,0~
,0,0,0,0,0,0,0,DD30)';$S;
    'VSS_DD32':'(0,0,0,0,0,0,0,0,0,0,0,0,0,0,0,0,0,0,0,0,0,0,0,0,0,0,0,0,0,0,0,0~
,0,0,0,0,0,0,0,DD32)';$S;
    'VSS_DD33':'(0,0,0,0,0,0,0,0,0,0,0,0,0,0,0,0,0,0,0,0,0,0,0,0,0,0,0,0,0,0,0,0~
,0,0,0,0,0,0,0,DD33)';$S;
    'VSS_DD35':'(0,0,0,0,0,0,0,0,0,0,0,0,0,0,0,0,0,0,0,0,0,0,0,0,0,0,0,0,0,0,0,0~
,0,0,0,0,0,0,0,DD35)';$S;
    'VSS_DD36':'(0,0,0,0,0,0,0,0,0,0,0,0,0,0,0,0,0,0,0,0,0,0,0,0,0,0,0,0,0,0,0,0~
,0,0,0,0,0,0,0,DD36)';$S;
    'VSS_DD37':'(0,0,0,0,0,0,0,0,0,0,0,0,0,0,0,0,0,0,0,0,0,0,0,0,0,0,0,0,0,0,0,0~
,0,0,0,0,0,0,0,DD37)';$S;
    'VSS_DD44':'(0,0,0,0,0,0,0,0,0,0,0,0,0,0,0,0,0,0,0,0,0,0,0,0,0,0,0,0,0,0,0,0~
,0,0,0,0,0,0,0,DD44)';$S;
    'VSS_DD46':'(0,0,0,0,0,0,0,0,0,0,0,0,0,0,0,0,0,0,0,0,0,0,0,0,0,0,0,0,0,0,0,0~
,0,0,0,0,0,0,0,DD46)';$S;
    'VSS_DD47':'(0,0,0,0,0,0,0,0,0,0,0,0,0,0,0,0,0,0,0,0,0,0,0,0,0,0,0,0,0,0,0,0~
,0,0,0,0,0,0,0,DD47)';$S;
    'VSS_DD49':'(0,0,0,0,0,0,0,0,0,0,0,0,0,0,0,0,0,0,0,0,0,0,0,0,0,0,0,0,0,0,0,0~
,0,0,0,0,0,0,0,DD49)';$S;
    'VSS_DD50':'(0,0,0,0,0,0,0,0,0,0,0,0,0,0,0,0,0,0,0,0,0,0,0,0,0,0,0,0,0,0,0,0~
,0,0,0,0,0,0,0,DD50)';$S;
    'VSS_DD52':'(0,0,0,0,0,0,0,0,0,0,0,0,0,0,0,0,0,0,0,0,0,0,0,0,0,0,0,0,0,0,0,0~
,0,0,0,0,0,0,0,DD52)';$S;
    'VSS_DD53':'(0,0,0,0,0,0,0,0,0,0,0,0,0,0,0,0,0,0,0,0,0,0,0,0,0,0,0,0,0,0,0,0~
,0,0,0,0,0,0,0,DD53)';$S;
    'VSS_DD66':'(0,0,0,0,0,0,0,0,0,0,0,0,0,0,0,0,0,0,0,0,0,0,0,0,0,0,0,0,0,0,0,0~
,0,0,0,0,0,0,0,DD66)';$S;
    'VSS_DD68':'(0,0,0,0,0,0,0,0,0,0,0,0,0,0,0,0,0,0,0,0,0,0,0,0,0,0,0,0,0,0,0,0~
,0,0,0,0,0,0,0,DD68)';$S;
    'VSS_DD71':'(0,0,0,0,0,0,0,0,0,0,0,0,0,0,0,0,0,0,0,0,0,0,0,0,0,0,0,0,0,0,0,0~
,0,0,0,0,0,0,0,DD71)';$S;
    'VSS_DD73':'(0,0,0,0,0,0,0,0,0,0,0,0,0,0,0,0,0,0,0,0,0,0,0,0,0,0,0,0,0,0,0,0~
,0,0,0,0,0,0,0,DD73)';$S;
    'VSS_DE1':'(0,0,0,0,0,0,0,0,0,0,0,0,0,0,0,0,0,0,0,0,0,0,0,0,0,0,0,0,0,0,0,0,~
0,0,0,0,0,0,0,DE1)';$S;
    'VSS_DE6':'(0,0,0,0,0,0,0,0,0,0,0,0,0,0,0,0,0,0,0,0,0,0,0,0,0,0,0,0,0,0,0,0,~
0,0,0,0,0,0,0,DE6)';$S;
    'VSS_DE8':'(0,0,0,0,0,0,0,0,0,0,0,0,0,0,0,0,0,0,0,0,0,0,0,0,0,0,0,0,0,0,0,0,~
0,0,0,0,0,0,0,DE8)';$S;
    'VSS_DE26':'(0,0,0,0,0,0,0,0,0,0,0,0,0,0,0,0,0,0,0,0,0,0,0,0,0,0,0,0,0,0,0,0~
,0,0,0,0,0,0,0,DE26)';$S;
    'VSS_DE29':'(0,0,0,0,0,0,0,0,0,0,0,0,0,0,0,0,0,0,0,0,0,0,0,0,0,0,0,0,0,0,0,0~
,0,0,0,0,0,0,0,DE29)';$S;
    'VSS_DE33':'(0,0,0,0,0,0,0,0,0,0,0,0,0,0,0,0,0,0,0,0,0,0,0,0,0,0,0,0,0,0,0,0~
,0,0,0,0,0,0,0,DE33)';$S;
    'VSS_DE56':'(0,0,0,0,0,0,0,0,0,0,0,0,0,0,0,0,0,0,0,0,0,0,0,0,0,0,0,0,0,0,0,0~
,0,0,0,0,0,0,0,DE56)';$S;
    'VSS_DE61':'(0,0,0,0,0,0,0,0,0,0,0,0,0,0,0,0,0,0,0,0,0,0,0,0,0,0,0,0,0,0,0,0~
,0,0,0,0,0,0,0,DE61)';$S;
    'VSS_DE63':'(0,0,0,0,0,0,0,0,0,0,0,0,0,0,0,0,0,0,0,0,0,0,0,0,0,0,0,0,0,0,0,0~
,0,0,0,0,0,0,0,DE63)';$S;
    'VSS_DE68':'(0,0,0,0,0,0,0,0,0,0,0,0,0,0,0,0,0,0,0,0,0,0,0,0,0,0,0,0,0,0,0,0~
,0,0,0,0,0,0,0,DE68)';$S;
    'VSS_DF5':'(0,0,0,0,0,0,0,0,0,0,0,0,0,0,0,0,0,0,0,0,0,0,0,0,0,0,0,0,0,0,0,0,~
0,0,0,0,0,0,0,DF5)';$S;
    'VSS_DF6':'(0,0,0,0,0,0,0,0,0,0,0,0,0,0,0,0,0,0,0,0,0,0,0,0,0,0,0,0,0,0,0,0,~
0,0,0,0,0,0,0,DF6)';$S;
    'VSS_DF8':'(0,0,0,0,0,0,0,0,0,0,0,0,0,0,0,0,0,0,0,0,0,0,0,0,0,0,0,0,0,0,0,0,~
0,0,0,0,0,0,0,DF8)';$S;
    'VSS_DF10':'(0,0,0,0,0,0,0,0,0,0,0,0,0,0,0,0,0,0,0,0,0,0,0,0,0,0,0,0,0,0,0,0~
,0,0,0,0,0,0,0,DF10)';$S;
    'VSS_DF11':'(0,0,0,0,0,0,0,0,0,0,0,0,0,0,0,0,0,0,0,0,0,0,0,0,0,0,0,0,0,0,0,0~
,0,0,0,0,0,0,0,DF11)';$S;
    'VSS_DF12':'(0,0,0,0,0,0,0,0,0,0,0,0,0,0,0,0,0,0,0,0,0,0,0,0,0,0,0,0,0,0,0,0~
,0,0,0,0,0,0,0,DF12)';$S;
    'VSS_DF13':'(0,0,0,0,0,0,0,0,0,0,0,0,0,0,0,0,0,0,0,0,0,0,0,0,0,0,0,0,0,0,0,0~
,0,0,0,0,0,0,0,DF13)';$S;
    'VSS_DF20':'(0,0,0,0,0,0,0,0,0,0,0,0,0,0,0,0,0,0,0,0,0,0,0,0,0,0,0,0,0,0,0,0~
,0,0,0,0,0,0,0,DF20)';$S;
    'VSS_DF22':'(0,0,0,0,0,0,0,0,0,0,0,0,0,0,0,0,0,0,0,0,0,0,0,0,0,0,0,0,0,0,0,0~
,0,0,0,0,0,0,0,DF22)';$S;
    'VSS_DF23':'(0,0,0,0,0,0,0,0,0,0,0,0,0,0,0,0,0,0,0,0,0,0,0,0,0,0,0,0,0,0,0,0~
,0,0,0,0,0,0,0,DF23)';$S;
    'VSS_DF26':'(0,0,0,0,0,0,0,0,0,0,0,0,0,0,0,0,0,0,0,0,0,0,0,0,0,0,0,0,0,0,0,0~
,0,0,0,0,0,0,0,DF26)';$S;
    'VSS_DF29':'(0,0,0,0,0,0,0,0,0,0,0,0,0,0,0,0,0,0,0,0,0,0,0,0,0,0,0,0,0,0,0,0~
,0,0,0,0,0,0,0,DF29)';$S;
    'VSS_DF32':'(0,0,0,0,0,0,0,0,0,0,0,0,0,0,0,0,0,0,0,0,0,0,0,0,0,0,0,0,0,0,0,0~
,0,0,0,0,0,0,0,DF32)';$S;
    'VSS_DF35':'(0,0,0,0,0,0,0,0,0,0,0,0,0,0,0,0,0,0,0,0,0,0,0,0,0,0,0,0,0,0,0,0~
,0,0,0,0,0,0,0,DF35)';$S;
    'VSS_DF37':'(0,0,0,0,0,0,0,0,0,0,0,0,0,0,0,0,0,0,0,0,0,0,0,0,0,0,0,0,0,0,0,0~
,0,0,0,0,0,0,0,DF37)';$S;
    'VSS_DF39':'(0,0,0,0,0,0,0,0,0,0,0,0,0,0,0,0,0,0,0,0,0,0,0,0,0,0,0,0,0,0,0,0~
,0,0,0,0,0,0,0,DF39)';$S;
    'VSS_DF42':'(0,0,0,0,0,0,0,0,0,0,0,0,0,0,0,0,0,0,0,0,0,0,0,0,0,0,0,0,0,0,0,0~
,0,0,0,0,0,0,0,DF42)';$S;
    'VSS_DF44':'(0,0,0,0,0,0,0,0,0,0,0,0,0,0,0,0,0,0,0,0,0,0,0,0,0,0,0,0,0,0,0,0~
,0,0,0,0,0,0,0,DF44)';$S;
    'VSS_DF45':'(0,0,0,0,0,0,0,0,0,0,0,0,0,0,0,0,0,0,0,0,0,0,0,0,0,0,0,0,0,0,0,0~
,0,0,0,0,0,0,0,DF45)';$S;
    'VSS_DF46':'(0,0,0,0,0,0,0,0,0,0,0,0,0,0,0,0,0,0,0,0,0,0,0,0,0,0,0,0,0,0,0,0~
,0,0,0,0,0,0,0,DF46)';$S;
    'VSS_DF47':'(0,0,0,0,0,0,0,0,0,0,0,0,0,0,0,0,0,0,0,0,0,0,0,0,0,0,0,0,0,0,0,0~
,0,0,0,0,0,0,0,DF47)';$S;
    'VSS_DF48':'(0,0,0,0,0,0,0,0,0,0,0,0,0,0,0,0,0,0,0,0,0,0,0,0,0,0,0,0,0,0,0,0~
,0,0,0,0,0,0,0,DF48)';$S;
    'VSS_DF49':'(0,0,0,0,0,0,0,0,0,0,0,0,0,0,0,0,0,0,0,0,0,0,0,0,0,0,0,0,0,0,0,0~
,0,0,0,0,0,0,0,DF49)';$S;
    'VSS_DF50':'(0,0,0,0,0,0,0,0,0,0,0,0,0,0,0,0,0,0,0,0,0,0,0,0,0,0,0,0,0,0,0,0~
,0,0,0,0,0,0,0,DF50)';$S;
    'VSS_DF51':'(0,0,0,0,0,0,0,0,0,0,0,0,0,0,0,0,0,0,0,0,0,0,0,0,0,0,0,0,0,0,0,0~
,0,0,0,0,0,0,0,DF51)';$S;
    'VSS_DF52':'(0,0,0,0,0,0,0,0,0,0,0,0,0,0,0,0,0,0,0,0,0,0,0,0,0,0,0,0,0,0,0,0~
,0,0,0,0,0,0,0,DF52)';$S;
    'VSS_DF56':'(0,0,0,0,0,0,0,0,0,0,0,0,0,0,0,0,0,0,0,0,0,0,0,0,0,0,0,0,0,0,0,0~
,0,0,0,0,0,0,0,DF56)';$S;
    'VSS_DF57':'(0,0,0,0,0,0,0,0,0,0,0,0,0,0,0,0,0,0,0,0,0,0,0,0,0,0,0,0,0,0,0,0~
,0,0,0,0,0,0,0,DF57)';$S;
    'VSS_DF58':'(0,0,0,0,0,0,0,0,0,0,0,0,0,0,0,0,0,0,0,0,0,0,0,0,0,0,0,0,0,0,0,0~
,0,0,0,0,0,0,0,DF58)';$S;
    'VSS_DF59':'(0,0,0,0,0,0,0,0,0,0,0,0,0,0,0,0,0,0,0,0,0,0,0,0,0,0,0,0,0,0,0,0~
,0,0,0,0,0,0,0,DF59)';$S;
    'VSS_DF61':'(0,0,0,0,0,0,0,0,0,0,0,0,0,0,0,0,0,0,0,0,0,0,0,0,0,0,0,0,0,0,0,0~
,0,0,0,0,0,0,0,DF61)';$S;
    'VSS_DF63':'(0,0,0,0,0,0,0,0,0,0,0,0,0,0,0,0,0,0,0,0,0,0,0,0,0,0,0,0,0,0,0,0~
,0,0,0,0,0,0,0,DF63)';$S;
    'VSS_DF64':'(0,0,0,0,0,0,0,0,0,0,0,0,0,0,0,0,0,0,0,0,0,0,0,0,0,0,0,0,0,0,0,0~
,0,0,0,0,0,0,0,DF64)';$S;
    'VSS_DF65':'(0,0,0,0,0,0,0,0,0,0,0,0,0,0,0,0,0,0,0,0,0,0,0,0,0,0,0,0,0,0,0,0~
,0,0,0,0,0,0,0,DF65)';$S;
    'VSS_DF71':'(0,0,0,0,0,0,0,0,0,0,0,0,0,0,0,0,0,0,0,0,0,0,0,0,0,0,0,0,0,0,0,0~
,0,0,0,0,0,0,0,DF71)';$S;
    'VSS_DF72':'(0,0,0,0,0,0,0,0,0,0,0,0,0,0,0,0,0,0,0,0,0,0,0,0,0,0,0,0,0,0,0,0~
,0,0,0,0,0,0,0,DF72)';$S;
    'VSS_DF73':'(0,0,0,0,0,0,0,0,0,0,0,0,0,0,0,0,0,0,0,0,0,0,0,0,0,0,0,0,0,0,0,0~
,0,0,0,0,0,0,0,DF73)';$S;
    'VSS_DG1':'(0,0,0,0,0,0,0,0,0,0,0,0,0,0,0,0,0,0,0,0,0,0,0,0,0,0,0,0,0,0,0,0,~
0,0,0,0,0,0,0,DG1)';$S;
    'VSS_DG2':'(0,0,0,0,0,0,0,0,0,0,0,0,0,0,0,0,0,0,0,0,0,0,0,0,0,0,0,0,0,0,0,0,~
0,0,0,0,0,0,0,DG2)';$S;
    'VSS_DG6':'(0,0,0,0,0,0,0,0,0,0,0,0,0,0,0,0,0,0,0,0,0,0,0,0,0,0,0,0,0,0,0,0,~
0,0,0,0,0,0,0,DG6)';$S;
    'VSS_DG7':'(0,0,0,0,0,0,0,0,0,0,0,0,0,0,0,0,0,0,0,0,0,0,0,0,0,0,0,0,0,0,0,0,~
0,0,0,0,0,0,0,DG7)';$S;
    'VSS_DG15':'(0,0,0,0,0,0,0,0,0,0,0,0,0,0,0,0,0,0,0,0,0,0,0,0,0,0,0,0,0,0,0,0~
,0,0,0,0,0,0,0,DG15)';$S;
    'VSS_DG16':'(0,0,0,0,0,0,0,0,0,0,0,0,0,0,0,0,0,0,0,0,0,0,0,0,0,0,0,0,0,0,0,0~
,0,0,0,0,0,0,0,DG16)';$S;
    'VSS_DG18':'(0,0,0,0,0,0,0,0,0,0,0,0,0,0,0,0,0,0,0,0,0,0,0,0,0,0,0,0,0,0,0,0~
,0,0,0,0,0,0,0,DG18)';$S;
    'VSS_DG20':'(0,0,0,0,0,0,0,0,0,0,0,0,0,0,0,0,0,0,0,0,0,0,0,0,0,0,0,0,0,0,0,0~
,0,0,0,0,0,0,0,DG20)';$S;
    'VSS_DG21':'(0,0,0,0,0,0,0,0,0,0,0,0,0,0,0,0,0,0,0,0,0,0,0,0,0,0,0,0,0,0,0,0~
,0,0,0,0,0,0,0,DG21)';$S;
    'VSS_DG24':'(0,0,0,0,0,0,0,0,0,0,0,0,0,0,0,0,0,0,0,0,0,0,0,0,0,0,0,0,0,0,0,0~
,0,0,0,0,0,0,0,DG24)';$S;
    'VSS_DG27':'(0,0,0,0,0,0,0,0,0,0,0,0,0,0,0,0,0,0,0,0,0,0,0,0,0,0,0,0,0,0,0,0~
,0,0,0,0,0,0,0,DG27)';$S;
    'VSS_DG46':'(0,0,0,0,0,0,0,0,0,0,0,0,0,0,0,0,0,0,0,0,0,0,0,0,0,0,0,0,0,0,0,0~
,0,0,0,0,0,0,0,DG46)';$S;
    'VSS_DG49':'(0,0,0,0,0,0,0,0,0,0,0,0,0,0,0,0,0,0,0,0,0,0,0,0,0,0,0,0,0,0,0,0~
,0,0,0,0,0,0,0,DG49)';$S;
    'VSS_DG52':'(0,0,0,0,0,0,0,0,0,0,0,0,0,0,0,0,0,0,0,0,0,0,0,0,0,0,0,0,0,0,0,0~
,0,0,0,0,0,0,0,DG52)';$S;
    'VSS_DG55':'(0,0,0,0,0,0,0,0,0,0,0,0,0,0,0,0,0,0,0,0,0,0,0,0,0,0,0,0,0,0,0,0~
,0,0,0,0,0,0,0,DG55)';$S;
    'VSS_DG56':'(0,0,0,0,0,0,0,0,0,0,0,0,0,0,0,0,0,0,0,0,0,0,0,0,0,0,0,0,0,0,0,0~
,0,0,0,0,0,0,0,DG56)';$S;
    'VSS_DG59':'(0,0,0,0,0,0,0,0,0,0,0,0,0,0,0,0,0,0,0,0,0,0,0,0,0,0,0,0,0,0,0,0~
,0,0,0,0,0,0,0,DG59)';$S;
    'VSS_DG60':'(0,0,0,0,0,0,0,0,0,0,0,0,0,0,0,0,0,0,0,0,0,0,0,0,0,0,0,0,0,0,0,0~
,0,0,0,0,0,0,0,DG60)';$S;
    'VSS_DG66':'(0,0,0,0,0,0,0,0,0,0,0,0,0,0,0,0,0,0,0,0,0,0,0,0,0,0,0,0,0,0,0,0~
,0,0,0,0,0,0,0,DG66)';$S;
    'VSS_DG67':'(0,0,0,0,0,0,0,0,0,0,0,0,0,0,0,0,0,0,0,0,0,0,0,0,0,0,0,0,0,0,0,0~
,0,0,0,0,0,0,0,DG67)';$S;
    'VSS_DG68':'(0,0,0,0,0,0,0,0,0,0,0,0,0,0,0,0,0,0,0,0,0,0,0,0,0,0,0,0,0,0,0,0~
,0,0,0,0,0,0,0,DG68)';$S;
    'VSS_DG69':'(0,0,0,0,0,0,0,0,0,0,0,0,0,0,0,0,0,0,0,0,0,0,0,0,0,0,0,0,0,0,0,0~
,0,0,0,0,0,0,0,DG69)';$S;
    'VSS_DG70':'(0,0,0,0,0,0,0,0,0,0,0,0,0,0,0,0,0,0,0,0,0,0,0,0,0,0,0,0,0,0,0,0~
,0,0,0,0,0,0,0,DG70)';$S;
    'VSS_DG74':'(0,0,0,0,0,0,0,0,0,0,0,0,0,0,0,0,0,0,0,0,0,0,0,0,0,0,0,0,0,0,0,0~
,0,0,0,0,0,0,0,DG74)';$S;
    'VSS_DG75':'(0,0,0,0,0,0,0,0,0,0,0,0,0,0,0,0,0,0,0,0,0,0,0,0,0,0,0,0,0,0,0,0~
,0,0,0,0,0,0,0,DG75)';$S;
    'VSS_DH39':'(0,0,0,0,0,0,0,0,0,0,0,0,0,0,0,0,0,0,0,0,0,0,0,0,0,0,0,0,0,0,0,0~
,0,0,0,0,0,0,0,DH39)';$S;
    'VSS_DH43':'(0,0,0,0,0,0,0,0,0,0,0,0,0,0,0,0,0,0,0,0,0,0,0,0,0,0,0,0,0,0,0,0~
,0,0,0,0,0,0,0,DH43)';$S;
    'VSS_DH46':'(0,0,0,0,0,0,0,0,0,0,0,0,0,0,0,0,0,0,0,0,0,0,0,0,0,0,0,0,0,0,0,0~
,0,0,0,0,0,0,0,DH46)';$S;
    'VSS_DH49':'(0,0,0,0,0,0,0,0,0,0,0,0,0,0,0,0,0,0,0,0,0,0,0,0,0,0,0,0,0,0,0,0~
,0,0,0,0,0,0,0,DH49)';$S;
    'VSS_DH52':'(0,0,0,0,0,0,0,0,0,0,0,0,0,0,0,0,0,0,0,0,0,0,0,0,0,0,0,0,0,0,0,0~
,0,0,0,0,0,0,0,DH52)';$S;
    'VSS_DH55':'(0,0,0,0,0,0,0,0,0,0,0,0,0,0,0,0,0,0,0,0,0,0,0,0,0,0,0,0,0,0,0,0~
,0,0,0,0,0,0,0,DH55)';$S;
    'VSS_DH59':'(0,0,0,0,0,0,0,0,0,0,0,0,0,0,0,0,0,0,0,0,0,0,0,0,0,0,0,0,0,0,0,0~
,0,0,0,0,0,0,0,DH59)';$S;
    'VSS_DH68':'(0,0,0,0,0,0,0,0,0,0,0,0,0,0,0,0,0,0,0,0,0,0,0,0,0,0,0,0,0,0,0,0~
,0,0,0,0,0,0,0,DH68)';$S;
    'VSS_DH70':'(0,0,0,0,0,0,0,0,0,0,0,0,0,0,0,0,0,0,0,0,0,0,0,0,0,0,0,0,0,0,0,0~
,0,0,0,0,0,0,0,DH70)';$S;
    'VSS_DJ7':'(0,0,0,0,0,0,0,0,0,0,0,0,0,0,0,0,0,0,0,0,0,0,0,0,0,0,0,0,0,0,0,0,~
0,0,0,0,0,0,0,DJ7)';$S;
    'VSS_DJ15':'(0,0,0,0,0,0,0,0,0,0,0,0,0,0,0,0,0,0,0,0,0,0,0,0,0,0,0,0,0,0,0,0~
,0,0,0,0,0,0,0,DJ15)';$S;
    'VSS_DJ19':'(0,0,0,0,0,0,0,0,0,0,0,0,0,0,0,0,0,0,0,0,0,0,0,0,0,0,0,0,0,0,0,0~
,0,0,0,0,0,0,0,DJ19)';$S;
    'VSS_DJ43':'(0,0,0,0,0,0,0,0,0,0,0,0,0,0,0,0,0,0,0,0,0,0,0,0,0,0,0,0,0,0,0,0~
,0,0,0,0,0,0,0,DJ43)';$S;
    'VSS_DJ49':'(0,0,0,0,0,0,0,0,0,0,0,0,0,0,0,0,0,0,0,0,0,0,0,0,0,0,0,0,0,0,0,0~
,0,0,0,0,0,0,0,DJ49)';$S;
    'VSS_DJ59':'(0,0,0,0,0,0,0,0,0,0,0,0,0,0,0,0,0,0,0,0,0,0,0,0,0,0,0,0,0,0,0,0~
,0,0,0,0,0,0,0,DJ59)';$S;
    'VSS_DJ61':'(0,0,0,0,0,0,0,0,0,0,0,0,0,0,0,0,0,0,0,0,0,0,0,0,0,0,0,0,0,0,0,0~
,0,0,0,0,0,0,0,DJ61)';$S;
    'VSS_DJ63':'(0,0,0,0,0,0,0,0,0,0,0,0,0,0,0,0,0,0,0,0,0,0,0,0,0,0,0,0,0,0,0,0~
,0,0,0,0,0,0,0,DJ63)';$S;
    'VSS_DJ66':'(0,0,0,0,0,0,0,0,0,0,0,0,0,0,0,0,0,0,0,0,0,0,0,0,0,0,0,0,0,0,0,0~
,0,0,0,0,0,0,0,DJ66)';$S;
    'VSS_DJ68':'(0,0,0,0,0,0,0,0,0,0,0,0,0,0,0,0,0,0,0,0,0,0,0,0,0,0,0,0,0,0,0,0~
,0,0,0,0,0,0,0,DJ68)';$S;
    'VSS_DJ73':'(0,0,0,0,0,0,0,0,0,0,0,0,0,0,0,0,0,0,0,0,0,0,0,0,0,0,0,0,0,0,0,0~
,0,0,0,0,0,0,0,DJ73)';$S;
    'VSS_CY57':'(0,0,0,0,0,0,0,0,0,0,0,0,0,0,0,0,0,0,0,0,0,0,0,0,0,0,0,0,0,0,0,0~
,0,0,0,0,0,0,0,CY57)';$S;
    'VSS_CK31':'(0,0,0,0,0,0,0,0,0,0,0,0,0,0,0,0,0,0,0,0,0,0,0,0,0,0,0,0,0,0,0,0~
,0,0,0,0,0,0,0,CK31)';$S;
    'VSS_CB44':'(0,0,0,0,0,0,0,0,0,0,0,0,0,0,0,0,0,0,0,0,0,0,0,0,0,0,0,0,0,0,0,0~
,0,0,0,0,0,0,0,CB44)';$S;
    'VSS_AM37':'(0,0,0,0,0,0,0,0,0,0,0,0,0,0,0,0,0,0,0,0,0,0,0,0,0,0,0,0,0,0,0,0~
,0,0,0,0,0,0,0,AM37)';$S;
    'VSS_K23':'(0,0,0,0,0,0,0,0,0,0,0,0,0,0,0,0,0,0,0,0,0,0,0,0,0,0,0,0,0,0,0,0,~
0,0,0,0,0,0,0,K23)';$S;
    'VSS_CN54':'(0,0,0,0,0,0,0,0,0,0,0,0,0,0,0,0,0,0,0,0,0,0,0,0,0,0,0,0,0,0,0,0~
,0,0,0,0,0,0,0,CN54)';$S;
    'VSS_CK10':'(0,0,0,0,0,0,0,0,0,0,0,0,0,0,0,0,0,0,0,0,0,0,0,0,0,0,0,0,0,0,0,0~
,0,0,0,0,0,0,0,CK10)';$S;
    'VSS_AA72':'(0,0,0,0,0,0,0,0,0,0,0,0,0,0,0,0,0,0,0,0,0,0,0,0,0,0,0,0,0,0,0,0~
,0,0,0,0,0,0,0,AA72)';$S;
    'VSS_AJ13':'(0,0,0,0,0,0,0,0,0,0,0,0,0,0,0,0,0,0,0,0,0,0,0,0,0,0,0,0,0,0,0,0~
,0,0,0,0,0,0,0,AJ13)';$S;
    'VSS_AD31':'(0,0,0,0,0,0,0,0,0,0,0,0,0,0,0,0,0,0,0,0,0,0,0,0,0,0,0,0,0,0,0,0~
,0,0,0,0,0,0,0,AD31)';$S;
    'VSS_AA42':'(0,0,0,0,0,0,0,0,0,0,0,0,0,0,0,0,0,0,0,0,0,0,0,0,0,0,0,0,0,0,0,0~
,0,0,0,0,0,0,0,AA42)';$S;
    'VSS_V27':'(0,0,0,0,0,0,0,0,0,0,0,0,0,0,0,0,0,0,0,0,0,0,0,0,0,0,0,0,0,0,0,0,~
0,0,0,0,0,0,0,V27)';$S;
    'VSS_CF46':'(0,0,0,0,0,0,0,0,0,0,0,0,0,0,0,0,0,0,0,0,0,0,0,0,0,0,0,0,0,0,0,0~
,0,0,0,0,0,0,0,CF46)';$S;
    'VSS_CC22':'(0,0,0,0,0,0,0,0,0,0,0,0,0,0,0,0,0,0,0,0,0,0,0,0,0,0,0,0,0,0,0,0~
,0,0,0,0,0,0,0,CC22)';$S;
    'VSS_AN20':'(0,0,0,0,0,0,0,0,0,0,0,0,0,0,0,0,0,0,0,0,0,0,0,0,0,0,0,0,0,0,0,0~
,0,0,0,0,0,0,0,AN20)';$S;
    'VSS_P68':'(0,0,0,0,0,0,0,0,0,0,0,0,0,0,0,0,0,0,0,0,0,0,0,0,0,0,0,0,0,0,0,0,~
0,0,0,0,0,0,0,P68)';$S;
    'VSS_P25':'(0,0,0,0,0,0,0,0,0,0,0,0,0,0,0,0,0,0,0,0,0,0,0,0,0,0,0,0,0,0,0,0,~
0,0,0,0,0,0,0,P25)';$S;
    'VSS_CU58':'(0,0,0,0,0,0,0,0,0,0,0,0,0,0,0,0,0,0,0,0,0,0,0,0,0,0,0,0,0,0,0,0~
,0,0,0,0,0,0,0,CU58)';$S;
    'VSS_BW25':'(0,0,0,0,0,0,0,0,0,0,0,0,0,0,0,0,0,0,0,0,0,0,0,0,0,0,0,0,0,0,0,0~
,0,0,0,0,0,0,0,BW25)';$S;
    'VSS_AH33':'(0,0,0,0,0,0,0,0,0,0,0,0,0,0,0,0,0,0,0,0,0,0,0,0,0,0,0,0,0,0,0,0~
,0,0,0,0,0,0,0,AH33)';$S;
    'VSS_AE4':'(0,0,0,0,0,0,0,0,0,0,0,0,0,0,0,0,0,0,0,0,0,0,0,0,0,0,0,0,0,0,0,0,~
0,0,0,0,0,0,0,AE4)';$S;
    'VSS_CG42':'(0,0,0,0,0,0,0,0,0,0,0,0,0,0,0,0,0,0,0,0,0,0,0,0,0,0,0,0,0,0,0,0~
,0,0,0,0,0,0,0,CG42)';$S;
    'VSS_DA56':'(0,0,0,0,0,0,0,0,0,0,0,0,0,0,0,0,0,0,0,0,0,0,0,0,0,0,0,0,0,0,0,0~
,0,0,0,0,0,0,0,DA56)';$S;
    'VSS_K59':'(0,0,0,0,0,0,0,0,0,0,0,0,0,0,0,0,0,0,0,0,0,0,0,0,0,0,0,0,0,0,0,0,~
0,0,0,0,0,0,0,K59)';$S;
    'VSS_CM50':'(0,0,0,0,0,0,0,0,0,0,0,0,0,0,0,0,0,0,0,0,0,0,0,0,0,0,0,0,0,0,0,0~
,0,0,0,0,0,0,0,CM50)';$S;
    'VSS_CT52':'(0,0,0,0,0,0,0,0,0,0,0,0,0,0,0,0,0,0,0,0,0,0,0,0,0,0,0,0,0,0,0,0~
,0,0,0,0,0,0,0,CT52)';$S;
    'VSS_BV42':'(0,0,0,0,0,0,0,0,0,0,0,0,0,0,0,0,0,0,0,0,0,0,0,0,0,0,0,0,0,0,0,0~
,0,0,0,0,0,0,0,BV42)';$S;
    'VSS_V68':'(0,0,0,0,0,0,0,0,0,0,0,0,0,0,0,0,0,0,0,0,0,0,0,0,0,0,0,0,0,0,0,0,~
0,0,0,0,0,0,0,V68)';$S;
end_primitive;
primitive 'GL852GOHY60-GL852G-OHY60,SMLF,IC,AL000852001';body 'GL852GOHY60';
    'X1':'(10)';IN;
    'X2':'(11)';OUT;
    'TEST||SCL':'(18)';BIDI;
    'SDA':'(26)';BIDI;
    'V5':'(27)';
    'V33':'(28)';
    'AVDD'<0>:'(5)';
    'AVDD'<1>:'(9)';
    'AVDD'<2>:'(14)';
    'DVDD':'(21)';
    'TH':'(TH)';
    'OVCUR1#||SMC':'(25)';IN;
    'OVCUR2#||SMD':'(24)';BIDI;
    'OVCUR3#':'(20)';IN;
    'OVCUR4#':'(19)';IN;
    'RESET#':'(17)';IN;
    'PGANG':'(23)';BIDI;
    'PSELF':'(22)';IN;
    'RREF':'(8)';IN;
    'DP0':'(2)';BIDI;
    'DM0':'(1)';BIDI;
    'DP1':'(4)';BIDI;
    'DM1':'(3)';BIDI;
    'DP2':'(7)';BIDI;
    'DM2':'(6)';BIDI;
    'DP3':'(13)';BIDI;
    'DM3':'(12)';BIDI;
    'DP4':'(16)';BIDI;
    'DM4':'(15)';BIDI;
end_primitive;
primitive 'GND_HOLE_TH-EMPTY,GND_HOLE140';body 'GND_HOLE';
    'GND3':'(3)';
    'GND2':'(2)';
    'GND9':'(9)';
    'GND8':'(8)';
    'GND7':'(7)';
    'GND6':'(6)';
    'GND5':'(5)';
    'GND4':'(4)';
end_primitive;
primitive 'GND_HOLE_TH-EMPTY,GND_HOLE514';body 'GND_HOLE';
    'GND3':'(3)';
    'GND2':'(2)';
    'GND9':'(9)';
    'GND8':'(8)';
    'GND7':'(7)';
    'GND6':'(6)';
    'GND5':'(5)';
    'GND4':'(4)';
end_primitive;
primitive 'GND_HOLE_TH-EMPTY,TMP-QGND_HOLE12';body 'GND_HOLE';
    'GND3':'(3)';
    'GND2':'(2)';
    'GND9':'(9)';
    'GND8':'(8)';
    'GND7':'(7)';
    'GND6':'(6)';
    'GND5':'(5)';
    'GND4':'(4)';
end_primitive;
primitive 'HOLE_TH-EMPTY,DUMMY50';body 'HOLE';
    '1':'(1)';BIDI;
end_primitive;
primitive 'HOLE_TH-EMPTY,HOLE1187';body 'HOLE';
    '1':'(1)';BIDI;
end_primitive;
primitive 'HOLE_TH-EMPTY,HOLE1195';body 'HOLE';
    '1':'(1)';BIDI;
end_primitive;
primitive 'HOLE_TH-EMPTY,HOLE1226';body 'HOLE';
    '1':'(1)';BIDI;
end_primitive;
primitive 'HOLE_TH-EMPTY,HOLE1247';body 'HOLE';
    '1':'(1)';BIDI;
end_primitive;
primitive 'HOLE_TH-EMPTY,HOLE1248';body 'HOLE';
    '1':'(1)';BIDI;
end_primitive;
primitive 'HOLE_TH-EMPTY,HOLE372';body 'HOLE';
    '1':'(1)';BIDI;
end_primitive;
primitive 'HOLE_TH-EMPTY,HOLE596';body 'HOLE';
    '1':'(1)';BIDI;
end_primitive;
primitive 'HOLE_TH-EMPTY,TMP-C_T2I_ALEX_1121_1';body 'HOLE';
    '1':'(1)';BIDI;
end_primitive;
primitive 'IML3112Y2B000NCG8-IML3112-Y2B000NCG8,SMLF,EMPTY,ALA';body 'IML3112Y2B000NCG8';
    'HSDA':'(2)';BIDI;
    'VDD':'(5)';
    'LSCL_1':'(6)';OUT;
    'VIO':'(7)';
    'LSDA_0':'(1)';BIDI;
    'LSCL_0':'(4)';OUT;
    'HSCL':'(3)';IN;
    'LSDA_1||HSA':'(8)';BIDI;
    'TH_GND':'(9)';
end_primitive;
primitive 'ISL28022FRZT-ISL28022FRZ-T,SMLF,IC,AL028022003';body 'ISL28022FRZT';
    'VCC':'(9)';
    'A1':'(1)';IN;
    'A0':'(2)';IN;
    'SCL|||SMBCLK':'(5)';IN;
    'SDA||SMBDAT':'(4)';BIDI;
    'VBUS':'(11)';
    'VINP':'(13)';IN;
    'VINM':'(12)';IN;
    'EXT_CLK||INT':'(3)';BIDI;
    'NC0':'(6)';OUT;
    'NC1':'(7)';OUT;
    'NC2':'(8)';OUT;
    'NC3':'(14)';OUT;
    'NC4':'(15)';OUT;
    'NC5':'(16)';OUT;
    'GND':'(10)';
    'TH_GND':'(TH)';
end_primitive;
primitive 'ISL69260IRAZT-ISL69260IRAZ-T,SMLF,IC,AL069260000';body 'ISL69260IRAZT';
    'CS7':'(23)';IN;
    'VCC':'(39)';
    'EN1':'(20)';IN;
    'PMSCL':'(10)';IN;
    'SVDATA':'(18)';BIDI;
    'CS6':'(24)';IN;
    'NSVALERT#':'(19)';OUT;
    'NVRHOT#':'(14)';OUT;
    'CS5':'(25)';IN;
    'CS4':'(26)';IN;
    'PG1':'(16)';OUT;
    'SVCLK':'(17)';IN;
    'NPMALERT#':'(11)';OUT;
    'EN0':'(13)';IN;
    'RGND0':'(22)';IN;
    'PMSDA':'(9)';BIDI;
    'PWM4':'(5)';OUT;
    'PWM5':'(6)';OUT;
    'VSEN0':'(21)';IN;
    'PWM1':'(2)';OUT;
    'PG0':'(12)';OUT;
    'PWM6':'(7)';OUT;
    'VCCS':'(40)';
    'VMON||IINSEN||VSYS||ISYS':'(37)';IN;
    'VINSEN||VSYS':'(38)';IN;
    'TEMP1||ISYS':'(36)';IN;
    'NPINALERT#||NPSYSCRIT#':'(15)';OUT;
    'VSEN1':'(32)';IN;
    'RGND1':'(31)';IN;
    'CS1':'(29)';IN;
    'PWM7':'(8)';OUT;
    'PWM3':'(4)';OUT;
    'CS3':'(27)';IN;
    'PWM2':'(3)';OUT;
    'CS2':'(28)';IN;
    'CFP':'(33)';OUT;
    'TH_GND':'(TH)';
    'ADDR_CFG':'(34)';IN;
    'TEMP0':'(35)';IN;
    'PWM0':'(1)';OUT;
    'CS0':'(30)';IN;
end_primitive;
primitive 'ISL99390FRZTR5935-ISL99390FRZ-TR5935,SMLF,IC,AL099A';body 'ISL99390FRZTR5935';
    'PWM':'(34)';IN;
    'REFIN':'(39)';IN;
    'VCC':'(3)';
    'AGND':'(2)';
    'BOOT':'(33)';
    'VIN1':'(25_29)';IN;
    'PHASE':'(32)';
    'PVCC':'(4)';
    'TOUT_FLT':'(36)';OUT;
    'IOUT':'(38)';OUT;
    'LSET':'(37)';OUT;
    'SW':'(10_19)';OUT;
    'PGND1':'(5)';
    'VIN2':'(30)';IN;
    'VOS':'(1)';IN;
    'PGND3':'(40)';
    'EN':'(35)';IN;
    'DNC':'(31)';OUT;
    'GL1':'(6)';OUT;
    'GL2':'(41)';OUT;
    'PGND2':'(7_9-20_24)';
end_primitive;
primitive 'LCMXO3LF9400C5BG484C-LCMXO3LF-9400C-5BG484C,SMLF,IA';body 'LCMXO3LF9400C5BG484C';
    'PL2A':'(D3,0,0,0,0,0,0)';$S;BIDI;
    'PL2B':'(D4,0,0,0,0,0,0)';$S;BIDI;
    'PL2C':'(F6,0,0,0,0,0,0)';$S;BIDI;
    'PL2D':'(G7,0,0,0,0,0,0)';$S;BIDI;
    'PL3A||L_GPLLT_FB':'(E4,0,0,0,0,0,0)';$S;BIDI;
    'PL3B||L_GPLLC_FB':'(F5,0,0,0,0,0,0)';$S;BIDI;
    'PL3C':'(G6,0,0,0,0,0,0)';$S;BIDI;
    'PL3D':'(H7,0,0,0,0,0,0)';$S;BIDI;
    'PL4A||L_GPLLT_IN':'(C1,0,0,0,0,0,0)';$S;BIDI;
    'PL4B||L_GPLLC_IN':'(D2,0,0,0,0,0,0)';$S;BIDI;
    'PL4C':'(G5,0,0,0,0,0,0)';$S;BIDI;
    'PL4D':'(H6,0,0,0,0,0,0)';$S;BIDI;
    'PL5A':'(D1,0,0,0,0,0,0)';$S;BIDI;
    'PL5B':'(E2,0,0,0,0,0,0)';$S;BIDI;
    'PL5C':'(E3,0,0,0,0,0,0)';$S;BIDI;
    'PL5D':'(F4,0,0,0,0,0,0)';$S;BIDI;
    'PL13A':'(L7,0,0,0,0,0,0)';$S;BIDI;
    'PL13B':'(K5,0,0,0,0,0,0)';$S;BIDI;
    'PL13C':'(K4,0,0,0,0,0,0)';$S;BIDI;
    'PL13D':'(K3,0,0,0,0,0,0)';$S;BIDI;
    'PL14A':'(K2,0,0,0,0,0,0)';$S;BIDI;
    'PL14B':'(K1,0,0,0,0,0,0)';$S;BIDI;
    'PL16A||PCLKT4_0':'(L1,0,0,0,0,0,0)';$S;BIDI;
    'PL16B||PCLKC4_0':'(M2,0,0,0,0,0,0)';$S;BIDI;
    'PL20A':'(P4,0,0,0,0,0,0)';$S;BIDI;
    'PL20B':'(N5,0,0,0,0,0,0)';$S;BIDI;
    'PL20C':'(N6,0,0,0,0,0,0)';$S;BIDI;
    'PL20D':'(N7,0,0,0,0,0,0)';$S;BIDI;
    'PL21A':'(R2,0,0,0,0,0,0)';$S;BIDI;
    'PL21B':'(T1,0,0,0,0,0,0)';$S;BIDI;
    'PL21C':'(P5,0,0,0,0,0,0)';$S;BIDI;
    'PL21D':'(P6,0,0,0,0,0,0)';$S;BIDI;
    'PL26C':'(T5,0,0,0,0,0,0)';$S;BIDI;
    'PL26D':'(T6,0,0,0,0,0,0)';$S;BIDI;
    'PL14C':'(L6,0,0,0,0,0,0)';$S;BIDI;
    'PL14D':'(L5,0,0,0,0,0,0)';$S;BIDI;
    'PL16C':'(L3,0,0,0,0,0,0)';$S;BIDI;
    'PL16D':'(L4,0,0,0,0,0,0)';$S;BIDI;
    'PL6C':'(G3,0,0,0,0,0,0)';$S;BIDI;
    'PL6D':'(G4,0,0,0,0,0,0)';$S;BIDI;
    'PL6A':'(E1,0,0,0,0,0,0)';$S;BIDI;
    'PL6B':'(F1,0,0,0,0,0,0)';$S;BIDI;
    'PL25A':'(T2,0,0,0,0,0,0)';$S;BIDI;
    'PL25B':'(U1,0,0,0,0,0,0)';$S;BIDI;
    'PL24A':'(R3,0,0,0,0,0,0)';$S;BIDI;
    'PL24B':'(R4,0,0,0,0,0,0)';$S;BIDI;
    'PL24C':'(R5,0,0,0,0,0,0)';$S;BIDI;
    'PL24D':'(P7,0,0,0,0,0,0)';$S;BIDI;
    'PL25C':'(R6,0,0,0,0,0,0)';$S;BIDI;
    'PL25D':'(R7,0,0,0,0,0,0)';$S;BIDI;
    'PL26A':'(T3,0,0,0,0,0,0)';$S;BIDI;
    'PL26B':'(T4,0,0,0,0,0,0)';$S;BIDI;
    'PL17A':'(M1,0,0,0,0,0,0)';$S;BIDI;
    'PL17B':'(N1,0,0,0,0,0,0)';$S;BIDI;
    'PL17C':'(M6,0,0,0,0,0,0)';$S;BIDI;
    'PL17D':'(M5,0,0,0,0,0,0)';$S;BIDI;
    'PL18A':'(N2,0,0,0,0,0,0)';$S;BIDI;
    'PL18B':'(P1,0,0,0,0,0,0)';$S;BIDI;
    'PL18C':'(N3,0,0,0,0,0,0)';$S;BIDI;
    'PL18D':'(N4,0,0,0,0,0,0)';$S;BIDI;
    'PL19A':'(P2,0,0,0,0,0,0)';$S;BIDI;
    'PL19B':'(R1,0,0,0,0,0,0)';$S;BIDI;
    'PL19C':'(P3,0,0,0,0,0,0)';$S;BIDI;
    'PL19D':'(M7,0,0,0,0,0,0)';$S;BIDI;
    'PL27A||PCLKT3_0':'(U2,0,0,0,0,0,0)';$S;BIDI;
    'PL27B||PCLKC3_0':'(V1,0,0,0,0,0,0)';$S;BIDI;
    'PL27C':'(U3,0,0,0,0,0,0)';$S;BIDI;
    'PL27D':'(U4,0,0,0,0,0,0)';$S;BIDI;
    'PL28A':'(W1,0,0,0,0,0,0)';$S;BIDI;
    'PL28B':'(W2,0,0,0,0,0,0)';$S;BIDI;
    'PL28C':'(V4,0,0,0,0,0,0)';$S;BIDI;
    'PL28D':'(U5,0,0,0,0,0,0)';$S;BIDI;
    'PL29A':'(Y1,0,0,0,0,0,0)';$S;BIDI;
    'PL29B':'(AA1,0,0,0,0,0,0)';$S;BIDI;
    'PL29C':'(W3,0,0,0,0,0,0)';$S;BIDI;
    'PL29D':'(Y2,0,0,0,0,0,0)';$S;BIDI;
    'PL30A':'(Y3,0,0,0,0,0,0)';$S;BIDI;
    'PL30B':'(W4,0,0,0,0,0,0)';$S;BIDI;
    'PL30C':'(V5,0,0,0,0,0,0)';$S;BIDI;
    'PL30D':'(T7,0,0,0,0,0,0)';$S;BIDI;
    'PL7A||PCLKT5_0':'(G2,0,0,0,0,0,0)';$S;BIDI;
    'PL7B||PCLKC5_0':'(G1,0,0,0,0,0,0)';$S;BIDI;
    'PL7C':'(H4,0,0,0,0,0,0)';$S;BIDI;
    'PL7D':'(H3,0,0,0,0,0,0)';$S;BIDI;
    'PL10A':'(H2,0,0,0,0,0,0)';$S;BIDI;
    'PL10B':'(H1,0,0,0,0,0,0)';$S;BIDI;
    'PL10C':'(J7,0,0,0,0,0,0)';$S;BIDI;
    'PL10D':'(J6,0,0,0,0,0,0)';$S;BIDI;
    'PL11A':'(H5,0,0,0,0,0,0)';$S;BIDI;
    'PL11B':'(J5,0,0,0,0,0,0)';$S;BIDI;
    'PL11C':'(J4,0,0,0,0,0,0)';$S;BIDI;
    'PL11D':'(J3,0,0,0,0,0,0)';$S;BIDI;
    'PL12A':'(J2,0,0,0,0,0,0)';$S;BIDI;
    'PL12B':'(J1,0,0,0,0,0,0)';$S;BIDI;
    'PL12C':'(K7,0,0,0,0,0,0)';$S;BIDI;
    'PL12D':'(K6,0,0,0,0,0,0)';$S;BIDI;
    'PB5A':'(0,AA2,0,0,0,0,0)';$S;BIDI;
    'PB5B':'(0,AB2,0,0,0,0,0)';$S;BIDI;
    'PB5C':'(0,V6,0,0,0,0,0)';$S;BIDI;
    'PB5D':'(0,U6,0,0,0,0,0)';$S;BIDI;
    'PB7A||CSSPIN':'(0,AA3,0,0,0,0,0)';$S;BIDI;
    'PB7B':'(0,AB3,0,0,0,0,0)';$S;BIDI;
    'PB7C':'(0,Y4,0,0,0,0,0)';$S;BIDI;
    'PB7D':'(0,W5,0,0,0,0,0)';$S;BIDI;
    'PB8C':'(0,U7,0,0,0,0,0)';$S;BIDI;
    'PB8D':'(0,T8,0,0,0,0,0)';$S;BIDI;
    'PB8A':'(0,AA4,0,0,0,0,0)';$S;BIDI;
    'PB8B':'(0,AB4,0,0,0,0,0)';$S;BIDI;
    'PB10A':'(0,AA5,0,0,0,0,0)';$S;BIDI;
    'PB10B':'(0,AB5,0,0,0,0,0)';$S;BIDI;
    'PB10C':'(0,Y5,0,0,0,0,0)';$S;BIDI;
    'PB10D':'(0,Y6,0,0,0,0,0)';$S;BIDI;
    'PB13C':'(0,V8,0,0,0,0,0)';$S;BIDI;
    'PB13D':'(0,U8,0,0,0,0,0)';$S;BIDI;
    'PB16A||MCLK||CCLK':'(0,T9,0,0,0,0,0)';$S;BIDI;
    'PB16B||SO||SPISO':'(0,U9,0,0,0,0,0)';$S;BIDI;
    'PB18A':'(0,AA8,0,0,0,0,0)';$S;BIDI;
    'PB18B':'(0,AB8,0,0,0,0,0)';$S;BIDI;
    'PB21A':'(0,V10,0,0,0,0,0)';$S;BIDI;
    'PB21B':'(0,W10,0,0,0,0,0)';$S;BIDI;
    'PB22A||PCLKT2_0':'(0,AA10,0,0,0,0,0)';$S;BIDI;
    'PB22B||PCLKC2_0':'(0,AB10,0,0,0,0,0)';$S;BIDI;
    'PB24A':'(0,AA11,0,0,0,0,0)';$S;BIDI;
    'PB24B':'(0,AB11,0,0,0,0,0)';$S;BIDI;
    'PB24C':'(0,V11,0,0,0,0,0)';$S;BIDI;
    'PB24D':'(0,Y11,0,0,0,0,0)';$S;BIDI;
    'PB29A||PCLKT2_1':'(0,AB12,0,0,0,0,0)';$S;BIDI;
    'PB29B||PCLKC2_1':'(0,AA12,0,0,0,0,0)';$S;BIDI;
    'PB30A':'(0,AB13,0,0,0,0,0)';$S;BIDI;
    'PB30B':'(0,AA13,0,0,0,0,0)';$S;BIDI;
    'PB33A':'(0,AB14,0,0,0,0,0)';$S;BIDI;
    'PB33B':'(0,AA14,0,0,0,0,0)';$S;BIDI;
    'PB43A':'(0,AB19,0,0,0,0,0)';$S;BIDI;
    'PB43B':'(0,AA19,0,0,0,0,0)';$S;BIDI;
    'PB44A':'(0,AB20,0,0,0,0,0)';$S;BIDI;
    'PB44B':'(0,AA20,0,0,0,0,0)';$S;BIDI;
    'PB46A||SN':'(0,AB21,0,0,0,0,0)';$S;BIDI;
    'PB46B||SI||SISPI':'(0,AA21,0,0,0,0,0)';$S;BIDI;
    'PB35A':'(0,AB15,0,0,0,0,0)';$S;BIDI;
    'PB35B':'(0,AA15,0,0,0,0,0)';$S;BIDI;
    'PB11A':'(0,AA6,0,0,0,0,0)';$S;BIDI;
    'PB11B':'(0,AB6,0,0,0,0,0)';$S;BIDI;
    'PB11C':'(0,W6,0,0,0,0,0)';$S;BIDI;
    'PB11D':'(0,V7,0,0,0,0,0)';$S;BIDI;
    'PB13A':'(0,AA7,0,0,0,0,0)';$S;BIDI;
    'PB13B':'(0,AB7,0,0,0,0,0)';$S;BIDI;
    'PB16C':'(0,V9,0,0,0,0,0)';$S;BIDI;
    'PB16D':'(0,W8,0,0,0,0,0)';$S;BIDI;
    'PB18C':'(0,Y8,0,0,0,0,0)';$S;BIDI;
    'PB18D':'(0,W9,0,0,0,0,0)';$S;BIDI;
    'PB19A':'(0,AA9,0,0,0,0,0)';$S;BIDI;
    'PB19B':'(0,AB9,0,0,0,0,0)';$S;BIDI;
    'PB19C':'(0,T10,0,0,0,0,0)';$S;BIDI;
    'PB19D':'(0,U10,0,0,0,0,0)';$S;BIDI;
    'PB22C':'(0,T11,0,0,0,0,0)';$S;BIDI;
    'PB22D':'(0,U11,0,0,0,0,0)';$S;BIDI;
    'PB27A':'(0,Y12,0,0,0,0,0)';$S;BIDI;
    'PB27B':'(0,T12,0,0,0,0,0)';$S;BIDI;
    'PB27C':'(0,U12,0,0,0,0,0)';$S;BIDI;
    'PB27D':'(0,V12,0,0,0,0,0)';$S;BIDI;
    'PB29C':'(0,V13,0,0,0,0,0)';$S;BIDI;
    'PB29D':'(0,U13,0,0,0,0,0)';$S;BIDI;
    'PB30C':'(0,Y13,0,0,0,0,0)';$S;BIDI;
    'PB30D':'(0,W13,0,0,0,0,0)';$S;BIDI;
    'PB33C':'(0,Y14,0,0,0,0,0)';$S;BIDI;
    'PB33D':'(0,W14,0,0,0,0,0)';$S;BIDI;
    'PB32A':'(0,T13,0,0,0,0,0)';$S;BIDI;
    'PB32B':'(0,T14,0,0,0,0,0)';$S;BIDI;
    'PB32C':'(0,U14,0,0,0,0,0)';$S;BIDI;
    'PB32D':'(0,V14,0,0,0,0,0)';$S;BIDI;
    'PB35C':'(0,Y15,0,0,0,0,0)';$S;BIDI;
    'PB35D':'(0,W15,0,0,0,0,0)';$S;BIDI;
    'PB38A':'(0,AB16,0,0,0,0,0)';$S;BIDI;
    'PB38B':'(0,AA16,0,0,0,0,0)';$S;BIDI;
    'PB38C':'(0,V15,0,0,0,0,0)';$S;BIDI;
    'PB38D':'(0,U15,0,0,0,0,0)';$S;BIDI;
    'PB40A':'(0,AB17,0,0,0,0,0)';$S;BIDI;
    'PB40B':'(0,AA17,0,0,0,0,0)';$S;BIDI;
    'PB40C':'(0,Y17,0,0,0,0,0)';$S;BIDI;
    'PB40D':'(0,V16,0,0,0,0,0)';$S;BIDI;
    'PB41A':'(0,AB18,0,0,0,0,0)';$S;BIDI;
    'PB41B':'(0,AA18,0,0,0,0,0)';$S;BIDI;
    'PB41C':'(0,Y18,0,0,0,0,0)';$S;BIDI;
    'PB41D':'(0,W17,0,0,0,0,0)';$S;BIDI;
    'PB43C':'(0,T15,0,0,0,0,0)';$S;BIDI;
    'PB43D':'(0,U16,0,0,0,0,0)';$S;BIDI;
    'PB44C':'(0,Y19,0,0,0,0,0)';$S;BIDI;
    'PB44D':'(0,W18,0,0,0,0,0)';$S;BIDI;
    'PB46C':'(0,V17,0,0,0,0,0)';$S;BIDI;
    'PB46D':'(0,T16,0,0,0,0,0)';$S;BIDI;
    'PB21C':'(0,Y9,0,0,0,0,0)';$S;BIDI;
    'PB21D':'(0,Y10,0,0,0,0,0)';$S;BIDI;
    'PT43B||R_GPLLC':'(0,0,B21,0,0,0,0)';$S;BIDI;
    'PT43A||R_GPLLT':'(0,0,A20,0,0,0,0)';$S;BIDI;
    'PT41B':'(0,0,B19,0,0,0,0)';$S;BIDI;
    'PT41A':'(0,0,A18,0,0,0,0)';$S;BIDI;
    'PT31B':'(0,0,F14,0,0,0,0)';$S;BIDI;
    'PT31A':'(0,0,G14,0,0,0,0)';$S;BIDI;
    'PT28B':'(0,0,F12,0,0,0,0)';$S;BIDI;
    'PT28A':'(0,0,G12,0,0,0,0)';$S;BIDI;
    'PT27D||SDA||PCLKC0_0':'(0,0,A12,0,0,0,0)';$S;BIDI;
    'PT27C||SCL||PCLKT0_0':'(0,0,B12,0,0,0,0)';$S;BIDI;
    'PT44B||R_GPLLC':'(0,0,B22,0,0,0,0)';$S;BIDI;
    'PT44A||R_GPLLT':'(0,0,A21,0,0,0,0)';$S;BIDI;
    'PT23B||PCLKC0_1':'(0,0,A10,0,0,0,0)';$S;BIDI;
    'PT23A||PCLKT0_1':'(0,0,B10,0,0,0,0)';$S;BIDI;
    'PT15B':'(0,0,D8,0,0,0,0)';$S;BIDI;
    'PT9D':'(0,0,F7,0,0,0,0)';$S;BIDI;
    'PT9B||L_GPLLC':'(0,0,A2,0,0,0,0)';$S;BIDI;
    'PT9C':'(0,0,E6,0,0,0,0)';$S;BIDI;
    'PT9A||L_GPLLT':'(0,0,B1,0,0,0,0)';$S;BIDI;
    'PT15A':'(0,0,C8,0,0,0,0)';$S;BIDI;
    'PT11A':'(0,0,B3,0,0,0,0)';$S;BIDI;
    'PT11B':'(0,0,A4,0,0,0,0)';$S;BIDI;
    'PT22A':'(0,0,F10,0,0,0,0)';$S;BIDI;
    'PT22B':'(0,0,E10,0,0,0,0)';$S;BIDI;
    'PT11C':'(0,0,F8,0,0,0,0)';$S;BIDI;
    'PT11D':'(0,0,G8,0,0,0,0)';$S;BIDI;
    'PT10A':'(0,0,B2,0,0,0,0)';$S;BIDI;
    'PT10B':'(0,0,A3,0,0,0,0)';$S;BIDI;
    'PT10C':'(0,0,C3,0,0,0,0)';$S;BIDI;
    'PT10D':'(0,0,C4,0,0,0,0)';$S;BIDI;
    'PT12A':'(0,0,B4,0,0,0,0)';$S;BIDI;
    'PT12B':'(0,0,A5,0,0,0,0)';$S;BIDI;
    'PT12C':'(0,0,D5,0,0,0,0)';$S;BIDI;
    'PT12D':'(0,0,C5,0,0,0,0)';$S;BIDI;
    'PT13A':'(0,0,B5,0,0,0,0)';$S;BIDI;
    'PT13B':'(0,0,A6,0,0,0,0)';$S;BIDI;
    'PT13C':'(0,0,D6,0,0,0,0)';$S;BIDI;
    'PT13D':'(0,0,E7,0,0,0,0)';$S;BIDI;
    'PT14A':'(0,0,B6,0,0,0,0)';$S;BIDI;
    'PT14B':'(0,0,A7,0,0,0,0)';$S;BIDI;
    'PT14C':'(0,0,C6,0,0,0,0)';$S;BIDI;
    'PT14D':'(0,0,D7,0,0,0,0)';$S;BIDI;
    'PT20A':'(0,0,B8,0,0,0,0)';$S;BIDI;
    'PT20B':'(0,0,A8,0,0,0,0)';$S;BIDI;
    'PT20C':'(0,0,C9,0,0,0,0)';$S;BIDI;
    'PT20D':'(0,0,D9,0,0,0,0)';$S;BIDI;
    'PT21A':'(0,0,B9,0,0,0,0)';$S;BIDI;
    'PT21B':'(0,0,A9,0,0,0,0)';$S;BIDI;
    'PT21C':'(0,0,F9,0,0,0,0)';$S;BIDI;
    'PT21D':'(0,0,G9,0,0,0,0)';$S;BIDI;
    'PT23C':'(0,0,G11,0,0,0,0)';$S;BIDI;
    'PT23D':'(0,0,F11,0,0,0,0)';$S;BIDI;
    'PT24A':'(0,0,B11,0,0,0,0)';$S;BIDI;
    'PT24B':'(0,0,A11,0,0,0,0)';$S;BIDI;
    'PT24C':'(0,0,E11,0,0,0,0)';$S;BIDI;
    'PT24D':'(0,0,D11,0,0,0,0)';$S;BIDI;
    'PT27A':'(0,0,D12,0,0,0,0)';$S;BIDI;
    'PT27B':'(0,0,E12,0,0,0,0)';$S;BIDI;
    'PT28C':'(0,0,E13,0,0,0,0)';$S;BIDI;
    'PT28D':'(0,0,F13,0,0,0,0)';$S;BIDI;
    'PT29A':'(0,0,A13,0,0,0,0)';$S;BIDI;
    'PT29B':'(0,0,B13,0,0,0,0)';$S;BIDI;
    'PT29C':'(0,0,C13,0,0,0,0)';$S;BIDI;
    'PT29D':'(0,0,D13,0,0,0,0)';$S;BIDI;
    'PT30A':'(0,0,A14,0,0,0,0)';$S;BIDI;
    'PT30B':'(0,0,B14,0,0,0,0)';$S;BIDI;
    'PT30C':'(0,0,C14,0,0,0,0)';$S;BIDI;
    'PT30D':'(0,0,D14,0,0,0,0)';$S;BIDI;
    'PT38A':'(0,0,A15,0,0,0,0)';$S;BIDI;
    'PT38B':'(0,0,B15,0,0,0,0)';$S;BIDI;
    'PT38C':'(0,0,C15,0,0,0,0)';$S;BIDI;
    'PT38D':'(0,0,D15,0,0,0,0)';$S;BIDI;
    'PT39A':'(0,0,A16,0,0,0,0)';$S;BIDI;
    'PT39B':'(0,0,B17,0,0,0,0)';$S;BIDI;
    'PT39C':'(0,0,C17,0,0,0,0)';$S;BIDI;
    'PT39D':'(0,0,D16,0,0,0,0)';$S;BIDI;
    'PT40A':'(0,0,A17,0,0,0,0)';$S;BIDI;
    'PT40B':'(0,0,B18,0,0,0,0)';$S;BIDI;
    'PT40C':'(0,0,E16,0,0,0,0)';$S;BIDI;
    'PT40D':'(0,0,D17,0,0,0,0)';$S;BIDI;
    'PT41C':'(0,0,C18,0,0,0,0)';$S;BIDI;
    'PT41D':'(0,0,D18,0,0,0,0)';$S;BIDI;
    'PT42A':'(0,0,A19,0,0,0,0)';$S;BIDI;
    'PT42B':'(0,0,B20,0,0,0,0)';$S;BIDI;
    'PT42C':'(0,0,F15,0,0,0,0)';$S;BIDI;
    'PT42D':'(0,0,G15,0,0,0,0)';$S;BIDI;
    'PT43C':'(0,0,C19,0,0,0,0)';$S;BIDI;
    'PT43D':'(0,0,C20,0,0,0,0)';$S;BIDI;
    'PT15C||TDO':'(0,0,0,E8,0,0,0)';$S;BIDI;
    'PT15D||TDI':'(0,0,0,E9,0,0,0)';$S;BIDI;
    'PT22C||TCK':'(0,0,0,D10,0,0,0)';$S;BIDI;
    'PT22D||TMS':'(0,0,0,C10,0,0,0)';$S;BIDI;
    'PT31D||PROGRAMN':'(0,0,0,E15,0,0,0)';$S;BIDI;
    'PT44C||INITN':'(0,0,0,F16,0,0,0)';$S;BIDI;
    'PT44D||DONE':'(0,0,0,E17,0,0,0)';$S;BIDI;
    'PT31C||JTAGENB':'(0,0,0,E14,0,0,0)';$S;BIDI;
    'VCC1':'(0,0,0,0,K10,0,0)';$S;
    'VCC2':'(0,0,0,0,K11,0,0)';$S;
    'VCC3':'(0,0,0,0,K12,0,0)';$S;
    'VCC4':'(0,0,0,0,K13,0,0)';$S;
    'VCC5':'(0,0,0,0,L11,0,0)';$S;
    'VCC6':'(0,0,0,0,L12,0,0)';$S;
    'VCC7':'(0,0,0,0,M11,0,0)';$S;
    'VCC8':'(0,0,0,0,M12,0,0)';$S;
    'VCC9':'(0,0,0,0,N10,0,0)';$S;
    'VCC10':'(0,0,0,0,N11,0,0)';$S;
    'VCC11':'(0,0,0,0,N12,0,0)';$S;
    'VCC12':'(0,0,0,0,N13,0,0)';$S;
    'VCCIO5_1':'(0,0,0,0,F3,0,0)';$S;
    'VCCIO5_2':'(0,0,0,0,J8,0,0)';$S;
    'VCCIO5_3':'(0,0,0,0,K8,0,0)';$S;
    'VCCIO4_1':'(0,0,0,0,L8,0,0)';$S;
    'VCCIO4_2':'(0,0,0,0,M8,0,0)';$S;
    'VCCIO4_3':'(0,0,0,0,M3,0,0)';$S;
    'VCCIO3_1':'(0,0,0,0,N8,0,0)';$S;
    'VCCIO3_2':'(0,0,0,0,P8,0,0)';$S;
    'VCCIO3_3':'(0,0,0,0,V3,0,0)';$S;
    'VCCIO2_1':'(0,0,0,0,R9,0,0)';$S;
    'VCCIO2_2':'(0,0,0,0,R10,0,0)';$S;
    'VCCIO2_3':'(0,0,0,0,R11,0,0)';$S;
    'VCCIO2_4':'(0,0,0,0,R12,0,0)';$S;
    'VCCIO2_5':'(0,0,0,0,R13,0,0)';$S;
    'VCCIO2_6':'(0,0,0,0,R14,0,0)';$S;
    'VCCIO2_7':'(0,0,0,0,W7,0,0)';$S;
    'VCCIO2_8':'(0,0,0,0,W11,0,0)';$S;
    'VCCIO2_9':'(0,0,0,0,W16,0,0)';$S;
    'VCCIO1_1':'(0,0,0,0,F20,0,0)';$S;
    'VCCIO1_2':'(0,0,0,0,J15,0,0)';$S;
    'VCCIO1_3':'(0,0,0,0,K15,0,0)';$S;
    'VCCIO1_4':'(0,0,0,0,L15,0,0)';$S;
    'VCCIO1_5':'(0,0,0,0,M15,0,0)';$S;
    'VCCIO1_6':'(0,0,0,0,M18,0,0)';$S;
    'VCCIO1_7':'(0,0,0,0,N15,0,0)';$S;
    'VCCIO1_8':'(0,0,0,0,P15,0,0)';$S;
    'VCCIO1_9':'(0,0,0,0,V20,0,0)';$S;
    'VCCIO0_1':'(0,0,0,0,C7,0,0)';$S;
    'VCCIO0_2':'(0,0,0,0,C12,0,0)';$S;
    'VCCIO0_3':'(0,0,0,0,C16,0,0)';$S;
    'VCCIO0_4':'(0,0,0,0,G10,0,0)';$S;
    'VCCIO0_7':'(0,0,0,0,H11,0,0)';$S;
    'VCCIO0_8':'(0,0,0,0,H12,0,0)';$S;
    'VCCIO0_9':'(0,0,0,0,H14,0,0)';$S;
    'VCCIO0_6':'(0,0,0,0,H9,0,0)';$S;
    'VCCIO0_5':'(0,0,0,0,G13,0,0)';$S;
    'GND1':'(0,0,0,0,0,A1,0)';$S;
    'GND2':'(0,0,0,0,0,A22,0)';$S;
    'GND3':'(0,0,0,0,0,B7,0)';$S;
    'GND4':'(0,0,0,0,0,B16,0)';$S;
    'GND5':'(0,0,0,0,0,C2,0)';$S;
    'GND6':'(0,0,0,0,0,C11,0)';$S;
    'GND7':'(0,0,0,0,0,E5,0)';$S;
    'GND8':'(0,0,0,0,0,E18,0)';$S;
    'GND9':'(0,0,0,0,0,F2,0)';$S;
    'GND10':'(0,0,0,0,0,F21,0)';$S;
    'GND11':'(0,0,0,0,0,H8,0)';$S;
    'GND12':'(0,0,0,0,0,H10,0)';$S;
    'GND13':'(0,0,0,0,0,H13,0)';$S;
    'GND14':'(0,0,0,0,0,H15,0)';$S;
    'GND15':'(0,0,0,0,0,J9,0)';$S;
    'GND16':'(0,0,0,0,0,J10,0)';$S;
    'GND17':'(0,0,0,0,0,J11,0)';$S;
    'GND18':'(0,0,0,0,0,J12,0)';$S;
    'GND19':'(0,0,0,0,0,J13,0)';$S;
    'GND20':'(0,0,0,0,0,J14,0)';$S;
    'GND21':'(0,0,0,0,0,K9,0)';$S;
    'GND22':'(0,0,0,0,0,K14,0)';$S;
    'GND23':'(0,0,0,0,0,K21,0)';$S;
    'GND24':'(0,0,0,0,0,L2,0)';$S;
    'GND25':'(0,0,0,0,0,L9,0)';$S;
    'GND26':'(0,0,0,0,0,L10,0)';$S;
    'GND27':'(0,0,0,0,0,L13,0)';$S;
    'GND28':'(0,0,0,0,0,L14,0)';$S;
    'GND29':'(0,0,0,0,0,L18,0)';$S;
    'GND30':'(0,0,0,0,0,M4,0)';$S;
    'GND31':'(0,0,0,0,0,M9,0)';$S;
    'GND32':'(0,0,0,0,0,M10,0)';$S;
    'GND33':'(0,0,0,0,0,M13,0)';$S;
    'GND34':'(0,0,0,0,0,M14,0)';$S;
    'GND35':'(0,0,0,0,0,N9,0)';$S;
    'GND36':'(0,0,0,0,0,N14,0)';$S;
    'GND37':'(0,0,0,0,0,N21,0)';$S;
    'GND38':'(0,0,0,0,0,P9,0)';$S;
    'GND39':'(0,0,0,0,0,P10,0)';$S;
    'GND40':'(0,0,0,0,0,P11,0)';$S;
    'GND41':'(0,0,0,0,0,P12,0)';$S;
    'GND42':'(0,0,0,0,0,P13,0)';$S;
    'GND43':'(0,0,0,0,0,P14,0)';$S;
    'GND44':'(0,0,0,0,0,R8,0)';$S;
    'GND45':'(0,0,0,0,0,R15,0)';$S;
    'GND46':'(0,0,0,0,0,V2,0)';$S;
    'GND47':'(0,0,0,0,0,V21,0)';$S;
    'GND48':'(0,0,0,0,0,W12,0)';$S;
    'GND50':'(0,0,0,0,0,Y16,0)';$S;
    'GND49':'(0,0,0,0,0,Y7,0)';$S;
    'GND51':'(0,0,0,0,0,AB1,0)';$S;
    'GND52':'(0,0,0,0,0,AB22,0)';$S;
    'PR30B':'(0,0,0,0,0,0,W20)';$S;BIDI;
    'PR30A':'(0,0,0,0,0,0,V18)';$S;BIDI;
    'PR29D':'(0,0,0,0,0,0,V19)';$S;BIDI;
    'PR29B':'(0,0,0,0,0,0,Y21)';$S;BIDI;
    'PR29C':'(0,0,0,0,0,0,U17)';$S;BIDI;
    'PR29A':'(0,0,0,0,0,0,AA22)';$S;BIDI;
    'PR25B':'(0,0,0,0,0,0,W22)';$S;BIDI;
    'PR25A':'(0,0,0,0,0,0,V22)';$S;BIDI;
    'PR20B':'(0,0,0,0,0,0,R21)';$S;BIDI;
    'PR20A':'(0,0,0,0,0,0,R22)';$S;BIDI;
    'PR19B':'(0,0,0,0,0,0,P21)';$S;BIDI;
    'PR19A':'(0,0,0,0,0,0,N22)';$S;BIDI;
    'PR17B||PCLKC1_0':'(0,0,0,0,0,0,M21)';$S;BIDI;
    'PR17A||PCLKT1_0':'(0,0,0,0,0,0,M22)';$S;BIDI;
    'PR16B':'(0,0,0,0,0,0,L21)';$S;BIDI;
    'PR16A':'(0,0,0,0,0,0,K22)';$S;BIDI;
    'PR14B':'(0,0,0,0,0,0,L16)';$S;BIDI;
    'PR14A':'(0,0,0,0,0,0,L17)';$S;BIDI;
    'PR7B':'(0,0,0,0,0,0,H21)';$S;BIDI;
    'PR7A':'(0,0,0,0,0,0,H22)';$S;BIDI;
    'PR3B||R_GPLLC_IN':'(0,0,0,0,0,0,D21)';$S;BIDI;
    'PR3A||R_GPLLT_IN':'(0,0,0,0,0,0,D22)';$S;BIDI;
    'PR2B||R_GPLLC_FB':'(0,0,0,0,0,0,C22)';$S;BIDI;
    'PR2A||R_GPLLT_FB':'(0,0,0,0,0,0,C21)';$S;BIDI;
    'PR2C':'(0,0,0,0,0,0,F17)';$S;BIDI;
    'PR2D':'(0,0,0,0,0,0,G16)';$S;BIDI;
    'PR3C':'(0,0,0,0,0,0,D19)';$S;BIDI;
    'PR3D':'(0,0,0,0,0,0,D20)';$S;BIDI;
    'PR4C':'(0,0,0,0,0,0,E19)';$S;BIDI;
    'PR4D':'(0,0,0,0,0,0,E20)';$S;BIDI;
    'PR4A':'(0,0,0,0,0,0,E22)';$S;BIDI;
    'PR4B':'(0,0,0,0,0,0,E21)';$S;BIDI;
    'PR5A':'(0,0,0,0,0,0,F22)';$S;BIDI;
    'PR5B':'(0,0,0,0,0,0,G22)';$S;BIDI;
    'PR5C':'(0,0,0,0,0,0,F18)';$S;BIDI;
    'PR5D':'(0,0,0,0,0,0,F19)';$S;BIDI;
    'PR6A':'(0,0,0,0,0,0,G21)';$S;BIDI;
    'PR6B':'(0,0,0,0,0,0,G20)';$S;BIDI;
    'PR6C':'(0,0,0,0,0,0,G19)';$S;BIDI;
    'PR6D':'(0,0,0,0,0,0,G18)';$S;BIDI;
    'PR7C':'(0,0,0,0,0,0,G17)';$S;BIDI;
    'PR7D':'(0,0,0,0,0,0,H20)';$S;BIDI;
    'PR10A':'(0,0,0,0,0,0,H19)';$S;BIDI;
    'PR10B':'(0,0,0,0,0,0,H18)';$S;BIDI;
    'PR10C':'(0,0,0,0,0,0,H17)';$S;BIDI;
    'PR10D':'(0,0,0,0,0,0,H16)';$S;BIDI;
    'PR11A':'(0,0,0,0,0,0,J16)';$S;BIDI;
    'PR11B':'(0,0,0,0,0,0,J17)';$S;BIDI;
    'PR11C':'(0,0,0,0,0,0,J18)';$S;BIDI;
    'PR11D':'(0,0,0,0,0,0,J19)';$S;BIDI;
    'PR12A':'(0,0,0,0,0,0,J21)';$S;BIDI;
    'PR12B':'(0,0,0,0,0,0,J22)';$S;BIDI;
    'PR12C':'(0,0,0,0,0,0,J20)';$S;BIDI;
    'PR12D':'(0,0,0,0,0,0,K20)';$S;BIDI;
    'PR13A':'(0,0,0,0,0,0,K19)';$S;BIDI;
    'PR13B':'(0,0,0,0,0,0,K18)';$S;BIDI;
    'PR13C':'(0,0,0,0,0,0,K17)';$S;BIDI;
    'PR13D':'(0,0,0,0,0,0,K16)';$S;BIDI;
    'PR14C':'(0,0,0,0,0,0,L19)';$S;BIDI;
    'PR14D':'(0,0,0,0,0,0,L20)';$S;BIDI;
    'PR16C':'(0,0,0,0,0,0,L22)';$S;BIDI;
    'PR16D':'(0,0,0,0,0,0,M17)';$S;BIDI;
    'PR17C':'(0,0,0,0,0,0,M20)';$S;BIDI;
    'PR17D':'(0,0,0,0,0,0,M19)';$S;BIDI;
    'PR18A':'(0,0,0,0,0,0,M16)';$S;BIDI;
    'PR18B':'(0,0,0,0,0,0,N16)';$S;BIDI;
    'PR18C':'(0,0,0,0,0,0,N17)';$S;BIDI;
    'PR18D':'(0,0,0,0,0,0,N18)';$S;BIDI;
    'PR19C':'(0,0,0,0,0,0,N20)';$S;BIDI;
    'PR19D':'(0,0,0,0,0,0,N19)';$S;BIDI;
    'PR20C':'(0,0,0,0,0,0,P22)';$S;BIDI;
    'PR20D':'(0,0,0,0,0,0,P20)';$S;BIDI;
    'PR21A':'(0,0,0,0,0,0,T22)';$S;BIDI;
    'PR21B':'(0,0,0,0,0,0,T21)';$S;BIDI;
    'PR21C':'(0,0,0,0,0,0,P19)';$S;BIDI;
    'PR21D':'(0,0,0,0,0,0,P18)';$S;BIDI;
    'PR24A':'(0,0,0,0,0,0,P17)';$S;BIDI;
    'PR24B':'(0,0,0,0,0,0,P16)';$S;BIDI;
    'PR24C':'(0,0,0,0,0,0,U22)';$S;BIDI;
    'PR24D':'(0,0,0,0,0,0,U21)';$S;BIDI;
    'PR25C':'(0,0,0,0,0,0,R20)';$S;BIDI;
    'PR25D':'(0,0,0,0,0,0,R19)';$S;BIDI;
    'PR26A':'(0,0,0,0,0,0,R18)';$S;BIDI;
    'PR26B':'(0,0,0,0,0,0,R17)';$S;BIDI;
    'PR26C':'(0,0,0,0,0,0,R16)';$S;BIDI;
    'PR26D':'(0,0,0,0,0,0,T20)';$S;BIDI;
    'PR27A':'(0,0,0,0,0,0,T19)';$S;BIDI;
    'PR27B':'(0,0,0,0,0,0,T18)';$S;BIDI;
    'PR27C':'(0,0,0,0,0,0,T17)';$S;BIDI;
    'PR27D':'(0,0,0,0,0,0,U20)';$S;BIDI;
    'PR28A':'(0,0,0,0,0,0,Y22)';$S;BIDI;
    'PR28B':'(0,0,0,0,0,0,W21)';$S;BIDI;
    'PR28C':'(0,0,0,0,0,0,U19)';$S;BIDI;
    'PR28D':'(0,0,0,0,0,0,U18)';$S;BIDI;
    'PR30C':'(0,0,0,0,0,0,W19)';$S;BIDI;
    'PR30D':'(0,0,0,0,0,0,Y20)';$S;BIDI;
end_primitive;
primitive 'LM4040AIM3X25NOPB-LM4040AIM3X-2.5/NOPB,SMLF,EMPTY,A';body 'LM4040AIM3X25NOPB';
    '1+':'(1)';BIDI;
    '2-':'(2)';OUT;
    '3':'(3)';BIDI;
end_primitive;
primitive 'LM4040AIM3X25NOPB-LM4040AIM3X-2.5/NOPB,SMLF,IC,AL4A';body 'LM4040AIM3X25NOPB';
    '1+':'(1)';BIDI;
    '2-':'(2)';OUT;
    '3':'(3)';BIDI;
end_primitive;
primitive 'LM75BD-LM75BD,SMLF,IC,AL0075BD000';body 'LM75BD';
    'SDA':'(1)';BIDI;
    'SCL':'(2)';IN;
    'OS':'(3)';OUT;
    'GND':'(4)';
    'A2':'(5)';IN;
    'A1':'(6)';IN;
    'A0':'(7)';IN;
    'VCC':'(8)';
end_primitive;
primitive 'LT6700CS61TRPBF-LT6700CS6-1#TRPBF,SMLF,EMPTY,AL006A';body 'LT6700CS61TRPBF';
    'VS':'(5)';
    'INB-':'(4)';IN;
    'GND':'(2)';
    'OUTA':'(1)';OUT;
    'INA+':'(3)';IN;
    'OUTB':'(6)';OUT;
end_primitive;
primitive 'LTC4307CMS8-LTC4307CMS8,SMLF,EMPTY,AL004307000';body 'LTC4307CMS8';
    'ENABLE':'(1)';IN;
    'SCL_IN':'(3)';BIDI;
    'SDA_IN':'(6)';BIDI;
    'SCL_OUT':'(2)';BIDI;
    'SDA_OUT':'(7)';BIDI;
    'READY':'(5)';OUT;
    'GND':'(4)';
    'VCC':'(8)';
end_primitive;
primitive 'LTC4307CMS8-LTC4307CMS8,SMLF,IC,AL004307000';body 'LTC4307CMS8';
    'ENABLE':'(1)';IN;
    'SCL_IN':'(3)';BIDI;
    'SDA_IN':'(6)';BIDI;
    'SCL_OUT':'(2)';BIDI;
    'SDA_OUT':'(7)';BIDI;
    'READY':'(5)';OUT;
    'GND':'(4)';
    'VCC':'(8)';
end_primitive;
primitive 'M24128BWMN6TP-M24128-BWMN6TP,SMLF,IC,AKE30Z00613';body 'M24128BWMN6TP';
    'VCC':'(8)';
    'WC#':'(7)';IN;
    'SCL':'(6)';IN;
    'SDA':'(5)';BIDI;
    'VSS':'(4)';
    'E2':'(3)';IN;
    'E1':'(2)';IN;
    'E0':'(1)';IN;
end_primitive;
primitive 'M24M02DRMN6TP-M24M02-DRMN6TP,SMLF,IC,AKE33Z00600';body 'M24M02DRMN6TP';
    'VCC':'(8)';
    'WC_N':'(7)';IN;
    'SCL':'(6)';IN;
    'SDA':'(5)';BIDI;
    'VSS':'(4)';
    'E2':'(3)';IN;
    'DU2':'(2)';IN;
    'DU1':'(1)';IN;
end_primitive;
primitive 'MAX11617EEET-MAX11617EEE+T,SMLF,EMPTY,AL011617W00';body 'MAX11617EEET';
    'AIN11||REF':'(1)';BIDI;
    'AIN10':'(2)';BIDI;
    'AIN9':'(3)';BIDI;
    'AIN8':'(4)';BIDI;
    'AIN0':'(5)';BIDI;
    'AIN1':'(6)';BIDI;
    'AIN2':'(7)';BIDI;
    'AIN3':'(8)';BIDI;
    'AIN4':'(9)';BIDI;
    'AIN5':'(10)';BIDI;
    'AIN6':'(11)';BIDI;
    'AIN7':'(12)';BIDI;
    'SCL':'(13)';BIDI;
    'SDA':'(14)';BIDI;
    'GND':'(15)';
    'VDD':'(16)';
end_primitive;
primitive 'MAX15090BEWIT-MAX15090BEWI+T,SMLF,IC,AL015080B00';body 'MAX15090BEWIT';
    'VCC':'(A2)';
    'IN_A3':'(A3)';IN;
    'IN_A5':'(A5)';IN;
    'IN_B3':'(B3)';IN;
    'IN_B5':'(B5)';IN;
    'IN_C3':'(C3)';IN;
    'IN_C5':'(C5)';IN;
    'IN_D5':'(D5)';IN;
    'CB':'(B1)';BIDI;
    'EN#':'(B7)';IN;
    'REG':'(D1)';OUT;
    'UV':'(D2)';IN;
    'OV':'(D3)';IN;
    'ISENSE':'(A1)';OUT;
    'OUT_A4':'(A4)';OUT;
    'OUT_B4':'(B4)';OUT;
    'OUT_B6':'(B6)';OUT;
    'OUT_C4':'(C4)';OUT;
    'OUT_C6':'(C6)';OUT;
    'OUT_D4':'(D4)';OUT;
    'OUT_D6':'(D6)';OUT;
    'GATE':'(A6)';BIDI;
    'CDLY':'(A7)';IN;
    'GND_B2':'(B2)';
    'GND_C1':'(C1)';
    'GND_C2':'(C2)';
    'FAULT#':'(C7)';OUT;
    'PG':'(D7)';OUT;
end_primitive;
primitive 'METR3904G-METR3904-G,SMLF,IC,BA039040020';body 'METR3904G';
    '1':'(B)';IN;
    '2':'(E)';BIDI;
    '3':'(C)';BIDI;
end_primitive;
primitive 'MOSFET_DUAL_6P-2N7002KDW,SMLF,IC,BAM70020047';body 'MOSFET_DUAL_6P';
    'G1':'(2)';BIDI;
    'G2':'(5)';BIDI;
    'S1':'(1)';BIDI;
    'S2':'(4)';BIDI;
    'D1':'(6)';BIDI;
    'D2':'(3)';BIDI;
end_primitive;
primitive 'MOSFET_NCH_1D3S-PSMNR58-30YLH,SMLF,EMPTY,BAMNR5800A';body 'MOSFET_NCH_1D3S';
    '3':'(3)';BIDI;
    '5':'(5)';BIDI;
    '2':'(2)';BIDI;
    '4':'(4)';IN;
    '1':'(1)';BIDI;
end_primitive;
primitive 'MOSFET_NCH_1D3S-PSMNR58-30YLH,SMLF,IC,BAMNR580000';body 'MOSFET_NCH_1D3S';
    '3':'(3)';BIDI;
    '5':'(5)';BIDI;
    '2':'(2)';BIDI;
    '4':'(4)';IN;
    '1':'(1)';BIDI;
end_primitive;
primitive 'MOSFET_NCH_DUAL-PJT138K,SMLF,IC,BAM138K0003';body 'MOSFET_NCH_DUAL';
    'S1':'(1,0)';$S;BIDI;
    'G1':'(2,0)';$S;BIDI;
    'D1':'(6,0)';$S;BIDI;
    'D2':'(0,3)';$S;BIDI;
    'G2':'(0,5)';$S;BIDI;
    'S2':'(0,4)';$S;BIDI;
end_primitive;
primitive 'MOSFET_NCH_GDS_ESD_PROTECTED-2N7002K,SMLF,EMPTY,BAA';body 'MOSFET_NCH_GDS_ESD_PROTECTED';
    'D':'(D)';BIDI;
    'G':'(G)';IN;
    'S':'(S)';BIDI;
end_primitive;
primitive 'MOSFET_NCH_GDS_ESD_PROTECTED-2N7002K,SMLF,IC,BAM70A';body 'MOSFET_NCH_GDS_ESD_PROTECTED';
    'D':'(D)';BIDI;
    'G':'(G)';IN;
    'S':'(S)';BIDI;
end_primitive;
primitive 'MOSFET_N_GSD-NX138BK,SMLF,IC,BAM01380023';body 'MOSFET_N_GSD';
    'GATE':'(G)';IN;
    'SOURCE':'(S)';BIDI;
    'DRAIN':'(D)';BIDI;
end_primitive;
primitive 'MOSFET_N_SMLF-BSS138K,BSS138K,EMPTY,BAM138K0000';body 'MOSFET_N';
    'GATE':'(G)';IN;
    'DRAIN':'(D)';OUT;
    'SOURCE':'(S)';BIDI;
end_primitive;
primitive 'MOSFET_N_SMLF-BSS138K,BSS138K,IC,BAM138K0000';body 'MOSFET_N';
    'GATE':'(G)';IN;
    'DRAIN':'(D)';OUT;
    'SOURCE':'(S)';BIDI;
end_primitive;
primitive 'MOSFET_PCH_GDS_ESD_PROTECTED-DMP2035U-7,SMLF,EMPTYA';body 'MOSFET_PCH_GDS_ESD_PROTECTED';
    'D':'(D)';BIDI;
    'G':'(G)';IN;
    'S':'(S)';BIDI;
end_primitive;
primitive 'MOSFET_PCH_GDS_ESD_PROTECTED-PJA3415AE,SMLF,IC,BAMA';body 'MOSFET_PCH_GDS_ESD_PROTECTED';
    'D':'(D)';BIDI;
    'G':'(G)';IN;
    'S':'(S)';BIDI;
end_primitive;
primitive 'MP5016GQHLZ-MP5016GQH-L-Z,SMLF,IC,AL005016007';body 'MP5016GQHLZ';
    'EN':'(9)';IN;
    'MODE':'(5)';IN;
    'ILIMIT':'(4)';OUT;
    'GND':'(3)';
    'VCC':'(1_2)';
    'DV_DT':'(10)';OUT;
    'GATE':'(8)';OUT;
    'SOURCE':'(6_7)';OUT;
end_primitive;
primitive 'MP5990GMA1111Z-MP5990GMA-1111-Z,SMLF,IC,AR0F0TP4023';body 'MP5990GMA1111Z';
    'VOUT3':'(29)';OUT;
    'VOUT2':'(28)';OUT;
    'VOUT1':'(27)';OUT;
    'VIN2':'(2)';IN;
    'EN':'(26)';IN;
    'VIN3':'(3)';IN;
    'VIN4':'(4)';IN;
    'GND1':'(18)';
    'SDA':'(12)';BIDI;
    'VIN_UVW#':'(14)';OUT;
    'SCL':'(11)';IN;
    'D_OC':'(37)';OUT;
    'VOUT5':'(31)';OUT;
    'VOUT9':'(35)';OUT;
    'ALT#':'(10)';OUT;
    'GOK':'(39)';BIDI;
    'VIN7':'(7)';IN;
    'VOUT7':'(33)';OUT;
    'MODE':'(41)';IN;
    'VIN8':'(8)';IN;
    'PG||OCW#':'(13)';OUT;
    'VOUT8':'(34)';OUT;
    'ON':'(38)';OUT;
    'VIN5':'(5)';IN;
    'VIN6':'(6)';IN;
    'VTEMP':'(15)';IN;
    'OCREF':'(22)';OUT;
    'SCREF_OCWREF':'(25)';OUT;
    'SS':'(16)';OUT;
    'VOUT6':'(32)';OUT;
    'IMON':'(21)';BIDI;
    'CS':'(20)';OUT;
    'VIN9':'(42)';IN;
    'VOUT10':'(36)';OUT;
    'VOSEN':'(24)';IN;
    'VOUT4':'(30)';OUT;
    'VIN1':'(1)';IN;
    'GND2':'(44)';
    'FLT_TYPE':'(40)';IN;
    'VIN10':'(43)';IN;
    'VINSEN':'(9)';IN;
    'VDD33_1':'(17)';
    'VDD33_2':'(45)';
    'VDD18':'(19)';
    'ADDR':'(23)';IN;
end_primitive;
primitive 'MP5991GLUZ-MP5991GLU-Z,SMLF,IC,AL005991A00';body 'MP5991GLUZ';
    'VIN1':'(9)';IN;
    'VIN2':'(10)';IN;
    'VIN3':'(11)';IN;
    'VIN4':'(12)';IN;
    'VIN5':'(13)';IN;
    'ON':'(4)';IN;
    'OCREF':'(24)';OUT;
    'CS':'(23)';OUT;
    'IMON':'(22)';OUT;
    'VDD33':'(21)';
    'GND':'(20)';
    'SS':'(19)';IN;
    'GOK':'(5)';OUT;
    'VTEMP':'(18)';OUT;
    'VOUT1':'(1)';OUT;
    'VOUT2':'(2)';OUT;
    'VOUT3':'(25)';OUT;
    'VOUT4':'(26)';OUT;
    'D_OC':'(3)';OUT;
    'VIN6':'(14)';IN;
    'VIN7':'(15)';IN;
    'VIN8':'(16)';IN;
    'VIN9':'(33)';IN;
    'VOUT5':'(27)';OUT;
    'VOUT6':'(28)';OUT;
    'VOUT7':'(29)';OUT;
    'VOUT8':'(30)';OUT;
    'VOUT9':'(31)';OUT;
    'VOUT10':'(32)';OUT;
    'MODE':'(8)';IN;
    'SCREF_OCWREF':'(17)';IN;
    'FLT_TYPE':'(6)';IN;
    'NC1':'(7)';OUT;
end_primitive;
primitive 'MPQ8626GDZ-MPQ8626GD-Z,SMLF,IC,AL008626000';body 'MPQ8626GDZ';
    'VIN':'(3)';IN;
    'PGOOD':'(9)';OUT;
    'PGND2':'(14)';
    'EN':'(5)';IN;
    'BST':'(10)';IN;
    'FB':'(6)';IN;
    'AGND':'(7)';
    'VCC':'(13)';OUT;
    'PGND1':'(1)';
    'SW2':'(11)';OUT;
    'TRK_REF':'(8)';IN;
    'MODE':'(12)';IN;
    'CS':'(4)';IN;
    'SW1':'(2)';OUT;
end_primitive;
primitive 'MPQ8633AGLEC807Z-MPQ8633AGLE-C807-Z,SMLF,IC,AL0086A';body 'MPQ8633AGLEC807Z';
    'VIN1':'(10)';IN;
    'PGOOD':'(9)';OUT;
    'PGND':'(11_18)';
    'EN':'(8)';IN;
    'BST':'(1)';IN;
    'FB':'(7)';IN;
    'AGND':'(2)';
    'VCC':'(19)';
    'RGND':'(6)';
    'SW':'(20)';OUT;
    'TRK_REF':'(5)';IN;
    'MODE':'(4)';IN;
    'CS':'(3)';IN;
    'VIN2':'(21)';IN;
end_primitive;
primitive 'MPQ8633BGLEC838Z-MPQ8633BGLE-C838-Z,SMLF,IC,AL0086A';body 'MPQ8633BGLEC838Z';
    'VIN1':'(10)';IN;
    'PGOOD':'(9)';OUT;
    'PGND':'(11_18)';
    'EN':'(8)';IN;
    'BST':'(1)';IN;
    'FB':'(7)';IN;
    'AGND':'(2)';
    'VCC':'(19)';IN;
    'RGND':'(6)';
    'SW':'(20)';OUT;
    'TRK_REF':'(5)';IN;
    'MODE':'(4)';IN;
    'CS':'(3)';IN;
    'VIN2':'(21)';IN;
end_primitive;
primitive 'NC7SB3157P6X-NC7SB3157P6X,SMLF,IC,ALSB3157000';body 'NC7SB3157P6X';
    'B1':'(1)';BIDI;
    'GND':'(2)';
    'B0':'(3)';BIDI;
    'S':'(6)';IN;
    'VCC':'(5)';
    'A':'(4)';BIDI;
end_primitive;
primitive 'NC7SB3157_SMLF-NC7SB3157P6X,NC7SB3157P6X,EMPTY,ALSA';body 'NC7SB3157';
    'B1':'(1)';BIDI;
    'GND':'(2)';
    'B0':'(3)';BIDI;
    'S':'(6)';IN;
    'VCC':'(5)';
    'A':'(4)';BIDI;
end_primitive;
primitive 'NCP3284AMNTXG-NCP3284AMNTXG,SMLF,IC,AL003284002';body 'NCP3284AMNTXG';
    'NC2':'(34)';OUT;
    'MODE||FSET':'(36)';IN;
    'VIN':'(3)';
    'FB':'(30)';IN;
    'BOOT':'(26)';BIDI;
    'ILIM':'(1)';OUT;
    'PHASE':'(25)';IN;
    'VCC':'(4)';
    'VSNS-':'(31)';IN;
    'HICCUP#':'(35)';IN;
    'PGND':'(7_10-19)';
    'NC1':'(33)';OUT;
    'SW':'(11_18)';BIDI;
    'PVIN':'(20_24)';
    'PGOOD':'(2)';OUT;
    'VOS':'(28)';IN;
    'AGND':'(32)';
    'EN':'(27)';IN;
    'VDRV':'(5)';
    'GL1':'(6)';OUT;
    'SS':'(29)';IN;
    'GL2':'(37)';OUT;
end_primitive;
primitive 'NCP698SQ15T1G-NCP698SQ15T1G,SMLF,EMPTY,AL000698000';body 'NCP698SQ15T1G';
    'GND':'(1)';
    'VOUT':'(3)';OUT;
    'VIN':'(2)';IN;
    'EN':'(4)';IN;
end_primitive;
primitive 'NCT7718W-NCT7718W,SMLF,IC,AL007718001';body 'NCT7718W';
    'VDD':'(1)';
    'D+':'(2)';IN;
    'D-':'(3)';IN;
    'T_CRIT#':'(4)';OUT;
    'GND':'(5)';
    'ALERT#':'(6)';OUT;
    'SDA':'(7)';BIDI;
    'SCL':'(8)';IN;
end_primitive;
primitive 'PCA9306DP1-PCA9306DP1,SMLF,IC,AL009306K04';body 'PCA9306DP1';
    'VREF1':'(2)';
    'SCL1':'(3)';BIDI;
    'SDA1':'(4)';BIDI;
    'SDA2':'(5)';BIDI;
    'SCL2':'(6)';BIDI;
    'VREF2':'(7)';
    'EN':'(8)';IN;
    'GND':'(1)';
end_primitive;
primitive 'PCA9539RPW-PCA9539RPW,SMLF,IC,AL009539K07';body 'PCA9539RPW';
    'INT':'(1)';BIDI;
    'A1':'(2)';IN;
    'RESET':'(3)';BIDI;
    'IO0_0':'(4)';BIDI;
    'IO0_1':'(5)';BIDI;
    'IO0_2':'(6)';BIDI;
    'IO0_3':'(7)';BIDI;
    'IO0_4':'(8)';BIDI;
    'IO0_5':'(9)';BIDI;
    'IO0_6':'(10)';BIDI;
    'IO0_7':'(11)';BIDI;
    'VSS':'(12)';
    'IO1_0':'(13)';BIDI;
    'IO1_1':'(14)';BIDI;
    'IO1_2':'(15)';BIDI;
    'IO1_3':'(16)';BIDI;
    'IO1_4':'(17)';BIDI;
    'IO1_5':'(18)';BIDI;
    'IO1_6':'(19)';BIDI;
    'IO1_7':'(20)';BIDI;
    'A0':'(21)';IN;
    'SCL':'(22)';BIDI;
    'SDA':'(23)';BIDI;
    'VDD':'(24)';
end_primitive;
primitive 'PCA9617ADP-PCA9617ADP,SMLF,EMPTY,AL009617K02';body 'PCA9617ADP';
    'EN':'(5)';IN;
    'VCCA':'(1)';
    'VCCB':'(8)';
    'SCLA':'(2)';BIDI;
    'SDAA':'(3)';BIDI;
    'SDAB':'(6)';BIDI;
    'SCLB':'(7)';BIDI;
    'GND':'(4)';
end_primitive;
primitive 'PCA9617ADP-PCA9617ADP,SMLF,IC,AL009617K02';body 'PCA9617ADP';
    'EN':'(5)';IN;
    'VCCA':'(1)';
    'VCCB':'(8)';
    'SCLA':'(2)';BIDI;
    'SDAA':'(3)';BIDI;
    'SDAB':'(6)';BIDI;
    'SCLB':'(7)';BIDI;
    'GND':'(4)';
end_primitive;
primitive 'PI3CSW12ZUAEX-PI3CSW12ZUAEX,SMLF,IC,AL3CSW12000';body 'PI3CSW12ZUAEX';
    '1D+':'(1)';BIDI;
    '2D+':'(3)';BIDI;
    '2D-':'(4)';BIDI;
    'D-':'(7)';BIDI;
    'OE#':'(6)';IN;
    'S':'(9)';IN;
    'VDD':'(10)';
    '1D-':'(2)';BIDI;
    'GND':'(5)';
    'D+':'(8)';BIDI;
end_primitive;
primitive 'PI3EQX12902AZLEX-PI3EQX12902AZLEX,SMLF,IC,AL012902A';body 'PI3EQX12902AZLEX';
    'VDD1':'(1)';
    'AIP':'(2)';IN;
    'AIN':'(3)';IN;
    'GND1':'(4)';
    'TEST#':'(5)';IN;
    'GND2':'(6)';
    'GND3':'(7)';
    'BON':'(8)';OUT;
    'BOP':'(9)';OUT;
    'VDD2':'(10)';
    'EN#':'(11)';IN;
    'SWB':'(12)';IN;
    'GND4':'(13)';
    'FGB':'(14)';IN;
    'EQB1':'(15)';IN;
    'VDD3':'(16)';
    'BIP':'(17)';IN;
    'BIN':'(18)';IN;
    'GND5':'(19)';
    'EQB0':'(20)';IN;
    'EQA0':'(21)';IN;
    'GND6':'(22)';
    'AON':'(23)';OUT;
    'AOP':'(24)';OUT;
    'VDD4':'(25)';
    'EQA1':'(26)';IN;
    'FGA':'(27)';IN;
    'GND7':'(28)';
    'SWA':'(29)';IN;
    'MODE':'(30)';IN;
    'GND_TH':'(TH)';
end_primitive;
primitive 'PI4ULS3V304AZMAEX-PI4ULS3V304AZMAEX,SMLF,IC,AL0003A';body 'PI4ULS3V304AZMAEX';
    'A1':'(2)';BIDI;
    'A2':'(3)';BIDI;
    'A3':'(4)';BIDI;
    'VCCB':'(11)';
    'EN':'(12)';IN;
    'A4':'(5)';BIDI;
    'VCCA':'(1)';
    'B1':'(10)';BIDI;
    'B2':'(9)';BIDI;
    'B3':'(8)';BIDI;
    'B4':'(7)';BIDI;
    'GND':'(6)';
end_primitive;
primitive 'PI6CV304LE-PI6CV304LE,SMLF,IC,AL000304K01';body 'PI6CV304LE';
    'CLK_IN':'(1)';IN;
    'OE':'(2)';IN;
    'Y0':'(3)';OUT;
    'Y1':'(5)';OUT;
    'Y2':'(7)';OUT;
    'Y3':'(8)';OUT;
    'VDD':'(6)';
    'GND':'(4)';
end_primitive;
primitive 'PICOPROBE_BXA-DELTA-L 4.0,SMLF,EMPTY,TP33';body 'PICOPROBE_BXA';
    '2_N':'(2)';
    '3_G':'(3)';
    '1_P':'(1)';
end_primitive;
primitive 'PT5161LRS-PT5161LRS,SMLF,IC,AJ051610U03';body 'PT5161LRS';
    'A_PERP0':'(R1,0,0,0,0,0,0,0,0,0,0)';$S;IN;
    'A_PERN0':'(N2,0,0,0,0,0,0,0,0,0,0)';$S;IN;
    'A_PERP1':'(AB1,0,0,0,0,0,0,0,0,0,0)';$S;IN;
    'A_PERN1':'(Y2,0,0,0,0,0,0,0,0,0,0)';$S;IN;
    'A_PERP2':'(AJ1,0,0,0,0,0,0,0,0,0,0)';$S;IN;
    'A_PERN2':'(AG2,0,0,0,0,0,0,0,0,0,0)';$S;IN;
    'A_PERP3':'(AT1,0,0,0,0,0,0,0,0,0,0)';$S;IN;
    'A_PERN3':'(AP2,0,0,0,0,0,0,0,0,0,0)';$S;IN;
    'A_PERP4':'(BC1,0,0,0,0,0,0,0,0,0,0)';$S;IN;
    'A_PERN4':'(BA2,0,0,0,0,0,0,0,0,0,0)';$S;IN;
    'A_PERP5':'(BK1,0,0,0,0,0,0,0,0,0,0)';$S;IN;
    'A_PERN5':'(BH2,0,0,0,0,0,0,0,0,0,0)';$S;IN;
    'A_PERP6':'(BU1,0,0,0,0,0,0,0,0,0,0)';$S;IN;
    'A_PERN6':'(BR2,0,0,0,0,0,0,0,0,0,0)';$S;IN;
    'A_PERP7':'(CD1,0,0,0,0,0,0,0,0,0,0)';$S;IN;
    'A_PERN7':'(CB2,0,0,0,0,0,0,0,0,0,0)';$S;IN;
    'A_PERP8':'(0,CL1,0,0,0,0,0,0,0,0,0)';$S;IN;
    'A_PERN8':'(0,CJ2,0,0,0,0,0,0,0,0,0)';$S;IN;
    'A_PERP9':'(0,CV1,0,0,0,0,0,0,0,0,0)';$S;IN;
    'A_PERN9':'(0,CT2,0,0,0,0,0,0,0,0,0)';$S;IN;
    'A_PERP10':'(0,DE1,0,0,0,0,0,0,0,0,0)';$S;IN;
    'A_PERN10':'(0,DC2,0,0,0,0,0,0,0,0,0)';$S;IN;
    'A_PERP11':'(0,DM1,0,0,0,0,0,0,0,0,0)';$S;IN;
    'A_PERN11':'(0,DK2,0,0,0,0,0,0,0,0,0)';$S;IN;
    'A_PERP12':'(0,DW1,0,0,0,0,0,0,0,0,0)';$S;IN;
    'A_PERN12':'(0,DU2,0,0,0,0,0,0,0,0,0)';$S;IN;
    'A_PERP13':'(0,EF1,0,0,0,0,0,0,0,0,0)';$S;IN;
    'A_PERN13':'(0,ED2,0,0,0,0,0,0,0,0,0)';$S;IN;
    'A_PERP14':'(0,EN1,0,0,0,0,0,0,0,0,0)';$S;IN;
    'A_PERN14':'(0,EL2,0,0,0,0,0,0,0,0,0)';$S;IN;
    'A_PERP15':'(0,EY1,0,0,0,0,0,0,0,0,0)';$S;IN;
    'A_PERN15':'(0,EV2,0,0,0,0,0,0,0,0,0)';$S;IN;
    'GPIO0':'(0,0,FJ6,0,0,0,0,0,0,0,0)';$S;BIDI;
    'GPIO1':'(0,0,FJ23,0,0,0,0,0,0,0,0)';$S;BIDI;
    'GPIO2':'(0,0,FJ25,0,0,0,0,0,0,0,0)';$S;BIDI;
    'GPIO3':'(0,0,FJ28,0,0,0,0,0,0,0,0)';$S;BIDI;
    'INT_N':'(0,0,FJ31,0,0,0,0,0,0,0,0)';$S;OUT;
    'JTAG_TCK':'(0,0,B3,0,0,0,0,0,0,0,0)';$S;IN;
    'JTAG_TDI':'(0,0,B6,0,0,0,0,0,0,0,0)';$S;IN;
    'JTAG_TDO':'(0,0,B9,0,0,0,0,0,0,0,0)';$S;OUT;
    'JTAG_TEST_MODE':'(0,0,FF8,0,0,0,0,0,0,0,0)';$S;IN;
    'JTAG_TMS':'(0,0,B12,0,0,0,0,0,0,0,0)';$S;IN;
    'JTAG_TRST_N':'(0,0,E8,0,0,0,0,0,0,0,0)';$S;IN;
    'MODE':'(0,0,FJ9,0,0,0,0,0,0,0,0)';$S;IN;
    'PERST_N':'(0,0,F2,0,0,0,0,0,0,0,0)';$S;IN;
    'REFCLK_OUTN':'(0,0,E18,0,0,0,0,0,0,0,0)';$S;OUT;
    'REFCLK_OUTP':'(0,0,B16,0,0,0,0,0,0,0,0)';$S;OUT;
    'REFCLKN':'(0,0,FF18,0,0,0,0,0,0,0,0)';$S;IN;
    'REFCLKP':'(0,0,FJ16,0,0,0,0,0,0,0,0)';$S;IN;
    'RESET_N':'(0,0,FF11,0,0,0,0,0,0,0,0)';$S;IN;
    'RXDET_BYP':'(0,0,E11,0,0,0,0,0,0,0,0)';$S;IN;
    'SCAN_MODE':'(0,0,FF33,0,0,0,0,0,0,0,0)';$S;IN;
    'SMB_ADDR1':'(0,0,F34,0,0,0,0,0,0,0,0)';$S;IN;
    'SMB_ADDR2':'(0,0,B23,0,0,0,0,0,0,0,0)';$S;IN;
    'SMB_ADDR3':'(0,0,B25,0,0,0,0,0,0,0,0)';$S;IN;
    'SMBCLK':'(0,0,B31,0,0,0,0,0,0,0,0)';$S;BIDI;
    'SMBDAT':'(0,0,B28,0,0,0,0,0,0,0,0)';$S;BIDI;
    'T_SENSE':'(0,0,E30,0,0,0,0,0,0,0,0)';$S;OUT;
    'TEST0':'(0,0,FF24,0,0,0,0,0,0,0,0)';$S;BIDI;
    'TEST1':'(0,0,FF27,0,0,0,0,0,0,0,0)';$S;BIDI;
    'TEST2':'(0,0,FF30,0,0,0,0,0,0,0,0)';$S;BIDI;
    'CLKREQ_N':'(0,0,G35,0,0,0,0,0,0,0,0)';$S;IN;
    'EE_CLK':'(0,0,FF5,0,0,0,0,0,0,0,0)';$S;BIDI;
    'EE_DAT':'(0,0,FJ3,0,0,0,0,0,0,0,0)';$S;BIDI;
    'VQPS':'(0,0,0,G1,0,0,0,0,0,0,0)';$S;IN;
    'PWR_1A_1':'(0,0,0,BV20,0,0,0,0,0,0,0)';$S;
    'PWR_1A_2':'(0,0,0,CE17,0,0,0,0,0,0,0)';$S;
    'PWR_1A_3':'(0,0,0,CE20,0,0,0,0,0,0,0)';$S;
    'PWR_1A_4':'(0,0,0,CM17,0,0,0,0,0,0,0)';$S;
    'PWR_1A_5':'(0,0,0,CM20,0,0,0,0,0,0,0)';$S;
    'PWR_2D_1':'(0,0,0,BL17,0,0,0,0,0,0,0)';$S;
    'PWR_2D_2':'(0,0,0,BL20,0,0,0,0,0,0,0)';$S;
    'PWR_2D_3':'(0,0,0,CW17,0,0,0,0,0,0,0)';$S;
    'PWR_2D_4':'(0,0,0,CW20,0,0,0,0,0,0,0)';$S;
    'PWR_1D':'(0,0,0,BV17,0,0,0,0,0,0,0)';$S;
    'PWR_2A_1':'(0,0,0,AC17,0,0,0,0,0,0,0)';$S;
    'PWR_2A_2':'(0,0,0,AC20,0,0,0,0,0,0,0)';$S;
    'PWR_2A_3':'(0,0,0,AK17,0,0,0,0,0,0,0)';$S;
    'PWR_2A_4':'(0,0,0,AK20,0,0,0,0,0,0,0)';$S;
    'PWR_2A_5':'(0,0,0,AU17,0,0,0,0,0,0,0)';$S;
    'PWR_2A_6':'(0,0,0,AU20,0,0,0,0,0,0,0)';$S;
    'PWR_2A_7':'(0,0,0,BD17,0,0,0,0,0,0,0)';$S;
    'PWR_2A_8':'(0,0,0,BD20,0,0,0,0,0,0,0)';$S;
    'PWR_2A_9':'(0,0,0,DF17,0,0,0,0,0,0,0)';$S;
    'PWR_2A_10':'(0,0,0,DF20,0,0,0,0,0,0,0)';$S;
    'PWR_2A_11':'(0,0,0,DN17,0,0,0,0,0,0,0)';$S;
    'PWR_2A_12':'(0,0,0,DN20,0,0,0,0,0,0,0)';$S;
    'PWR_2A_13':'(0,0,0,DY17,0,0,0,0,0,0,0)';$S;
    'PWR_2A_14':'(0,0,0,DY20,0,0,0,0,0,0,0)';$S;
    'PWR_2A_15':'(0,0,0,EG17,0,0,0,0,0,0,0)';$S;
    'PWR_2A_16':'(0,0,0,EG20,0,0,0,0,0,0,0)';$S;
    'PWR_2A_17':'(0,0,0,EP17,0,0,0,0,0,0,0)';$S;
    'PWR_2A_18':'(0,0,0,EP20,0,0,0,0,0,0,0)';$S;
    'PWR_2A_19':'(0,0,0,T17,0,0,0,0,0,0,0)';$S;
    'PWR_2A_20':'(0,0,0,T20,0,0,0,0,0,0,0)';$S;
    'GND1':'(0,0,0,0,AC13,0,0,0,0,0,0)';$S;
    'GND2':'(0,0,0,0,AC22,0,0,0,0,0,0)';$S;
    'GND3':'(0,0,0,0,AC32,0,0,0,0,0,0)';$S;
    'GND4':'(0,0,0,0,AC4,0,0,0,0,0,0)';$S;
    'GND5':'(0,0,0,0,AD2,0,0,0,0,0,0)';$S;
    'GND6':'(0,0,0,0,AD34,0,0,0,0,0,0)';$S;
    'GND7':'(0,0,0,0,AE1,0,0,0,0,0,0)';$S;
    'GND8':'(0,0,0,0,AE35,0,0,0,0,0,0)';$S;
    'GND9':'(0,0,0,0,AK13,0,0,0,0,0,0)';$S;
    'GND10':'(0,0,0,0,AK22,0,0,0,0,0,0)';$S;
    'GND11':'(0,0,0,0,AK32,0,0,0,0,0,0)';$S;
    'GND12':'(0,0,0,0,AK4,0,0,0,0,0,0)';$S;
    'GND13':'(0,0,0,0,AL2,0,0,0,0,0,0)';$S;
    'GND14':'(0,0,0,0,AL34,0,0,0,0,0,0)';$S;
    'GND15':'(0,0,0,0,AM1,0,0,0,0,0,0)';$S;
    'GND16':'(0,0,0,0,AM35,0,0,0,0,0,0)';$S;
    'GND17':'(0,0,0,0,AU13,0,0,0,0,0,0)';$S;
    'GND18':'(0,0,0,0,AU22,0,0,0,0,0,0)';$S;
    'GND19':'(0,0,0,0,AU32,0,0,0,0,0,0)';$S;
    'GND20':'(0,0,0,0,AU4,0,0,0,0,0,0)';$S;
    'GND21':'(0,0,0,0,AV2,0,0,0,0,0,0)';$S;
    'GND22':'(0,0,0,0,AV34,0,0,0,0,0,0)';$S;
    'GND23':'(0,0,0,0,AW1,0,0,0,0,0,0)';$S;
    'GND24':'(0,0,0,0,AW35,0,0,0,0,0,0)';$S;
    'GND25':'(0,0,0,0,B19,0,0,0,0,0,0)';$S;
    'GND26':'(0,0,0,0,BD13,0,0,0,0,0,0)';$S;
    'GND27':'(0,0,0,0,BD22,0,0,0,0,0,0)';$S;
    'GND28':'(0,0,0,0,BD32,0,0,0,0,0,0)';$S;
    'GND29':'(0,0,0,0,BD4,0,0,0,0,0,0)';$S;
    'GND30':'(0,0,0,0,BE2,0,0,0,0,0,0)';$S;
    'GND31':'(0,0,0,0,BE34,0,0,0,0,0,0)';$S;
    'GND32':'(0,0,0,0,BF1,0,0,0,0,0,0)';$S;
    'GND33':'(0,0,0,0,BF35,0,0,0,0,0,0)';$S;
    'GND34':'(0,0,0,0,BL13,0,0,0,0,0,0)';$S;
    'GND35':'(0,0,0,0,BL22,0,0,0,0,0,0)';$S;
    'GND36':'(0,0,0,0,BL32,0,0,0,0,0,0)';$S;
    'GND37':'(0,0,0,0,BL4,0,0,0,0,0,0)';$S;
    'GND38':'(0,0,0,0,BM2,0,0,0,0,0,0)';$S;
    'GND39':'(0,0,0,0,BM34,0,0,0,0,0,0)';$S;
    'GND40':'(0,0,0,0,BN1,0,0,0,0,0,0)';$S;
    'GND41':'(0,0,0,0,BN35,0,0,0,0,0,0)';$S;
    'GND42':'(0,0,0,0,BV13,0,0,0,0,0,0)';$S;
    'GND43':'(0,0,0,0,BV22,0,0,0,0,0,0)';$S;
    'GND44':'(0,0,0,0,BV32,0,0,0,0,0,0)';$S;
    'GND45':'(0,0,0,0,BV4,0,0,0,0,0,0)';$S;
    'GND46':'(0,0,0,0,BW2,0,0,0,0,0,0)';$S;
    'GND47':'(0,0,0,0,BW34,0,0,0,0,0,0)';$S;
    'GND48':'(0,0,0,0,BY1,0,0,0,0,0,0)';$S;
    'GND49':'(0,0,0,0,BY35,0,0,0,0,0,0)';$S;
    'GND50':'(0,0,0,0,CE13,0,0,0,0,0,0)';$S;
    'GND51':'(0,0,0,0,CE22,0,0,0,0,0,0)';$S;
    'GND52':'(0,0,0,0,CE32,0,0,0,0,0,0)';$S;
    'GND53':'(0,0,0,0,CE4,0,0,0,0,0,0)';$S;
    'GND54':'(0,0,0,0,CF2,0,0,0,0,0,0)';$S;
    'GND55':'(0,0,0,0,CF34,0,0,0,0,0,0)';$S;
    'GND56':'(0,0,0,0,CG1,0,0,0,0,0,0)';$S;
    'GND57':'(0,0,0,0,CG35,0,0,0,0,0,0)';$S;
    'GND58':'(0,0,0,0,CM13,0,0,0,0,0,0)';$S;
    'GND59':'(0,0,0,0,CM22,0,0,0,0,0,0)';$S;
    'GND60':'(0,0,0,0,CM32,0,0,0,0,0,0)';$S;
    'GND61':'(0,0,0,0,CM4,0,0,0,0,0,0)';$S;
    'GND62':'(0,0,0,0,CN2,0,0,0,0,0,0)';$S;
    'GND63':'(0,0,0,0,CN34,0,0,0,0,0,0)';$S;
    'GND64':'(0,0,0,0,CP1,0,0,0,0,0,0)';$S;
    'GND65':'(0,0,0,0,CP35,0,0,0,0,0,0)';$S;
    'GND66':'(0,0,0,0,CW13,0,0,0,0,0,0)';$S;
    'GND67':'(0,0,0,0,CW22,0,0,0,0,0,0)';$S;
    'GND68':'(0,0,0,0,CW32,0,0,0,0,0,0)';$S;
    'GND69':'(0,0,0,0,CW4,0,0,0,0,0,0)';$S;
    'GND70':'(0,0,0,0,CY2,0,0,0,0,0,0)';$S;
    'GND71':'(0,0,0,0,CY34,0,0,0,0,0,0)';$S;
    'GND72':'(0,0,0,0,DA1,0,0,0,0,0,0)';$S;
    'GND73':'(0,0,0,0,DA35,0,0,0,0,0,0)';$S;
    'GND74':'(0,0,0,0,DF13,0,0,0,0,0,0)';$S;
    'GND75':'(0,0,0,0,DF22,0,0,0,0,0,0)';$S;
    'GND76':'(0,0,0,0,DF32,0,0,0,0,0,0)';$S;
    'GND77':'(0,0,0,0,DF4,0,0,0,0,0,0)';$S;
    'GND78':'(0,0,0,0,DG2,0,0,0,0,0,0)';$S;
    'GND79':'(0,0,0,0,DG34,0,0,0,0,0,0)';$S;
    'GND80':'(0,0,0,0,DH1,0,0,0,0,0,0)';$S;
    'GND81':'(0,0,0,0,DH35,0,0,0,0,0,0)';$S;
    'GND82':'(0,0,0,0,DN13,0,0,0,0,0,0)';$S;
    'NCF_GND1':'(0,0,0,0,A1,0,0,0,0,0,0)';$S;
    'NCF_GND2':'(0,0,0,0,A35,0,0,0,0,0,0)';$S;
    'NCF_GND3':'(0,0,0,0,C2,0,0,0,0,0,0)';$S;
    'NCF_GND4':'(0,0,0,0,C34,0,0,0,0,0,0)';$S;
    'NCF_GND5':'(0,0,0,0,D1,0,0,0,0,0,0)';$S;
    'NCF_GND6':'(0,0,0,0,D35,0,0,0,0,0,0)';$S;
    'NCF_GND7':'(0,0,0,0,FE2,0,0,0,0,0,0)';$S;
    'NCF_GND8':'(0,0,0,0,FE34,0,0,0,0,0,0)';$S;
    'NCF_GND9':'(0,0,0,0,FG1,0,0,0,0,0,0)';$S;
    'NCF_GND10':'(0,0,0,0,FG35,0,0,0,0,0,0)';$S;
    'NCF_GND11':'(0,0,0,0,FH2,0,0,0,0,0,0)';$S;
    'NCF_GND12':'(0,0,0,0,FH34,0,0,0,0,0,0)';$S;
    'GND83':'(0,0,0,0,DN22,0,0,0,0,0,0)';$S;
    'GND84':'(0,0,0,0,DN32,0,0,0,0,0,0)';$S;
    'GND85':'(0,0,0,0,DN4,0,0,0,0,0,0)';$S;
    'GND86':'(0,0,0,0,DP2,0,0,0,0,0,0)';$S;
    'GND87':'(0,0,0,0,DP34,0,0,0,0,0,0)';$S;
    'GND88':'(0,0,0,0,DR1,0,0,0,0,0,0)';$S;
    'GND89':'(0,0,0,0,DR35,0,0,0,0,0,0)';$S;
    'GND90':'(0,0,0,0,DY13,0,0,0,0,0,0)';$S;
    'GND91':'(0,0,0,0,DY22,0,0,0,0,0,0)';$S;
    'GND92':'(0,0,0,0,DY32,0,0,0,0,0,0)';$S;
    'GND93':'(0,0,0,0,DY4,0,0,0,0,0,0)';$S;
    'GND94':'(0,0,0,0,E14,0,0,0,0,0,0)';$S;
    'GND95':'(0,0,0,0,E27,0,0,0,0,0,0)';$S;
    'GND96':'(0,0,0,0,E33,0,0,0,0,0,0)';$S;
    'GND97':'(0,0,0,0,EA2,0,0,0,0,0,0)';$S;
    'GND98':'(0,0,0,0,EA34,0,0,0,0,0,0)';$S;
    'GND99':'(0,0,0,0,EB1,0,0,0,0,0,0)';$S;
    'GND100':'(0,0,0,0,EB35,0,0,0,0,0,0)';$S;
    'GND101':'(0,0,0,0,EG13,0,0,0,0,0,0)';$S;
    'GND102':'(0,0,0,0,EG22,0,0,0,0,0,0)';$S;
    'GND103':'(0,0,0,0,EG32,0,0,0,0,0,0)';$S;
    'GND104':'(0,0,0,0,EG4,0,0,0,0,0,0)';$S;
    'GND105':'(0,0,0,0,EH2,0,0,0,0,0,0)';$S;
    'GND106':'(0,0,0,0,EH34,0,0,0,0,0,0)';$S;
    'GND107':'(0,0,0,0,EJ1,0,0,0,0,0,0)';$S;
    'GND108':'(0,0,0,0,EJ35,0,0,0,0,0,0)';$S;
    'GND109':'(0,0,0,0,EP13,0,0,0,0,0,0)';$S;
    'GND110':'(0,0,0,0,EP22,0,0,0,0,0,0)';$S;
    'GND111':'(0,0,0,0,EP32,0,0,0,0,0,0)';$S;
    'GND112':'(0,0,0,0,EP4,0,0,0,0,0,0)';$S;
    'GND113':'(0,0,0,0,ER2,0,0,0,0,0,0)';$S;
    'GND114':'(0,0,0,0,ER34,0,0,0,0,0,0)';$S;
    'GND115':'(0,0,0,0,ET1,0,0,0,0,0,0)';$S;
    'GND116':'(0,0,0,0,ET35,0,0,0,0,0,0)';$S;
    'GND117':'(0,0,0,0,FA15,0,0,0,0,0,0)';$S;
    'GND118':'(0,0,0,0,FA32,0,0,0,0,0,0)';$S;
    'GND119':'(0,0,0,0,FB2,0,0,0,0,0,0)';$S;
    'GND120':'(0,0,0,0,FB34,0,0,0,0,0,0)';$S;
    'GND121':'(0,0,0,0,FC19,0,0,0,0,0,0)';$S;
    'GND122':'(0,0,0,0,FC23,0,0,0,0,0,0)';$S;
    'GND123':'(0,0,0,0,FC25,0,0,0,0,0,0)';$S;
    'GND124':'(0,0,0,0,FC28,0,0,0,0,0,0)';$S;
    'GND125':'(0,0,0,0,FC3,0,0,0,0,0,0)';$S;
    'GND126':'(0,0,0,0,FC6,0,0,0,0,0,0)';$S;
    'GND127':'(0,0,0,0,FC9,0,0,0,0,0,0)';$S;
    'GND128':'(0,0,0,0,FD1,0,0,0,0,0,0)';$S;
    'GND129':'(0,0,0,0,FD35,0,0,0,0,0,0)';$S;
    'GND130':'(0,0,0,0,FF14,0,0,0,0,0,0)';$S;
    'GND131':'(0,0,0,0,FF21,0,0,0,0,0,0)';$S;
    'GND132':'(0,0,0,0,FJ12,0,0,0,0,0,0)';$S;
    'GND133':'(0,0,0,0,FJ19,0,0,0,0,0,0)';$S;
    'GND134':'(0,0,0,0,H12,0,0,0,0,0,0)';$S;
    'GND135':'(0,0,0,0,H16,0,0,0,0,0,0)';$S;
    'GND136':'(0,0,0,0,H19,0,0,0,0,0,0)';$S;
    'GND137':'(0,0,0,0,H31,0,0,0,0,0,0)';$S;
    'GND138':'(0,0,0,0,J22,0,0,0,0,0,0)';$S;
    'GND139':'(0,0,0,0,J4,0,0,0,0,0,0)';$S;
    'GND140':'(0,0,0,0,K2,0,0,0,0,0,0)';$S;
    'GND141':'(0,0,0,0,K34,0,0,0,0,0,0)';$S;
    'GND142':'(0,0,0,0,L1,0,0,0,0,0,0)';$S;
    'GND143':'(0,0,0,0,L35,0,0,0,0,0,0)';$S;
    'GND144':'(0,0,0,0,T13,0,0,0,0,0,0)';$S;
    'GND145':'(0,0,0,0,T22,0,0,0,0,0,0)';$S;
    'GND146':'(0,0,0,0,T32,0,0,0,0,0,0)';$S;
    'GND147':'(0,0,0,0,T4,0,0,0,0,0,0)';$S;
    'GND148':'(0,0,0,0,U2,0,0,0,0,0,0)';$S;
    'GND149':'(0,0,0,0,U34,0,0,0,0,0,0)';$S;
    'GND150':'(0,0,0,0,V1,0,0,0,0,0,0)';$S;
    'GND151':'(0,0,0,0,V35,0,0,0,0,0,0)';$S;
    'A_PETP0':'(0,0,0,0,0,M26,0,0,0,0,0)';$S;OUT;
    'A_PETN0':'(0,0,0,0,0,P29,0,0,0,0,0)';$S;OUT;
    'A_PETP1':'(0,0,0,0,0,W26,0,0,0,0,0)';$S;OUT;
    'A_PETN1':'(0,0,0,0,0,AA29,0,0,0,0,0)';$S;OUT;
    'A_PETP2':'(0,0,0,0,0,AF26,0,0,0,0,0)';$S;OUT;
    'A_PETN2':'(0,0,0,0,0,AH29,0,0,0,0,0)';$S;OUT;
    'A_PETP3':'(0,0,0,0,0,AN26,0,0,0,0,0)';$S;OUT;
    'A_PETN3':'(0,0,0,0,0,AR29,0,0,0,0,0)';$S;OUT;
    'A_PETP4':'(0,0,0,0,0,AY26,0,0,0,0,0)';$S;OUT;
    'A_PETN4':'(0,0,0,0,0,BB29,0,0,0,0,0)';$S;OUT;
    'A_PETP5':'(0,0,0,0,0,BG26,0,0,0,0,0)';$S;OUT;
    'A_PETN5':'(0,0,0,0,0,BJ29,0,0,0,0,0)';$S;OUT;
    'A_PETP6':'(0,0,0,0,0,BP26,0,0,0,0,0)';$S;OUT;
    'A_PETN6':'(0,0,0,0,0,BT29,0,0,0,0,0)';$S;OUT;
    'A_PETP7':'(0,0,0,0,0,CA26,0,0,0,0,0)';$S;OUT;
    'A_PETN7':'(0,0,0,0,0,CC29,0,0,0,0,0)';$S;OUT;
    'A_PETP8':'(0,0,0,0,0,0,CH26,0,0,0,0)';$S;OUT;
    'A_PETN8':'(0,0,0,0,0,0,CK29,0,0,0,0)';$S;OUT;
    'A_PETP9':'(0,0,0,0,0,0,CR26,0,0,0,0)';$S;OUT;
    'A_PETN9':'(0,0,0,0,0,0,CU29,0,0,0,0)';$S;OUT;
    'A_PETP10':'(0,0,0,0,0,0,DB26,0,0,0,0)';$S;OUT;
    'A_PETN10':'(0,0,0,0,0,0,DD29,0,0,0,0)';$S;OUT;
    'A_PETP11':'(0,0,0,0,0,0,DJ26,0,0,0,0)';$S;OUT;
    'A_PETN11':'(0,0,0,0,0,0,DL29,0,0,0,0)';$S;OUT;
    'A_PETP12':'(0,0,0,0,0,0,DT26,0,0,0,0)';$S;OUT;
    'A_PETN12':'(0,0,0,0,0,0,DV29,0,0,0,0)';$S;OUT;
    'A_PETP13':'(0,0,0,0,0,0,EC26,0,0,0,0)';$S;OUT;
    'A_PETN13':'(0,0,0,0,0,0,EE29,0,0,0,0)';$S;OUT;
    'A_PETP14':'(0,0,0,0,0,0,EK26,0,0,0,0)';$S;OUT;
    'A_PETN14':'(0,0,0,0,0,0,EM29,0,0,0,0)';$S;OUT;
    'A_PETP15':'(0,0,0,0,0,0,EU26,0,0,0,0)';$S;OUT;
    'A_PETN15':'(0,0,0,0,0,0,EW29,0,0,0,0)';$S;OUT;
    'B_PERP0':'(0,0,0,0,0,0,0,N34,0,0,0)';$S;IN;
    'B_PERN0':'(0,0,0,0,0,0,0,R35,0,0,0)';$S;IN;
    'B_PERP1':'(0,0,0,0,0,0,0,Y34,0,0,0)';$S;IN;
    'B_PERN1':'(0,0,0,0,0,0,0,AB35,0,0,0)';$S;IN;
    'B_PERP2':'(0,0,0,0,0,0,0,AG34,0,0,0)';$S;IN;
    'B_PERN2':'(0,0,0,0,0,0,0,AJ35,0,0,0)';$S;IN;
    'B_PERP3':'(0,0,0,0,0,0,0,AP34,0,0,0)';$S;IN;
    'B_PERN3':'(0,0,0,0,0,0,0,AT35,0,0,0)';$S;IN;
    'B_PERP4':'(0,0,0,0,0,0,0,BA34,0,0,0)';$S;IN;
    'B_PERN4':'(0,0,0,0,0,0,0,BC35,0,0,0)';$S;IN;
    'B_PERP5':'(0,0,0,0,0,0,0,BH34,0,0,0)';$S;IN;
    'B_PERN5':'(0,0,0,0,0,0,0,BK35,0,0,0)';$S;IN;
    'B_PERP6':'(0,0,0,0,0,0,0,BR34,0,0,0)';$S;IN;
    'B_PERN6':'(0,0,0,0,0,0,0,BU35,0,0,0)';$S;IN;
    'B_PERP7':'(0,0,0,0,0,0,0,CB34,0,0,0)';$S;IN;
    'B_PERN7':'(0,0,0,0,0,0,0,CD35,0,0,0)';$S;IN;
    'B_PERP8':'(0,0,0,0,0,0,0,0,CJ34,0,0)';$S;IN;
    'B_PERN8':'(0,0,0,0,0,0,0,0,CL35,0,0)';$S;IN;
    'B_PERP9':'(0,0,0,0,0,0,0,0,CT34,0,0)';$S;IN;
    'B_PERN9':'(0,0,0,0,0,0,0,0,CV35,0,0)';$S;IN;
    'B_PERP10':'(0,0,0,0,0,0,0,0,DC34,0,0)';$S;IN;
    'B_PERN10':'(0,0,0,0,0,0,0,0,DE35,0,0)';$S;IN;
    'B_PERP11':'(0,0,0,0,0,0,0,0,DK34,0,0)';$S;IN;
    'B_PERN11':'(0,0,0,0,0,0,0,0,DM35,0,0)';$S;IN;
    'B_PERP12':'(0,0,0,0,0,0,0,0,DU34,0,0)';$S;IN;
    'B_PERN12':'(0,0,0,0,0,0,0,0,DW35,0,0)';$S;IN;
    'B_PERP13':'(0,0,0,0,0,0,0,0,ED34,0,0)';$S;IN;
    'B_PERN13':'(0,0,0,0,0,0,0,0,EF35,0,0)';$S;IN;
    'B_PERP14':'(0,0,0,0,0,0,0,0,EL34,0,0)';$S;IN;
    'B_PERN14':'(0,0,0,0,0,0,0,0,EN35,0,0)';$S;IN;
    'B_PERP15':'(0,0,0,0,0,0,0,0,EV34,0,0)';$S;IN;
    'B_PERN15':'(0,0,0,0,0,0,0,0,EY35,0,0)';$S;IN;
    'B_PETP0':'(0,0,0,0,0,0,0,0,0,M7,0)';$S;OUT;
    'B_PETN0':'(0,0,0,0,0,0,0,0,0,P10,0)';$S;OUT;
    'B_PETP1':'(0,0,0,0,0,0,0,0,0,W7,0)';$S;OUT;
    'B_PETN1':'(0,0,0,0,0,0,0,0,0,AA10,0)';$S;OUT;
    'B_PETP2':'(0,0,0,0,0,0,0,0,0,AF7,0)';$S;OUT;
    'B_PETN2':'(0,0,0,0,0,0,0,0,0,AH10,0)';$S;OUT;
    'B_PETP3':'(0,0,0,0,0,0,0,0,0,AN7,0)';$S;OUT;
    'B_PETN3':'(0,0,0,0,0,0,0,0,0,AR10,0)';$S;OUT;
    'B_PETP4':'(0,0,0,0,0,0,0,0,0,AY7,0)';$S;OUT;
    'B_PETN4':'(0,0,0,0,0,0,0,0,0,BB10,0)';$S;OUT;
    'B_PETP5':'(0,0,0,0,0,0,0,0,0,BG7,0)';$S;OUT;
    'B_PETN5':'(0,0,0,0,0,0,0,0,0,BJ10,0)';$S;OUT;
    'B_PETP6':'(0,0,0,0,0,0,0,0,0,BP7,0)';$S;OUT;
    'B_PETN6':'(0,0,0,0,0,0,0,0,0,BT10,0)';$S;OUT;
    'B_PETP7':'(0,0,0,0,0,0,0,0,0,CA7,0)';$S;OUT;
    'B_PETN7':'(0,0,0,0,0,0,0,0,0,CC10,0)';$S;OUT;
    'B_PETP8':'(0,0,0,0,0,0,0,0,0,0,CH7)';$S;OUT;
    'B_PETN8':'(0,0,0,0,0,0,0,0,0,0,CK10)';$S;OUT;
    'B_PETP9':'(0,0,0,0,0,0,0,0,0,0,CR7)';$S;OUT;
    'B_PETN9':'(0,0,0,0,0,0,0,0,0,0,CU10)';$S;OUT;
    'B_PETP10':'(0,0,0,0,0,0,0,0,0,0,DB7)';$S;OUT;
    'B_PETN10':'(0,0,0,0,0,0,0,0,0,0,DD10)';$S;OUT;
    'B_PETP11':'(0,0,0,0,0,0,0,0,0,0,DJ7)';$S;OUT;
    'B_PETN11':'(0,0,0,0,0,0,0,0,0,0,DL10)';$S;OUT;
    'B_PETP12':'(0,0,0,0,0,0,0,0,0,0,DT7)';$S;OUT;
    'B_PETN12':'(0,0,0,0,0,0,0,0,0,0,DV10)';$S;OUT;
    'B_PETP13':'(0,0,0,0,0,0,0,0,0,0,EC7)';$S;OUT;
    'B_PETN13':'(0,0,0,0,0,0,0,0,0,0,EE10)';$S;OUT;
    'B_PETP14':'(0,0,0,0,0,0,0,0,0,0,EK7)';$S;OUT;
    'B_PETN14':'(0,0,0,0,0,0,0,0,0,0,EM10)';$S;OUT;
    'B_PETP15':'(0,0,0,0,0,0,0,0,0,0,EU7)';$S;OUT;
    'B_PETN15':'(0,0,0,0,0,0,0,0,0,0,EW10)';$S;OUT;
end_primitive;
primitive 'Q_CAPP_SMLF-100UF,16V,20%,OSCON,CC71003MZ30';body 'Q_CAPP';
    'A':'(1)';
    'B':'(2)';
end_primitive;
primitive 'Q_CAPP_SMLF-220UF,4V,20%,SPCAP,CH122KM8801';body 'Q_CAPP';
    'A':'(1)';
    'B':'(2)';
end_primitive;
primitive 'Q_CAPP_SMLF-220UF,6.3V,20%,ALUM,CC72201MZ28';body 'Q_CAPP';
    'A':'(1)';
    'B':'(2)';
end_primitive;
primitive 'Q_CAPP_SMLF-270UF,16V,20%,OSCON,CC72703MZ11';body 'Q_CAPP';
    'A':'(1)';
    'B':'(2)';
end_primitive;
primitive 'Q_CAPP_SMLF-390UF,2.5V,20%,ALUM,CC7390JMZ13';body 'Q_CAPP';
    'A':'(1)';
    'B':'(2)';
end_primitive;
primitive 'Q_CAPP_SMLF-470UF,2.5V,20%,EMPTY,CH747LM8825';body 'Q_CAPP';
    'A':'(1)';
    'B':'(2)';
end_primitive;
primitive 'Q_CAPP_SMLF-470UF,2.5V,20%,SPCAP,CH747LM8818';body 'Q_CAPP';
    'A':'(1)';
    'B':'(2)';
end_primitive;
primitive 'Q_CAPP_SMLF-470UF,2.5V,20%,SPCAP,CH747LM8825';body 'Q_CAPP';
    'A':'(1)';
    'B':'(2)';
end_primitive;
primitive 'Q_CAPP_THLF-270UF,16V,20%,OSCON,CC72703MD38';body 'Q_CAPP';
    'A':'(1)';
    'B':'(2)';
end_primitive;
primitive 'Q_CAPP_THLF-560UF,6.3V,20%,OSCON,CC75601MD16';body 'Q_CAPP';
    'A':'(1)';
    'B':'(2)';
end_primitive;
primitive 'Q_CAP_0201-1UF,4V,20%,X6S,CH-10KMEE00';body 'Q_CAP';
    'A':'(1)';
    'B':'(2)';
end_primitive;
primitive 'Q_CAP_0402-0.022UF,25V,10%,X7R,CH3224K1B01';body 'Q_CAP';
    'A':'(1)';
    'B':'(2)';
end_primitive;
primitive 'Q_CAP_0402-0.068UF,16V,10%,X7R,CH3683K1B09';body 'Q_CAP';
    'A':'(1)';
    'B':'(2)';
end_primitive;
primitive 'Q_CAP_0402-0.1UF,25V,10%,EMPTY,CH4104K1B00';body 'Q_CAP';
    'A':'(1)';
    'B':'(2)';
end_primitive;
primitive 'Q_CAP_0402-0.1UF,25V,10%,X7R,CH4104K1B00';body 'Q_CAP';
    'A':'(1)';
    'B':'(2)';
end_primitive;
primitive 'Q_CAP_0402-0.22UF,16V,10%,X7R,CH4223K1B00';body 'Q_CAP';
    'A':'(1)';
    'B':'(2)';
end_primitive;
primitive 'Q_CAP_0402-1000PF,50V,5%,EMPTY,TMP_QCH21006JB10';body 'Q_CAP';
    'A':'(1)';
    'B':'(2)';
end_primitive;
primitive 'Q_CAP_0402-1000PF,50V,5%,X7R,TMP_QCH21006JB10';body 'Q_CAP';
    'A':'(1)';
    'B':'(2)';
end_primitive;
primitive 'Q_CAP_0402-100PF,50V,5%,EMPTY,CH11006JB18';body 'Q_CAP';
    'A':'(1)';
    'B':'(2)';
end_primitive;
primitive 'Q_CAP_0402-100PF,50V,5%,NPO,CH11006JB00';body 'Q_CAP';
    'A':'(1)';
    'B':'(2)';
end_primitive;
primitive 'Q_CAP_0402-100PF,50V,5%,X7R,CH11006JB18';body 'Q_CAP';
    'A':'(1)';
    'B':'(2)';
end_primitive;
primitive 'Q_CAP_0402-10PF,50V,1%,NPO,TMP_QCH0106F0B00';body 'Q_CAP';
    'A':'(1)';
    'B':'(2)';
end_primitive;
primitive 'Q_CAP_0402-10PF,50V,5%,EMPTY,CH01006JB08';body 'Q_CAP';
    'A':'(1)';
    'B':'(2)';
end_primitive;
primitive 'Q_CAP_0402-150PF,50V,5%,NPO,TMP_QCH11506JB08';body 'Q_CAP';
    'A':'(1)';
    'B':'(2)';
end_primitive;
primitive 'Q_CAP_0402-15PF,50V,5%,C0G,CH01506JB06';body 'Q_CAP';
    'A':'(1)';
    'B':'(2)';
end_primitive;
primitive 'Q_CAP_0402-1NF,50V,10%,EMPTY,CH21006KB16';body 'Q_CAP';
    'A':'(1)';
    'B':'(2)';
end_primitive;
primitive 'Q_CAP_0402-1UF,6.3V,10%,X7R,CH5101K1B01';body 'Q_CAP';
    'A':'(1)';
    'B':'(2)';
end_primitive;
primitive 'Q_CAP_0402-220PF,50V,10%,EMPTY,TMP_QCH12206KB14';body 'Q_CAP';
    'A':'(1)';
    'B':'(2)';
end_primitive;
primitive 'Q_CAP_0402-220PF,50V,10%,X7R,TMP_QCH12206KB14';body 'Q_CAP';
    'A':'(1)';
    'B':'(2)';
end_primitive;
primitive 'Q_CAP_0402-27PF,50V,5%,NPO,CH02706JB06';body 'Q_CAP';
    'A':'(1)';
    'B':'(2)';
end_primitive;
primitive 'Q_CAP_0402-3300PF,50V,10%,X7R,TMP_QCH2336K1B12';body 'Q_CAP';
    'A':'(1)';
    'B':'(2)';
end_primitive;
primitive 'Q_CAP_0402-330PF,50V,10%,X7R,CH1336K1B02';body 'Q_CAP';
    'A':'(1)';
    'B':'(2)';
end_primitive;
primitive 'Q_CAP_0402-33PF,50V,5%,NPO,TMP_QCH03306JB04';body 'Q_CAP';
    'A':'(1)';
    'B':'(2)';
end_primitive;
primitive 'Q_CAP_0402-39PF,50V,5%,NPO,CH03906JB06';body 'Q_CAP';
    'A':'(1)';
    'B':'(2)';
end_primitive;
primitive 'Q_CAP_0402-4.7UF,6.3V,20%,X6S,CH5471MEB01';body 'Q_CAP';
    'A':'(1)';
    'B':'(2)';
end_primitive;
primitive 'Q_CAP_0402-470PF,50V,10%,X7R,TMP_QCH14706KB18';body 'Q_CAP';
    'A':'(1)';
    'B':'(2)';
end_primitive;
primitive 'Q_CAP_0402-47PF,50V,5%,NPO,TMP_QCH04706JB01';body 'Q_CAP';
    'A':'(1)';
    'B':'(2)';
end_primitive;
primitive 'Q_CAP_0603-1000PF,50V,10%,X7R,TMP_QCH21006K917';body 'Q_CAP';
    'A':'(1)';
    'B':'(2)';
end_primitive;
primitive 'Q_CAP_0603-1UF,16V,10%,X7R,TMP_QCH5103K1900';body 'Q_CAP';
    'A':'(1)';
    'B':'(2)';
end_primitive;
primitive 'Q_CAP_C0201-0.1UF,10V,10%,X7S,CH4102K6E00';body 'Q_CAP';
    'A':'(1)';
    'B':'(2)';
end_primitive;
primitive 'Q_CAP_C0402-0.001UF,50V,10%,EMPTY,CH30106KB19';body 'Q_CAP';
    'A':'(1)';
    'B':'(2)';
end_primitive;
primitive 'Q_CAP_C0402-0.001UF,50V,10%,X7R,CH30106KB19';body 'Q_CAP';
    'A':'(1)';
    'B':'(2)';
end_primitive;
primitive 'Q_CAP_C0402-0.01UF,25V,10%,EMPTY,CH3104K1B11';body 'Q_CAP';
    'A':'(1)';
    'B':'(2)';
end_primitive;
primitive 'Q_CAP_C0402-0.01UF,50V,10%,EMPTY,CH31006KB18';body 'Q_CAP';
    'A':'(1)';
    'B':'(2)';
end_primitive;
primitive 'Q_CAP_C0402-0.01UF,50V,10%,X7R,CH31006KB18';body 'Q_CAP';
    'A':'(1)';
    'B':'(2)';
end_primitive;
primitive 'Q_CAP_C0402-0.047UF,25V,10%,X7R,CH3474K1B04';body 'Q_CAP';
    'A':'(1)';
    'B':'(2)';
end_primitive;
primitive 'Q_CAP_C0402-0.1UF,16V,10%,X7R,CH4103K1B08';body 'Q_CAP';
    'A':'(1)';
    'B':'(2)';
end_primitive;
primitive 'Q_CAP_C0402-0.1UF,25V,10%,EMPTY,CH4104KEB00';body 'Q_CAP';
    'A':'(1)';
    'B':'(2)';
end_primitive;
primitive 'Q_CAP_C0402-0.1UF,25V,10%,X6S,CH4104KEB00';body 'Q_CAP';
    'A':'(1)';
    'B':'(2)';
end_primitive;
primitive 'Q_CAP_C0402-0.22UF,25V,10%,X7R,CH4224K1B01';body 'Q_CAP';
    'A':'(1)';
    'B':'(2)';
end_primitive;
primitive 'Q_CAP_C0402-100NF,50V,10%,EMPTY,CH4106K1B01';body 'Q_CAP';
    'A':'(1)';
    'B':'(2)';
end_primitive;
primitive 'Q_CAP_C0402-100NF,50V,10%,X7R,CH4106K1B01';body 'Q_CAP';
    'A':'(1)';
    'B':'(2)';
end_primitive;
primitive 'Q_CAP_C0402-10UF,6.3V,20%,EMPTY,CH6101MEB01';body 'Q_CAP';
    'A':'(1)';
    'B':'(2)';
end_primitive;
primitive 'Q_CAP_C0402-10UF,6.3V,20%,X6S,CH6101MEB01';body 'Q_CAP';
    'A':'(1)';
    'B':'(2)';
end_primitive;
primitive 'Q_CAP_C0402-10UF,6.3V,20%,X6S,CH6101MEB03';body 'Q_CAP';
    'A':'(1)';
    'B':'(2)';
end_primitive;
primitive 'Q_CAP_C0402-12PF,50V,5%,C0G,CH01206JB05';body 'Q_CAP';
    'A':'(1)';
    'B':'(2)';
end_primitive;
primitive 'Q_CAP_C0402-1PF,50V,0.05P,COG,CH-106T0B00';body 'Q_CAP';
    'A':'(1)';
    'B':'(2)';
end_primitive;
primitive 'Q_CAP_C0402-1UF,16V,10%,X6S,CH5103KEB01';body 'Q_CAP';
    'A':'(1)';
    'B':'(2)';
end_primitive;
primitive 'Q_CAP_C0402-1UF,25V,10%,EMPTY,CH5104KEB02';body 'Q_CAP';
    'A':'(1)';
    'B':'(2)';
end_primitive;
primitive 'Q_CAP_C0402-1UF,25V,10%,X6S,CH5104KEB02';body 'Q_CAP';
    'A':'(1)';
    'B':'(2)';
end_primitive;
primitive 'Q_CAP_C0402-2.2UF,10V,10%,X6S,CH5222KEB01';body 'Q_CAP';
    'A':'(1)';
    'B':'(2)';
end_primitive;
primitive 'Q_CAP_C0402-2.7PF,50V,0.1PF,NPO,CH-276B0B00';body 'Q_CAP';
    'A':'(1)';
    'B':'(2)';
end_primitive;
primitive 'Q_CAP_C0402-220PF,50V,5%,C0G,CH12206JB00';body 'Q_CAP';
    'A':'(1)';
    'B':'(2)';
end_primitive;
primitive 'Q_CAP_C0402-22UF,4V,20%,X6S,CH622KMEB02';body 'Q_CAP';
    'A':'(1)';
    'B':'(2)';
end_primitive;
primitive 'Q_CAP_C0402-3.9P,50V,0.1P,NPO,CH-3916TB01';body 'Q_CAP';
    'A':'(1)';
    'B':'(2)';
end_primitive;
primitive 'Q_CAP_C0402-33NF,25V,10%,EMPTY,CH3334K1B00';body 'Q_CAP';
    'A':'(1)';
    'B':'(2)';
end_primitive;
primitive 'Q_CAP_C0402-3900PF,50V,10%,X7R,CH23906KB14';body 'Q_CAP';
    'A':'(1)';
    'B':'(2)';
end_primitive;
primitive 'Q_CAP_C0402-4.7PF,50V,0.1P,NPO,CH-4716TB06';body 'Q_CAP';
    'A':'(1)';
    'B':'(2)';
end_primitive;
primitive 'Q_CAP_C0402-560PF,50V,10%,EMPTY,CH1566K1B09';body 'Q_CAP';
    'A':'(1)';
    'B':'(2)';
end_primitive;
primitive 'Q_CAP_C0402-560PF,50V,10%,X7R,CH1566K1B09';body 'Q_CAP';
    'A':'(1)';
    'B':'(2)';
end_primitive;
primitive 'Q_CAP_C0402-6800PF,50V,10%,X7R,CH2686K1B01';body 'Q_CAP';
    'A':'(1)';
    'B':'(2)';
end_primitive;
primitive 'Q_CAP_C0402-8.2PF,50V,0.1P,NP0,CH-8216TB09';body 'Q_CAP';
    'A':'(1)';
    'B':'(2)';
end_primitive;
primitive 'Q_CAP_C0603-2.2UF,16V,10%,X6S,CH5223KE901';body 'Q_CAP';
    'A':'(1)';
    'B':'(2)';
end_primitive;
primitive 'Q_CAP_C0603-2.2UF,16V,20%,X7R,CH5223M1900';body 'Q_CAP';
    'A':'(1)';
    'B':'(2)';
end_primitive;
primitive 'Q_CAP_C0603-22UF,6.3V,20%,X6S,CH6221ME900';body 'Q_CAP';
    'A':'(1)';
    'B':'(2)';
end_primitive;
primitive 'Q_CAP_C0603-4.7UF,16V,10%,X6S,CH5473KE902';body 'Q_CAP';
    'A':'(1)';
    'B':'(2)';
end_primitive;
primitive 'Q_CAP_C0805-100UF,4V,20%,X6S,CH710KMEA01';body 'Q_CAP';
    'A':'(1)';
    'B':'(2)';
end_primitive;
primitive 'Q_CAP_C0805-10UF,16V,10%,EMPTY,CH6103KEA00';body 'Q_CAP';
    'A':'(1)';
    'B':'(2)';
end_primitive;
primitive 'Q_CAP_C0805-10UF,16V,10%,X6S,CH6103KEA00';body 'Q_CAP';
    'A':'(1)';
    'B':'(2)';
end_primitive;
primitive 'Q_CAP_C0805-10UF,16V,10%,X6S,CH6103KEA01';body 'Q_CAP';
    'A':'(1)';
    'B':'(2)';
end_primitive;
primitive 'Q_CAP_C0805-10UF,25V,10%,X6S,CH6104KEA00';body 'Q_CAP';
    'A':'(1)';
    'B':'(2)';
end_primitive;
primitive 'Q_CAP_C0805-22UF,10V,20%,X6S,CH6222MEA01';body 'Q_CAP';
    'A':'(1)';
    'B':'(2)';
end_primitive;
primitive 'Q_CAP_C0805-22UF,16V,20%,EMPTY,CH6223MEA00';body 'Q_CAP';
    'A':'(1)';
    'B':'(2)';
end_primitive;
primitive 'Q_CAP_C0805-22UF,16V,20%,X6S,CH6223MEA00';body 'Q_CAP';
    'A':'(1)';
    'B':'(2)';
end_primitive;
primitive 'Q_CAP_C0805-22UF,16V,20%,X6S,CH6223MEA01';body 'Q_CAP';
    'A':'(1)';
    'B':'(2)';
end_primitive;
primitive 'Q_CAP_C0805-22UF,4V,20%,EMPTY,CH622KMEA03';body 'Q_CAP';
    'A':'(1)';
    'B':'(2)';
end_primitive;
primitive 'Q_CAP_C0805-22UF,4V,20%,X6S,CH622KMEA03';body 'Q_CAP';
    'A':'(1)';
    'B':'(2)';
end_primitive;
primitive 'Q_CAP_C0805-47UF,4V,20%,X6S,CH647KMEA04';body 'Q_CAP';
    'A':'(1)';
    'B':'(2)';
end_primitive;
primitive 'Q_CAP_DIFFBUS_C0201-DIFF BUS_0.22UF,6.3V,20%,X6S,SA';body 'Q_CAP_DIFFBUS';
    '1':'(1)';BIDI;
    '2':'(2)';BIDI;
end_primitive;
primitive 'Q_CAP_DIFFBUS_C0402-DIFF BUS_0.33UF,6.3V,10%,X6S,SA';body 'Q_CAP_DIFFBUS';
    '1':'(1)';BIDI;
    '2':'(2)';BIDI;
end_primitive;
primitive 'Q_CRYSTAL_SMLF-32.768KHZ,EMPTY,BG632768012';body 'Q_CRYSTAL';
    '1':'(1)';BIDI;
    '2':'(2)';BIDI;
end_primitive;
primitive 'Q_CRYSTAL_SMLF-32.768KHZ,IC,BG632768012';body 'Q_CRYSTAL';
    '1':'(1)';BIDI;
    '2':'(2)';BIDI;
end_primitive;
primitive 'Q_FUSE_SMLF-20A/125V,IC,DKK00XFU000';body 'Q_FUSE';
    '1':'(1)';BIDI;
    '2':'(2)';BIDI;
end_primitive;
primitive 'Q_INDUCTOR4P_14-150NH,SMLF,IND,CV+15^0TZ04';body 'Q_INDUCTOR4P_14';
    '2':'(2)';BIDI;
    '3':'(3)';BIDI;
    '4':'(4)';BIDI;
    '1':'(1)';BIDI;
end_primitive;
primitive 'Q_INDUCTOR_SMLF-0.22UH/33A,IND,CV+22Y0EZ00';body 'Q_INDUCTOR';
    '2':'(2)';BIDI;
    '1':'(1)';BIDI;
end_primitive;
primitive 'Q_INDUCTOR_SMLF-1.0UH/18A,IND,CV-10I0MZ01';body 'Q_INDUCTOR';
    '2':'(2)';BIDI;
    '1':'(1)';BIDI;
end_primitive;
primitive 'Q_INDUCTOR_SMLF-1.5UH,IND,CV-15I0MZ28';body 'Q_INDUCTOR';
    '2':'(2)';BIDI;
    '1':'(1)';BIDI;
end_primitive;
primitive 'Q_INDUCTOR_SMLF-1.5UH/53A,IND,CV-15^0MZ02';body 'Q_INDUCTOR';
    '2':'(2)';BIDI;
    '1':'(1)';BIDI;
end_primitive;
primitive 'Q_INDUCTOR_SMLF-100NH/16A,IND,CV+10G0MZ04';body 'Q_INDUCTOR';
    '2':'(2)';BIDI;
    '1':'(1)';BIDI;
end_primitive;
primitive 'Q_INDUCTOR_SMLF-120NH/69A,IND,CV+12^0EZ03';body 'Q_INDUCTOR';
    '2':'(2)';BIDI;
    '1':'(1)';BIDI;
end_primitive;
primitive 'Q_INDUCTOR_SMLF-1UH,IND,CV-10U0MZ01';body 'Q_INDUCTOR';
    '2':'(2)';BIDI;
    '1':'(1)';BIDI;
end_primitive;
primitive 'Q_INDUCTOR_SMLF-2.2UH,IND,CV-2280MZ15';body 'Q_INDUCTOR';
    '2':'(2)';BIDI;
    '1':'(1)';BIDI;
end_primitive;
primitive 'Q_INDUCTOR_SMLF-3.3UH/6A,IND,CV-3360MZ07';body 'Q_INDUCTOR';
    '2':'(2)';BIDI;
    '1':'(1)';BIDI;
end_primitive;
primitive 'Q_INDUCTOR_SMLF-4.7UH,IND,CV-47A0MZ10';body 'Q_INDUCTOR';
    '2':'(2)';BIDI;
    '1':'(1)';BIDI;
end_primitive;
primitive 'Q_INDUCTOR_SMLF-50NH/86A,IND,CVA50^0MZ09';body 'Q_INDUCTOR';
    '2':'(2)';BIDI;
    '1':'(1)';BIDI;
end_primitive;
primitive 'Q_INDUCTOR_SMLF-90NH/155A,IND,CVA90^0KZ13';body 'Q_INDUCTOR';
    '2':'(2)';BIDI;
    '1':'(1)';BIDI;
end_primitive;
primitive 'Q_INDUCTOR_SMLF-BLM15PD121SN1D/1300MA,IND,CX5PD121A';body 'Q_INDUCTOR';
    '2':'(2)';BIDI;
    '1':'(1)';BIDI;
end_primitive;
primitive 'Q_INDUCTOR_SMLF-BLM18PG300SN1D ,IND,TMP_QCX8PG3000A';body 'Q_INDUCTOR';
    '2':'(2)';BIDI;
    '1':'(1)';BIDI;
end_primitive;
primitive 'Q_INDUCTOR_SMLF-BLM18SN220TN1D/8000MA,IND,CX220TN1A';body 'Q_INDUCTOR';
    '2':'(2)';BIDI;
    '1':'(1)';BIDI;
end_primitive;
primitive 'Q_INDUCTOR_SMLF-BLM21PG221SN1D,IND,CX1PG221001';body 'Q_INDUCTOR';
    '2':'(2)';BIDI;
    '1':'(1)';BIDI;
end_primitive;
primitive 'Q_INDUCTOR_SMLF-BLM21SN300SN1D/5A,IND,CX300SN1000';body 'Q_INDUCTOR';
    '2':'(2)';BIDI;
    '1':'(1)';BIDI;
end_primitive;
primitive 'Q_INDUCTOR_SMLF-FCM2012KF-601T/0.5A,IND,CX601T05003';body 'Q_INDUCTOR';
    '2':'(2)';BIDI;
    '1':'(1)';BIDI;
end_primitive;
primitive 'Q_LED_SMLF-LED_BLUE,LTST-C281TBKT-5A,IC,BEBL0172Z00';body 'Q_LED';
    'A':'(A)';BIDI;
    'C':'(C)';BIDI;
end_primitive;
primitive 'Q_LED_SMLF-LED_YELLOW,LTST-C190KSKT-P,IC,BEYL0159ZA';body 'Q_LED';
    'A':'(A)';BIDI;
    'C':'(C)';BIDI;
end_primitive;
primitive 'Q_OSC4P_SMLF-50MHZ,OSC,BF650000032';body 'Q_OSC4P';
    'OE':'(1)';IN;
    'OUT':'(3)';OUT;
    'GND':'(2)';
    'VDD':'(4)';
end_primitive;
primitive 'Q_RES_0201LF-0,5%,1/20W,CHIP,CS00001JE10';body 'Q_RES';
    'A':'(1)';
    'B':'(2)';
end_primitive;
primitive 'Q_RES_0201LF-10K,1%,1/20W,CHIP,CS31001FE17';body 'Q_RES';
    'A':'(1)';
    'B':'(2)';
end_primitive;
primitive 'Q_RES_0201LF-1K,1%,1/20W,CHIP,CS21001FE07';body 'Q_RES';
    'A':'(1)';
    'B':'(2)';
end_primitive;
primitive 'Q_RES_0201LF-1K,1%,1/20W,EMPTY,CS21001FE07';body 'Q_RES';
    'A':'(1)';
    'B':'(2)';
end_primitive;
primitive 'Q_RES_0201LF-200,1%,1/20W,CHIP,CS12001FE12';body 'Q_RES';
    'A':'(1)';
    'B':'(2)';
end_primitive;
primitive 'Q_RES_0201LF-20K,1%,1/20W,CHIP,CS32001FE00';body 'Q_RES';
    'A':'(1)';
    'B':'(2)';
end_primitive;
primitive 'Q_RES_0201LF-22,1%,1/20W,CHIP,CS02201FE11';body 'Q_RES';
    'A':'(1)';
    'B':'(2)';
end_primitive;
primitive 'Q_RES_0201LF-33.2,1%,1/20W,CHIP,CS03321FE09';body 'Q_RES';
    'A':'(1)';
    'B':'(2)';
end_primitive;
primitive 'Q_RES_0201LF-4.7K,5%,1/20W,CHIP,CS24701JE04';body 'Q_RES';
    'A':'(1)';
    'B':'(2)';
end_primitive;
primitive 'Q_RES_0201LF-4.7K,5%,1/20W,EMPTY,CS24701JE04';body 'Q_RES';
    'A':'(1)';
    'B':'(2)';
end_primitive;
primitive 'Q_RES_0201LF-49.9,1%,1/20W,CHIP,CS04991FE06';body 'Q_RES';
    'A':'(1)';
    'B':'(2)';
end_primitive;
primitive 'Q_RES_0201LF-49.9,1%,1/20W,EMPTY,CS04991FE06';body 'Q_RES';
    'A':'(1)';
    'B':'(2)';
end_primitive;
primitive 'Q_RES_0201LF-51.1,1%,1/20W,EMPTY,CS05111FE00';body 'Q_RES';
    'A':'(1)';
    'B':'(2)';
end_primitive;
primitive 'Q_RES_0402LF-0,5%,1/16W,CHIP,CS00002JB13';body 'Q_RES';
    'A':'(1)';
    'B':'(2)';
end_primitive;
primitive 'Q_RES_0402LF-0,5%,1/16W,EMPTY,CS00002JB13';body 'Q_RES';
    'A':'(1)';
    'B':'(2)';
end_primitive;
primitive 'Q_RES_0402LF-1,1%,1/16W,CHIP,CS-1002FB04';body 'Q_RES';
    'A':'(1)';
    'B':'(2)';
end_primitive;
primitive 'Q_RES_0402LF-1.21K,1%,1/16W,CHIP,CS21212FB05';body 'Q_RES';
    'A':'(1)';
    'B':'(2)';
end_primitive;
primitive 'Q_RES_0402LF-1.33K,1%,1/16W,CHIP,CS21332FB05';body 'Q_RES';
    'A':'(1)';
    'B':'(2)';
end_primitive;
primitive 'Q_RES_0402LF-1.5,1%,1/8W,EMPTY,CS-1504FB00';body 'Q_RES';
    'A':'(1)';
    'B':'(2)';
end_primitive;
primitive 'Q_RES_0402LF-1.5K,1%,1/16W,EMPTY,CS21502FB07';body 'Q_RES';
    'A':'(1)';
    'B':'(2)';
end_primitive;
primitive 'Q_RES_0402LF-1.96K,1%,1/16W,CHIP,CS21962FB05';body 'Q_RES';
    'A':'(1)';
    'B':'(2)';
end_primitive;
primitive 'Q_RES_0402LF-10,1%,1/16W,CHIP,CS01002FB07';body 'Q_RES';
    'A':'(1)';
    'B':'(2)';
end_primitive;
primitive 'Q_RES_0402LF-10,1%,1/16W,EMPTY,CS01002FB07';body 'Q_RES';
    'A':'(1)';
    'B':'(2)';
end_primitive;
primitive 'Q_RES_0402LF-10.5K,1%,1/16W,CHIP,CS31052FB03';body 'Q_RES';
    'A':'(1)';
    'B':'(2)';
end_primitive;
primitive 'Q_RES_0402LF-100,1%,1/16W,CHIP,CS11002FB07';body 'Q_RES';
    'A':'(1)';
    'B':'(2)';
end_primitive;
primitive 'Q_RES_0402LF-100,1%,1/16W,EMPTY,CS11002FB07';body 'Q_RES';
    'A':'(1)';
    'B':'(2)';
end_primitive;
primitive 'Q_RES_0402LF-100K,1%,1/16W,CHIP,CS41002FB09';body 'Q_RES';
    'A':'(1)';
    'B':'(2)';
end_primitive;
primitive 'Q_RES_0402LF-100K,1%,1/16W,EMPTY,CS41002FB09';body 'Q_RES';
    'A':'(1)';
    'B':'(2)';
end_primitive;
primitive 'Q_RES_0402LF-10K,1%,1/16W,CHIP,CS31002FB08';body 'Q_RES';
    'A':'(1)';
    'B':'(2)';
end_primitive;
primitive 'Q_RES_0402LF-10K,1%,1/16W,EMPTY,CS31002FB08';body 'Q_RES';
    'A':'(1)';
    'B':'(2)';
end_primitive;
primitive 'Q_RES_0402LF-10K,5%,1/16W,CHIP,CS31002JB08';body 'Q_RES';
    'A':'(1)';
    'B':'(2)';
end_primitive;
primitive 'Q_RES_0402LF-10K,5%,1/16W,EMPTY,CS31002JB08';body 'Q_RES';
    'A':'(1)';
    'B':'(2)';
end_primitive;
primitive 'Q_RES_0402LF-10M,1%,1/16W,CHIP,CS61002FB02';body 'Q_RES';
    'A':'(1)';
    'B':'(2)';
end_primitive;
primitive 'Q_RES_0402LF-10M,1%,1/16W,EMPTY,CS61002FB02';body 'Q_RES';
    'A':'(1)';
    'B':'(2)';
end_primitive;
primitive 'Q_RES_0402LF-11.5K,1%,1/16W,CHIP,CS31152FB03';body 'Q_RES';
    'A':'(1)';
    'B':'(2)';
end_primitive;
primitive 'Q_RES_0402LF-11.5K,1%,1/16W,EMPTY,CS31152FB03';body 'Q_RES';
    'A':'(1)';
    'B':'(2)';
end_primitive;
primitive 'Q_RES_0402LF-11.8K,0.1%,1/16W,CHIP,CS31182BB06';body 'Q_RES';
    'A':'(1)';
    'B':'(2)';
end_primitive;
primitive 'Q_RES_0402LF-12.4K,1%,1/16W,CHIP,CS31242FB02';body 'Q_RES';
    'A':'(1)';
    'B':'(2)';
end_primitive;
primitive 'Q_RES_0402LF-120K,1%,1/16W,CHIP,CS41202FB05';body 'Q_RES';
    'A':'(1)';
    'B':'(2)';
end_primitive;
primitive 'Q_RES_0402LF-12K,1%,1/16W,CHIP,CS31202FB04';body 'Q_RES';
    'A':'(1)';
    'B':'(2)';
end_primitive;
primitive 'Q_RES_0402LF-13.7K,1%,1/16W,CHIP,CS31372FB03';body 'Q_RES';
    'A':'(1)';
    'B':'(2)';
end_primitive;
primitive 'Q_RES_0402LF-130,1%,1/16W,CHIP,CS11302FB03';body 'Q_RES';
    'A':'(1)';
    'B':'(2)';
end_primitive;
primitive 'Q_RES_0402LF-14.3K,1%,1/16W,CHIP,CS31432FB02';body 'Q_RES';
    'A':'(1)';
    'B':'(2)';
end_primitive;
primitive 'Q_RES_0402LF-15,1%,1/16W,CHIP,CS01502FB03';body 'Q_RES';
    'A':'(1)';
    'B':'(2)';
end_primitive;
primitive 'Q_RES_0402LF-15.4K,1%,1/16W,CHIP,CS31542FB02';body 'Q_RES';
    'A':'(1)';
    'B':'(2)';
end_primitive;
primitive 'Q_RES_0402LF-15K,0.1%,1/16W,CHIP,CS31502BB03';body 'Q_RES';
    'A':'(1)';
    'B':'(2)';
end_primitive;
primitive 'Q_RES_0402LF-15K,1%,1/16W,CHIP,CS31502FB05';body 'Q_RES';
    'A':'(1)';
    'B':'(2)';
end_primitive;
primitive 'Q_RES_0402LF-16.9K,1%,1/16W,CHIP,CS31692FB03';body 'Q_RES';
    'A':'(1)';
    'B':'(2)';
end_primitive;
primitive 'Q_RES_0402LF-160K,1%,1/16W,CHIP,CS41602FB05';body 'Q_RES';
    'A':'(1)';
    'B':'(2)';
end_primitive;
primitive 'Q_RES_0402LF-160K,1%,1/16W,EMPTY,CS41602FB05';body 'Q_RES';
    'A':'(1)';
    'B':'(2)';
end_primitive;
primitive 'Q_RES_0402LF-17.4K,1%,1/16W,CHIP,CS31742FB04';body 'Q_RES';
    'A':'(1)';
    'B':'(2)';
end_primitive;
primitive 'Q_RES_0402LF-17.8K,1%,1/16W,CHIP,CS31782FB04';body 'Q_RES';
    'A':'(1)';
    'B':'(2)';
end_primitive;
primitive 'Q_RES_0402LF-18K,1%,1/16W,CHIP,CS31802FB04';body 'Q_RES';
    'A':'(1)';
    'B':'(2)';
end_primitive;
primitive 'Q_RES_0402LF-1K,1%,1/16W,CHIP,CS21002FB06';body 'Q_RES';
    'A':'(1)';
    'B':'(2)';
end_primitive;
primitive 'Q_RES_0402LF-1K,1%,1/16W,EMPTY,CS21002FB06';body 'Q_RES';
    'A':'(1)';
    'B':'(2)';
end_primitive;
primitive 'Q_RES_0402LF-1M,1%,1/16W,CHIP,CS51002FB05';body 'Q_RES';
    'A':'(1)';
    'B':'(2)';
end_primitive;
primitive 'Q_RES_0402LF-1M,1%,1/16W,EMPTY,CS51002FB05';body 'Q_RES';
    'A':'(1)';
    'B':'(2)';
end_primitive;
primitive 'Q_RES_0402LF-2.2,1%,1/16W,CHIP,CS-2202FB01';body 'Q_RES';
    'A':'(1)';
    'B':'(2)';
end_primitive;
primitive 'Q_RES_0402LF-2.2,5%,1/16W,CHIP,TMP_QCS-2202JB25';body 'Q_RES';
    'A':'(1)';
    'B':'(2)';
end_primitive;
primitive 'Q_RES_0402LF-2.2K,5%,1/16W,CHIP,CS22202JB07';body 'Q_RES';
    'A':'(1)';
    'B':'(2)';
end_primitive;
primitive 'Q_RES_0402LF-2.2K,5%,1/16W,EMPTY,CS22202JB07';body 'Q_RES';
    'A':'(1)';
    'B':'(2)';
end_primitive;
primitive 'Q_RES_0402LF-2.49K,1%,1/16W,CHIP,CS22492FB05';body 'Q_RES';
    'A':'(1)';
    'B':'(2)';
end_primitive;
primitive 'Q_RES_0402LF-2.67K,1%,1/16W,CHIP,CS22672FB03';body 'Q_RES';
    'A':'(1)';
    'B':'(2)';
end_primitive;
primitive 'Q_RES_0402LF-2.8K,1%,1/16W,CHIP,CS22802FB04';body 'Q_RES';
    'A':'(1)';
    'B':'(2)';
end_primitive;
primitive 'Q_RES_0402LF-200,1%,1/16W,CHIP,CS12002FB06';body 'Q_RES';
    'A':'(1)';
    'B':'(2)';
end_primitive;
primitive 'Q_RES_0402LF-200K,1%,1/16W,CHIP,CS42002FB05';body 'Q_RES';
    'A':'(1)';
    'B':'(2)';
end_primitive;
primitive 'Q_RES_0402LF-200K,1%,1/16W,EMPTY,CS42002FB05';body 'Q_RES';
    'A':'(1)';
    'B':'(2)';
end_primitive;
primitive 'Q_RES_0402LF-20K,1%,1/16W,CHIP,CS32002FB06';body 'Q_RES';
    'A':'(1)';
    'B':'(2)';
end_primitive;
primitive 'Q_RES_0402LF-20M,1%,1/16W,CHIP,CS62002FB01';body 'Q_RES';
    'A':'(1)';
    'B':'(2)';
end_primitive;
primitive 'Q_RES_0402LF-21.5K,1%,1/16W,CHIP,CS32152FB04';body 'Q_RES';
    'A':'(1)';
    'B':'(2)';
end_primitive;
primitive 'Q_RES_0402LF-22,1%,1/16W,CHIP,CS02202FB02';body 'Q_RES';
    'A':'(1)';
    'B':'(2)';
end_primitive;
primitive 'Q_RES_0402LF-22,1%,1/16W,EMPTY,CS02202FB02';body 'Q_RES';
    'A':'(1)';
    'B':'(2)';
end_primitive;
primitive 'Q_RES_0402LF-22.1K,1%,1/16W,CHIP,CS32212FB02';body 'Q_RES';
    'A':'(1)';
    'B':'(2)';
end_primitive;
primitive 'Q_RES_0402LF-23.2K,1%,1/16W,CHIP,CS32322FB03';body 'Q_RES';
    'A':'(1)';
    'B':'(2)';
end_primitive;
primitive 'Q_RES_0402LF-24.3K,1%,1/16W,CHIP,CS32432FB03';body 'Q_RES';
    'A':'(1)';
    'B':'(2)';
end_primitive;
primitive 'Q_RES_0402LF-249,1%,1/16W,CHIP,CS12492FB02';body 'Q_RES';
    'A':'(1)';
    'B':'(2)';
end_primitive;
primitive 'Q_RES_0402LF-25.5K,1%,1/16W,CHIP,CS32552FB06';body 'Q_RES';
    'A':'(1)';
    'B':'(2)';
end_primitive;
primitive 'Q_RES_0402LF-26.7K,1%,1/16W,EMPTY,CS32672FB03';body 'Q_RES';
    'A':'(1)';
    'B':'(2)';
end_primitive;
primitive 'Q_RES_0402LF-267K,1%,1/16W,EMPTY,CS42672FB03';body 'Q_RES';
    'A':'(1)';
    'B':'(2)';
end_primitive;
primitive 'Q_RES_0402LF-27,5%,1/16W,CHIP,CS02702JB02';body 'Q_RES';
    'A':'(1)';
    'B':'(2)';
end_primitive;
primitive 'Q_RES_0402LF-27.4,1%,1/16W,CHIP,CS02742FB03';body 'Q_RES';
    'A':'(1)';
    'B':'(2)';
end_primitive;
primitive 'Q_RES_0402LF-2K,0.1%,1/16W,CHIP,CS22002BB07';body 'Q_RES';
    'A':'(1)';
    'B':'(2)';
end_primitive;
primitive 'Q_RES_0402LF-2K,1%,1/16W,CHIP,CS22002FB07';body 'Q_RES';
    'A':'(1)';
    'B':'(2)';
end_primitive;
primitive 'Q_RES_0402LF-2K,1%,1/16W,EMPTY,CS22002FB07';body 'Q_RES';
    'A':'(1)';
    'B':'(2)';
end_primitive;
primitive 'Q_RES_0402LF-2K,5%,1/16W,EMPTY,TMP_QCS22002JB29';body 'Q_RES';
    'A':'(1)';
    'B':'(2)';
end_primitive;
primitive 'Q_RES_0402LF-3.09K,1%,1/16W,CHIP,CS23092FB04';body 'Q_RES';
    'A':'(1)';
    'B':'(2)';
end_primitive;
primitive 'Q_RES_0402LF-3.9K,5%,1/16W,EMPTY,CS23902JB04';body 'Q_RES';
    'A':'(1)';
    'B':'(2)';
end_primitive;
primitive 'Q_RES_0402LF-30.1K,1%,1/16W,CHIP,CS33012FB03';body 'Q_RES';
    'A':'(1)';
    'B':'(2)';
end_primitive;
primitive 'Q_RES_0402LF-30K,1%,1/16W,CHIP,CS33002FB02';body 'Q_RES';
    'A':'(1)';
    'B':'(2)';
end_primitive;
primitive 'Q_RES_0402LF-30K,1%,1/16W,EMPTY,CS33002FB02';body 'Q_RES';
    'A':'(1)';
    'B':'(2)';
end_primitive;
primitive 'Q_RES_0402LF-31.6K,1%,1/16W,CHIP,CS33162FB02';body 'Q_RES';
    'A':'(1)';
    'B':'(2)';
end_primitive;
primitive 'Q_RES_0402LF-33,5%,1/16W,CHIP,CS03302JB10';body 'Q_RES';
    'A':'(1)';
    'B':'(2)';
end_primitive;
primitive 'Q_RES_0402LF-33,5%,1/16W,EMPTY,CS03302JB10';body 'Q_RES';
    'A':'(1)';
    'B':'(2)';
end_primitive;
primitive 'Q_RES_0402LF-33.2,1%,1/16W,CHIP,CS03322FB03';body 'Q_RES';
    'A':'(1)';
    'B':'(2)';
end_primitive;
primitive 'Q_RES_0402LF-33.2,1%,1/16W,EMPTY,CS03322FB03';body 'Q_RES';
    'A':'(1)';
    'B':'(2)';
end_primitive;
primitive 'Q_RES_0402LF-33K,1%,1/16W,CHIP,CS33302FB00';body 'Q_RES';
    'A':'(1)';
    'B':'(2)';
end_primitive;
primitive 'Q_RES_0402LF-35.7K,1%,1/16W,CHIP,CS33572FB01';body 'Q_RES';
    'A':'(1)';
    'B':'(2)';
end_primitive;
primitive 'Q_RES_0402LF-4.53K,1%,1/16W,CHIP,CS24532FB03';body 'Q_RES';
    'A':'(1)';
    'B':'(2)';
end_primitive;
primitive 'Q_RES_0402LF-4.75K,1%,1/16W,CHIP,CS24752FB03';body 'Q_RES';
    'A':'(1)';
    'B':'(2)';
end_primitive;
primitive 'Q_RES_0402LF-4.75K,1%,1/16W,EMPTY,CS24752FB03';body 'Q_RES';
    'A':'(1)';
    'B':'(2)';
end_primitive;
primitive 'Q_RES_0402LF-4.7K,1%,1/16W,CHIP,CS24702FB06';body 'Q_RES';
    'A':'(1)';
    'B':'(2)';
end_primitive;
primitive 'Q_RES_0402LF-4.7K,1%,1/16W,EMPTY,CS24702FB06';body 'Q_RES';
    'A':'(1)';
    'B':'(2)';
end_primitive;
primitive 'Q_RES_0402LF-4.7K,5%,1/16W,CHIP,CS24702JB10';body 'Q_RES';
    'A':'(1)';
    'B':'(2)';
end_primitive;
primitive 'Q_RES_0402LF-4.7K,5%,1/16W,EMPTY,CS24702JB10';body 'Q_RES';
    'A':'(1)';
    'B':'(2)';
end_primitive;
primitive 'Q_RES_0402LF-4.87K,1%,1/16W,EMPTY,CS24872FB01';body 'Q_RES';
    'A':'(1)';
    'B':'(2)';
end_primitive;
primitive 'Q_RES_0402LF-4.87K,1%,1/16W,EMPTY,CS24872FB07';body 'Q_RES';
    'A':'(1)';
    'B':'(2)';
end_primitive;
primitive 'Q_RES_0402LF-4.99K,0.1%,1/16W,CHIP,CS24992BB04';body 'Q_RES';
    'A':'(1)';
    'B':'(2)';
end_primitive;
primitive 'Q_RES_0402LF-4.99K,1%,1/16W,EMPTY,CS24992FB07';body 'Q_RES';
    'A':'(1)';
    'B':'(2)';
end_primitive;
primitive 'Q_RES_0402LF-40.2K,1%,1/16W,CHIP,CS34022FB04';body 'Q_RES';
    'A':'(1)';
    'B':'(2)';
end_primitive;
primitive 'Q_RES_0402LF-46.4K,1%,1/16W,CHIP,CS34642FB02';body 'Q_RES';
    'A':'(1)';
    'B':'(2)';
end_primitive;
primitive 'Q_RES_0402LF-470,1%,1/16W,CHIP,CS14702FB04';body 'Q_RES';
    'A':'(1)';
    'B':'(2)';
end_primitive;
primitive 'Q_RES_0402LF-47K,0.1%,1/16W,CHIP,CS34702BB05';body 'Q_RES';
    'A':'(1)';
    'B':'(2)';
end_primitive;
primitive 'Q_RES_0402LF-47K,0.1%,1/16W,EMPTY,CS34702BB05';body 'Q_RES';
    'A':'(1)';
    'B':'(2)';
end_primitive;
primitive 'Q_RES_0402LF-49.9,1%,1/16W,CHIP,CS04992FB07';body 'Q_RES';
    'A':'(1)';
    'B':'(2)';
end_primitive;
primitive 'Q_RES_0402LF-49.9,1%,1/16W,EMPTY,CS04992FB07';body 'Q_RES';
    'A':'(1)';
    'B':'(2)';
end_primitive;
primitive 'Q_RES_0402LF-5.11K,1%,1/16W,CHIP,CS25112FB04';body 'Q_RES';
    'A':'(1)';
    'B':'(2)';
end_primitive;
primitive 'Q_RES_0402LF-5.23K,1%,1/16W,CHIP,CS25232FB08';body 'Q_RES';
    'A':'(1)';
    'B':'(2)';
end_primitive;
primitive 'Q_RES_0402LF-5.36K,1%,1/16W,CHIP,CS25362FB02';body 'Q_RES';
    'A':'(1)';
    'B':'(2)';
end_primitive;
primitive 'Q_RES_0402LF-5.36K,1%,1/16W,EMPTY,CS25362FB02';body 'Q_RES';
    'A':'(1)';
    'B':'(2)';
end_primitive;
primitive 'Q_RES_0402LF-5.6,1%,1/16W,CHIP,CS-5602FB01';body 'Q_RES';
    'A':'(1)';
    'B':'(2)';
end_primitive;
primitive 'Q_RES_0402LF-51,5%,1/16W,EMPTY,CS05102JB04';body 'Q_RES';
    'A':'(1)';
    'B':'(2)';
end_primitive;
primitive 'Q_RES_0402LF-510K,5%,1/16W,EMPTY,CS45102JB03';body 'Q_RES';
    'A':'(1)';
    'B':'(2)';
end_primitive;
primitive 'Q_RES_0402LF-54.9K,1%,1/16W,CHIP,CS35492FB03';body 'Q_RES';
    'A':'(1)';
    'B':'(2)';
end_primitive;
primitive 'Q_RES_0402LF-54.9K,1%,1/16W,EMPTY,CS35492FB03';body 'Q_RES';
    'A':'(1)';
    'B':'(2)';
end_primitive;
primitive 'Q_RES_0402LF-560,1%,1/16W,CHIP,CS15602FB03';body 'Q_RES';
    'A':'(1)';
    'B':'(2)';
end_primitive;
primitive 'Q_RES_0402LF-56K,1%,1/16W,CHIP,CS35602FB00';body 'Q_RES';
    'A':'(1)';
    'B':'(2)';
end_primitive;
primitive 'Q_RES_0402LF-6.04K,1%,1/16W,CHIP,CS26042FB04';body 'Q_RES';
    'A':'(1)';
    'B':'(2)';
end_primitive;
primitive 'Q_RES_0402LF-6.19K,1%,1/16W,CHIP,CS26192FB03';body 'Q_RES';
    'A':'(1)';
    'B':'(2)';
end_primitive;
primitive 'Q_RES_0402LF-6.8K,1%,1/16W,CHIP,CS26802FB02';body 'Q_RES';
    'A':'(1)';
    'B':'(2)';
end_primitive;
primitive 'Q_RES_0402LF-6.98K,1%,1/16W,CHIP,CS26982FB08';body 'Q_RES';
    'A':'(1)';
    'B':'(2)';
end_primitive;
primitive 'Q_RES_0402LF-60.4K,1%,1/16W,CHIP,CS36042FB04';body 'Q_RES';
    'A':'(1)';
    'B':'(2)';
end_primitive;
primitive 'Q_RES_0402LF-63.4K,1%,1/16W,CHIP,CS36342FB04';body 'Q_RES';
    'A':'(1)';
    'B':'(2)';
end_primitive;
primitive 'Q_RES_0402LF-680,1%,1/16W,CHIP,CS16802FB03';body 'Q_RES';
    'A':'(1)';
    'B':'(2)';
end_primitive;
primitive 'Q_RES_0402LF-681,1%,1/16W,CHIP,CS16812FB02';body 'Q_RES';
    'A':'(1)';
    'B':'(2)';
end_primitive;
primitive 'Q_RES_0402LF-68K,1%,1/16W,EMPTY,CS36802FB04';body 'Q_RES';
    'A':'(1)';
    'B':'(2)';
end_primitive;
primitive 'Q_RES_0402LF-7.15K,1%,1/16W,CHIP,CS27152FB03';body 'Q_RES';
    'A':'(1)';
    'B':'(2)';
end_primitive;
primitive 'Q_RES_0402LF-7.87K,1%,1/16W,CHIP,CS27872FB02';body 'Q_RES';
    'A':'(1)';
    'B':'(2)';
end_primitive;
primitive 'Q_RES_0402LF-71.5K,1%,1/16W,CHIP,CS37152FB05';body 'Q_RES';
    'A':'(1)';
    'B':'(2)';
end_primitive;
primitive 'Q_RES_0402LF-71.5K,1%,1/16W,EMPTY,CS37152FB05';body 'Q_RES';
    'A':'(1)';
    'B':'(2)';
end_primitive;
primitive 'Q_RES_0402LF-75K,0.1%,1/16W,CHIP,CS37502BB01';body 'Q_RES';
    'A':'(1)';
    'B':'(2)';
end_primitive;
primitive 'Q_RES_0402LF-8.45K,1%,1/16W,EMPTY,CS28452FB06';body 'Q_RES';
    'A':'(1)';
    'B':'(2)';
end_primitive;
primitive 'Q_RES_0402LF-8.66K,1%,1/16W,CHIP,CS28662FB02';body 'Q_RES';
    'A':'(1)';
    'B':'(2)';
end_primitive;
primitive 'Q_RES_0402LF-8.87K,1%,1/16W,EMPTY,CS28872FB01';body 'Q_RES';
    'A':'(1)';
    'B':'(2)';
end_primitive;
primitive 'Q_RES_0402LF-82K,1%,1/16W,CHIP,CS38202FB01';body 'Q_RES';
    'A':'(1)';
    'B':'(2)';
end_primitive;
primitive 'Q_RES_0402LF-84.5K,1%,1/16W,CHIP,CS38452FB05';body 'Q_RES';
    'A':'(1)';
    'B':'(2)';
end_primitive;
primitive 'Q_RES_0402LF-845,1%,1/16W,CHIP,CS18452FB01';body 'Q_RES';
    'A':'(1)';
    'B':'(2)';
end_primitive;
primitive 'Q_RES_0402LF-86.6K,1%,1/16W,CHIP,CS38662FB05';body 'Q_RES';
    'A':'(1)';
    'B':'(2)';
end_primitive;
primitive 'Q_RES_0402LF-86.6K,1%,1/16W,EMPTY,CS38662FB05';body 'Q_RES';
    'A':'(1)';
    'B':'(2)';
end_primitive;
primitive 'Q_RES_0402LF-9.09K,1%,1/16W,CHIP,CS29092FB05';body 'Q_RES';
    'A':'(1)';
    'B':'(2)';
end_primitive;
primitive 'Q_RES_0402LF-9.31K,1%,1/16W,CHIP,CS29312FB02';body 'Q_RES';
    'A':'(1)';
    'B':'(2)';
end_primitive;
primitive 'Q_RES_0402LF-9.53K,1%,1/16W,CHIP,CS29532FB06';body 'Q_RES';
    'A':'(1)';
    'B':'(2)';
end_primitive;
primitive 'Q_RES_0402LF-9.76K,1%,1/16W,CHIP,CS29762FB05';body 'Q_RES';
    'A':'(1)';
    'B':'(2)';
end_primitive;
primitive 'Q_RES_0402LF-90.9K,1%,1/16W,CHIP,CS39092FB04';body 'Q_RES';
    'A':'(1)';
    'B':'(2)';
end_primitive;
primitive 'Q_RES_0603LF-0,5%,1/4W,CHIP,CS00006J900';body 'Q_RES';
    'A':'(1)';
    'B':'(2)';
end_primitive;
primitive 'Q_RES_0603LF-0,5%,1/4W,EMPTY,CS00006J900';body 'Q_RES';
    'A':'(1)';
    'B':'(2)';
end_primitive;
primitive 'Q_RES_0603LF-1,1%,1/10W,CHIP,CS-1003F900';body 'Q_RES';
    'A':'(1)';
    'B':'(2)';
end_primitive;
primitive 'Q_RES_0603LF-49.9,1%,1/10W,CHIP,CS04993F909';body 'Q_RES';
    'A':'(1)';
    'B':'(2)';
end_primitive;
primitive 'Q_RES_0603LF-499,1%,1/10W,CHIP,CS14993F901';body 'Q_RES';
    'A':'(1)';
    'B':'(2)';
end_primitive;
primitive 'Q_RES_1206LF-243,1%,1/4W,CHIP,CS12436F201';body 'Q_RES';
    'A':'(1)';
    'B':'(2)';
end_primitive;
primitive 'Q_RES_2512LF-0.002,1%,2W,CHIP,CS+002AFR06';body 'Q_RES';
    'A':'(1)';
    'B':'(2)';
end_primitive;
primitive 'Q_RES_2512LF-10,1%,2W,EMPTY,CS0100AFR00';body 'Q_RES';
    'A':'(1)';
    'B':'(2)';
end_primitive;
primitive 'Q_RES_4P_12-0.001,1%,3W,SMLF,CHIP,SP_CS+001DFR10';body 'Q_RES_4P_12';
    '1':'(1)';
    '2':'(2)';
    '3':'(3)';
    '4':'(4)';
end_primitive;
primitive 'Q_SHORT_SM-EMPTY,SHORT16';body 'Q_SHORT';
    '1':'(1)';BIDI;
    '2':'(2)';BIDI;
end_primitive;
primitive 'Q_SP_RES4P-0.0003,1%,4W,SMLF,CHIP,SP_CS0000FFT09';body 'Q_SP_RES4P';
    '2B':'(2B)';BIDI;
    '1B':'(1B)';BIDI;
    '2A':'(2A)';BIDI;
    '1A':'(1A)';BIDI;
end_primitive;
primitive 'Q_SP_RES4P-0.003,1%,2W,SMLF,CHIP,SP_CS+003AFR00_1';body 'Q_SP_RES4P';
    '2B':'(2B)';BIDI;
    '1B':'(1B)';BIDI;
    '2A':'(2A)';BIDI;
    '1A':'(1A)';BIDI;
end_primitive;
primitive 'Q_XTAL_4P_13BI_24GND-12MHZ,SMLF,MISC,BG6120000B0';body 'Q_XTAL_4P_13BI_24GND';
    'X1':'(1)';BIDI;
    'G1':'(2)';
    'G2':'(4)';
    'X2':'(3)';BIDI;
end_primitive;
primitive 'Q_XTAL_4P_13BI_24GND-24MHZ,SMLF,MISC,BG624000101';body 'Q_XTAL_4P_13BI_24GND';
    'X1':'(1)';BIDI;
    'G1':'(2)';
    'G2':'(4)';
    'X2':'(3)';BIDI;
end_primitive;
primitive 'Q_XTAL_4P_13BI_24GND-25MHZ,SMLF,MISC,BG6250000L4';body 'Q_XTAL_4P_13BI_24GND';
    'X1':'(1)';BIDI;
    'G1':'(2)';
    'G2':'(4)';
    'X2':'(3)';BIDI;
end_primitive;
primitive 'Q_XTAL_4P_13BI_24GND-26MHZ,SMLF,MISC,BG626000049';body 'Q_XTAL_4P_13BI_24GND';
    'X1':'(1)';BIDI;
    'G1':'(2)';
    'G2':'(4)';
    'X2':'(3)';BIDI;
end_primitive;
primitive 'Q_XTAL_4P_13BI_24GND-48MHZ,SMLF,MISC,BG648000076';body 'Q_XTAL_4P_13BI_24GND';
    'X1':'(1)';BIDI;
    'G1':'(2)';
    'G2':'(4)';
    'X2':'(3)';BIDI;
end_primitive;
primitive 'RAA229620GNPHA0-RAA229620GNP#HA0,SMLF,IC,ARF0TGP40A';body 'RAA229620GNPHA0';
    'CS11':'(27)';IN;
    'VCC':'(47)';
    'SVTI':'(24)';IN;
    'PMSCL':'(14)';IN;
    'SVC':'(22)';IN;
    'CS6':'(32)';IN;
    'SVTO':'(23)';OUT;
    'RESET_L':'(18)';IN;
    'CS5':'(33)';IN;
    'CS4':'(34)';IN;
    'PG1':'(20)';OUT;
    'SVD':'(21)';IN;
    'NPMALERT':'(15)';OUT;
    'EN0':'(17)';IN;
    'RGND0':'(26)';IN;
    'PMSDA':'(13)';BIDI;
    'PWM4':'(5)';OUT;
    'PWM5':'(6)';OUT;
    'VSEN0':'(25)';IN;
    'PWM1':'(2)';OUT;
    'PG0':'(16)';OUT;
    'PWM6':'(7)';OUT;
    'VCCS':'(48)';
    'VMON||IINSEN':'(45)';BIDI;
    'VINSEN':'(46)';IN;
    'TEMP0':'(44)';IN;
    'VDDIO':'(19)';
    'VSEN1':'(40)';IN;
    'RGND1':'(39)';IN;
    'CS1':'(37)';IN;
    'PWM11':'(12)';OUT;
    'PWM3':'(4)';OUT;
    'CS3':'(35)';IN;
    'PWM2':'(3)';OUT;
    'CS2':'(36)';IN;
    'OCP_L':'(41)';OUT;
    'TH_GND':'(TH)';
    'EN1||ADDR_CFG':'(42)';IN;
    'TEMP1':'(43)';IN;
    'PWM0':'(1)';OUT;
    'CS0':'(38)';IN;
    'PWM7':'(8)';OUT;
    'CS7':'(31)';IN;
    'PWM8':'(9)';OUT;
    'CS8':'(30)';IN;
    'PWM9':'(10)';OUT;
    'CS9':'(29)';IN;
    'PWM10':'(11)';OUT;
    'CS10':'(28)';IN;
end_primitive;
primitive 'RAA229621GNPHA0-RAA229621GNP#HA0,SMLF,IC,ARF0TGP40A';body 'RAA229621GNPHA0';
    'CS7':'(23)';IN;
    'VCC':'(39)';
    'SVTI':'(20)';IN;
    'PMSCL':'(10)';IN;
    'SVC':'(18)';IN;
    'CS6':'(24)';IN;
    'SVTO':'(19)';OUT;
    'RESET_L':'(14)';IN;
    'CS5':'(25)';IN;
    'CS4':'(26)';IN;
    'PG1':'(16)';OUT;
    'SVD':'(17)';BIDI;
    'NPMALERT':'(11)';OUT;
    'EN0':'(13)';IN;
    'RGND0':'(22)';IN;
    'PMSDA':'(9)';BIDI;
    'PWM4':'(5)';OUT;
    'PWM5':'(6)';OUT;
    'VSEN0':'(21)';IN;
    'PWM1':'(2)';OUT;
    'PG0':'(12)';OUT;
    'PWM6':'(7)';OUT;
    'VCCS':'(40)';
    'VMON||IINSEN':'(37)';IN;
    'VINSEN':'(38)';IN;
    'TEMP0':'(36)';IN;
    'VDDIO':'(15)';IN;
    'VSEN1':'(32)';IN;
    'RGND1':'(31)';IN;
    'CS1':'(29)';IN;
    'PWM7':'(8)';OUT;
    'PWM3':'(4)';OUT;
    'CS3':'(27)';IN;
    'PWM2':'(3)';OUT;
    'CS2':'(28)';IN;
    'OCP_L':'(33)';OUT;
    'TH_GND':'(TH)';
    'EN1||ADDR_CFG':'(34)';IN;
    'TEMP1':'(35)';IN;
    'PWM0':'(1)';OUT;
    'CS0':'(30)';IN;
end_primitive;
primitive 'RS31312R-RS31312R,SMLF,IC,AL031312000';body 'RS31312R';
    'VOUT_20':'(20)';OUT;
    'VIN_21_22':'(21_22)';IN;
    'VOUT_19':'(19)';OUT;
    'VOUT_18':'(18)';OUT;
    'VOUT_17':'(17)';OUT;
    'VOUT_16':'(16)';OUT;
    'VOUT_15':'(15)';OUT;
    'VOUT_14':'(14)';OUT;
    'AVIN':'(12)';IN;
    'VOUT_13':'(13)';OUT;
    'OV':'(11)';IN;
    'PG':'(10)';OUT;
    'FLTB':'(9)';OUT;
    'IMON':'(8)';OUT;
    'VIN_23':'(23)';IN;
    'VIN_24':'(24)';IN;
    'VIN_25':'(25)';IN;
    'VIN_26':'(26)';IN;
    'EN':'(1)';IN;
    'LOADEN':'(2)';IN;
    'ENTM':'(3)';IN;
    'TIMER':'(4)';IN;
    'ISET':'(5)';IN;
    'SS':'(6)';IN;
    'GND':'(7)';
end_primitive;
primitive 'RT9818C44GV-RT9818C-44GV,SMLF,IC,AL009818001';body 'RT9818C44GV';
    'VDD':'(3)';
    'RESET#':'(1)';OUT;
    'GND':'(2)';
end_primitive;
primitive 'SCHOTTKY_12-B0530WS7F,SMLF,EMPTY,BC000530Z41';body 'SCHOTTKY_12';
    'A':'(1)';IN;
    'C':'(2)';BIDI;
end_primitive;
primitive 'SCHOTTKY_AC-B340A-13-F,SMLF,IC,BC000340Z30';body 'SCHOTTKY_AC';
    'A':'(A)';IN;
    'C':'(C)';BIDI;
end_primitive;
primitive 'SCHOTTKY_DUAL_12A_3C-BAT54CW,SMLF,EMPTY,BCBAT54CZ13';body 'SCHOTTKY_DUAL_12A_3C';
    'A':'(2)';IN;
    'B':'(1)';IN;
    'C':'(3)';BIDI;
end_primitive;
primitive 'SCHOTTKY_DUAL_12A_3C-BAT54CW,SMLF,IC,BCBAT54CZ13';body 'SCHOTTKY_DUAL_12A_3C';
    'A':'(2)';IN;
    'B':'(1)';IN;
    'C':'(3)';BIDI;
end_primitive;
primitive 'SCONN168_ME1016810202011-SCONN168_ME1016810202011,A';body 'SCONN168_ME1016810202011';
    'NIC_PWR_GOOD':'(OB1)';IN;
    'MAIN_PWR_EN':'(OB2)';OUT;
    'LD#':'(OB3)';OUT;
    'DATA_IN':'(OB4)';IN;
    'DATA_OUT':'(OB5)';OUT;
    'CLK':'(OB6)';OUT;
    'SLOT_ID0':'(OB7)';OUT;
    'RBT_RXD1':'(OB8)';IN;
    'RBT_RXD0':'(OB9)';IN;
    'GND_OB10':'(OB10)';
    'REFCLKN2':'(OB11)';OUT;
    'REFCLKP2':'(OB12)';OUT;
    'GND_OB13':'(OB13)';
    'RBT_CRS_DV':'(OB14)';OUT;
    '+12V_EDGE_B1':'(B1)';
    '+12V_EDGE_B2':'(B2)';
    '+12V_EDGE_B3':'(B3)';
    '+12V_EDGE_B4':'(B4)';
    '+12V_EDGE_B5':'(B5)';
    '+12V_EDGE_B6':'(B6)';
    'BIF0#':'(B7)';OUT;
    'BIF1#':'(B8)';OUT;
    'BIF2#':'(B9)';OUT;
    'PERST0#':'(B10)';OUT;
    '+3.3V_EDGE':'(B11)';
    'AUX_PWR_EN':'(B12)';OUT;
    'GND_B13':'(B13)';
    'REFCLKN0':'(B14)';IN;
    'REFCLKP0':'(B15)';OUT;
    'GND_B16':'(B16)';
    'PETN0':'(B17)';OUT;
    'PETP0':'(B18)';OUT;
    'GND_B19':'(B19)';
    'PETN1':'(B20)';OUT;
    'PETP1':'(B21)';OUT;
    'GND_B22':'(B22)';
    'PETN2':'(B23)';OUT;
    'PETP2':'(B24)';OUT;
    'GND_B25':'(B25)';
    'PETN3':'(B26)';OUT;
    'PETP3':'(B27)';OUT;
    'GND_B28':'(B28)';
    'GND_B29':'(B29)';
    'PETN4':'(B30)';OUT;
    'PETP4':'(B31)';OUT;
    'GND_B32':'(B32)';
    'PETN5':'(B33)';OUT;
    'PETP5':'(B34)';OUT;
    'GND_B35':'(B35)';
    'PETN6':'(B36)';OUT;
    'PETP6':'(B37)';OUT;
    'GND_B38':'(B38)';
    'PETN7':'(B39)';OUT;
    'PETP7':'(B40)';OUT;
    'GND_B41':'(B41)';
    'PRSNTB0#':'(B42)';IN;
    'GND_B43':'(B43)';
    'PETN8':'(B44)';OUT;
    'PETP8':'(B45)';OUT;
    'GND_B46':'(B46)';
    'PETN9':'(B47)';OUT;
    'PETP9':'(B48)';OUT;
    'GND_B49':'(B49)';
    'PETN10':'(B50)';OUT;
    'PETP10':'(B51)';OUT;
    'GND_B52':'(B52)';
    'PETN11':'(B53)';OUT;
    'PETP11':'(B54)';OUT;
    'GND_B55':'(B55)';
    'PETN12':'(B56)';OUT;
    'PERST2#':'(OA1)';OUT;
    'PERST3#':'(OA2)';OUT;
    'WAKE#':'(OA3)';IN;
    'RBT_ARB_IN':'(OA4)';IN;
    'RBT_ARB_OUT':'(OA5)';OUT;
    'SLOT_ID1':'(OA6)';OUT;
    'RBT_TX_EN':'(OA7)';OUT;
    'RBT_TXD1':'(OA8)';OUT;
    'RBT_TXD0':'(OA9)';OUT;
    'GND_OA10':'(OA10)';
    'REFCLKN3':'(OA11)';OUT;
    'REFCLKP3':'(OA12)';OUT;
    'GND_OA13':'(OA13)';
    'RBT_CLK_IN':'(OA14)';OUT;
    'GND_A1':'(A1)';
    'GND_A2':'(A2)';
    'GND_A3':'(A3)';
    'GND_A4':'(A4)';
    'GND_A5':'(A5)';
    'GND_A6':'(A6)';
    'SMCLK':'(A7)';OUT;
    'SMDAT':'(A8)';BIDI;
    'SMRST#':'(A9)';OUT;
    'PRSNTA#':'(A10)';OUT;
    'PERST1#':'(A11)';OUT;
    'PRSNTB2#':'(A12)';IN;
    'GND_A13':'(A13)';
    'REFCLKN1':'(A14)';OUT;
    'REFCLKP1':'(A15)';OUT;
    'GND_A16':'(A16)';
    'PERN0':'(A17)';IN;
    'PERP0':'(A18)';IN;
    'GND_A19':'(A19)';
    'PERN1':'(A20)';IN;
    'PERP1':'(A21)';IN;
    'GND_A22':'(A22)';
    'PERN2':'(A23)';IN;
    'PERP2':'(A24)';IN;
    'GND_A25':'(A25)';
    'PERN3':'(A26)';IN;
    'PERP3':'(A27)';IN;
    'GND_A28':'(A28)';
    'GND_A29':'(A29)';
    'PERN4':'(A30)';IN;
    'PERP4':'(A31)';IN;
    'GND_A32':'(A32)';
    'PERN5':'(A33)';IN;
    'PERP5':'(A34)';IN;
    'GND_A35':'(A35)';
    'PERN6':'(A36)';IN;
    'PERP6':'(A37)';IN;
    'GND_A38':'(A38)';
    'PERN7':'(A39)';IN;
    'PERP7':'(A40)';IN;
    'GND_A41':'(A41)';
    'PRSNTB1#':'(A42)';IN;
    'GND_A43':'(A43)';
    'PERN8':'(A44)';IN;
    'PERP8':'(A45)';IN;
    'GND_A46':'(A46)';
    'PERN9':'(A47)';IN;
    'PERP9':'(A48)';IN;
    'GND_A49':'(A49)';
    'PERN10':'(A50)';IN;
    'PERP10':'(A51)';IN;
    'GND_A52':'(A52)';
    'PERN11':'(A53)';IN;
    'PERP11':'(A54)';IN;
    'GND_A55':'(A55)';
    'PERN12':'(A56)';IN;
    'PERP12':'(A57)';IN;
    'GND_A58':'(A58)';
    'PERN13':'(A59)';IN;
    'PERP13':'(A60)';IN;
    'GND_A61':'(A61)';
    'PERN14':'(A62)';IN;
    'PERP14':'(A63)';IN;
    'GND_A64':'(A64)';
    'PERN15':'(A65)';IN;
    'PERP15':'(A66)';IN;
    'GND_A67':'(A67)';
    'USB_DATN':'(A68)';BIDI;
    'USB_DATP':'(A69)';BIDI;
    'PWRBRK0#':'(A70)';BIDI;
    'PETP12':'(B57)';OUT;
    'GND_B58':'(B58)';
    'PETN13':'(B59)';OUT;
    'PETP13':'(B60)';OUT;
    'GND_B61':'(B61)';
    'PETN14':'(B62)';OUT;
    'PETP14':'(B63)';OUT;
    'GND_B64':'(B64)';
    'PETN15':'(B65)';OUT;
    'PETP15':'(B66)';OUT;
    'GND_B67':'(B67)';
    'RFU1_NC_B68':'(B68)';OUT;
    'RFU1_NC_B69':'(B69)';OUT;
    'PRSNTB3#':'(B70)';IN;
    'G1':'(G1)';
    'G2':'(G2)';
    'G3':'(G3)';
    'G4':'(G4)';
    'G5':'(G5)';
end_primitive;
primitive 'SCONN20_HSU2101L00007H-SCONN20_HSU2101-L0000-7H,SMA';body 'SCONN20_HSU2101L00007H';
    '1':'(1)';BIDI;
    '2':'(2)';BIDI;
    '3':'(3)';BIDI;
    '4':'(4)';BIDI;
    '5':'(5)';BIDI;
    '6':'(6)';BIDI;
    '7':'(7)';BIDI;
    '8':'(8)';BIDI;
    '9':'(9)';BIDI;
    '10':'(10)';BIDI;
    '11':'(11)';BIDI;
    '12':'(12)';BIDI;
    '13':'(13)';BIDI;
    '14':'(14)';BIDI;
    '15':'(15)';BIDI;
    '16':'(16)';BIDI;
    '17':'(17)';BIDI;
    '18':'(18)';BIDI;
    '19':'(19)';BIDI;
    '20':'(20)';BIDI;
end_primitive;
primitive 'SCONN21_9193031121LF-SCONN21_91930-31121LF,SMLF,IOA';body 'SCONN21_9193031121LF';
    '1':'(1)';BIDI;
    '3':'(3)';BIDI;
    '4':'(4)';BIDI;
    '5':'(5)';BIDI;
    '2':'(2)';BIDI;
    'G1':'(G1)';
    'G2':'(G2)';
    '6':'(6)';BIDI;
    '7':'(7)';BIDI;
    '8':'(8)';BIDI;
    '9':'(9)';BIDI;
    '10':'(10)';BIDI;
    '11':'(11)';BIDI;
    '12':'(12)';BIDI;
    '13':'(13)';BIDI;
    '14':'(14)';BIDI;
    '15':'(15)';BIDI;
    '16':'(16)';BIDI;
    '17':'(17)';BIDI;
    '18':'(18)';BIDI;
    '19':'(19)';BIDI;
    '20':'(20)';BIDI;
    '21':'(21)';BIDI;
end_primitive;
primitive 'SCONN288_DDR506112002KQ-SCONN288_DDR506112002KQ,SMA';body 'SCONN288_DDR506112002KQ';
    'VIN_MGMT':'(3,0,0)';$S;
    'RFU0':'(2,0,0)';$S;OUT;
    'RFU1':'(144,0,0)';$S;OUT;
    'RFU2':'(149,0,0)';$S;OUT;
    'RFU3':'(150,0,0)';$S;OUT;
    'RFU4':'(220,0,0)';$S;OUT;
    'RFU5':'(231,0,0)';$S;OUT;
    'RFU6':'(232,0,0)';$S;OUT;
    'RESET_N':'(207,0,0)';$S;IN;
    'PWR_GOOD||FAIL_N':'(147,0,0)';$S;BIDI;
    'PAR_B':'(227,0,0)';$S;IN;
    'PAR_A':'(74,0,0)';$S;IN;
    'LBS||RSP_B_N':'(87,0,0)';$S;OUT;
    'LBD||RSP_A_N':'(86,0,0)';$S;OUT;
    'HSDA':'(5,0,0)';$S;BIDI;
    'HSCL':'(4,0,0)';$S;IN;
    'HAS':'(148,0,0)';$S;IN;
    'DQ0_B':'(100,0,0)';$S;BIDI;
    'DQ1_B':'(102,0,0)';$S;BIDI;
    'DQ2_B':'(245,0,0)';$S;BIDI;
    'DQ3_B':'(247,0,0)';$S;BIDI;
    'DQ4_B':'(107,0,0)';$S;BIDI;
    'DQ5_B':'(109,0,0)';$S;BIDI;
    'DQ6_B':'(252,0,0)';$S;BIDI;
    'DQ7_B':'(254,0,0)';$S;BIDI;
    'DQ8_B':'(111,0,0)';$S;BIDI;
    'DQ9_B':'(113,0,0)';$S;BIDI;
    'DQ10_B':'(256,0,0)';$S;BIDI;
    'DQ11_B':'(258,0,0)';$S;BIDI;
    'DQ12_B':'(118,0,0)';$S;BIDI;
    'DQ13_B':'(120,0,0)';$S;BIDI;
    'DQ14_B':'(263,0,0)';$S;BIDI;
    'DQ15_B':'(265,0,0)';$S;BIDI;
    'DQ16_B':'(122,0,0)';$S;BIDI;
    'DQ17_B':'(124,0,0)';$S;BIDI;
    'DQ18_B':'(267,0,0)';$S;BIDI;
    'DQ19_B':'(269,0,0)';$S;BIDI;
    'DQ20_B':'(129,0,0)';$S;BIDI;
    'DQ21_B':'(131,0,0)';$S;BIDI;
    'DQ22_B':'(274,0,0)';$S;BIDI;
    'DQ23_B':'(276,0,0)';$S;BIDI;
    'DQ24_B':'(133,0,0)';$S;BIDI;
    'DQ25_B':'(135,0,0)';$S;BIDI;
    'DQ26_B':'(278,0,0)';$S;BIDI;
    'DQ27_B':'(280,0,0)';$S;BIDI;
    'DQ28_B':'(140,0,0)';$S;BIDI;
    'DQ29_B':'(142,0,0)';$S;BIDI;
    'DQ30_B':'(285,0,0)';$S;BIDI;
    'DQ31_B':'(287,0,0)';$S;BIDI;
    'DQ0_A':'(7,0,0)';$S;BIDI;
    'DQ1_A':'(9,0,0)';$S;BIDI;
    'DQ2_A':'(152,0,0)';$S;BIDI;
    'DQ3_A':'(154,0,0)';$S;BIDI;
    'DQ4_A':'(14,0,0)';$S;BIDI;
    'DQ5_A':'(16,0,0)';$S;BIDI;
    'DQ6_A':'(159,0,0)';$S;BIDI;
    'DQ7_A':'(161,0,0)';$S;BIDI;
    'DQ8_A':'(18,0,0)';$S;BIDI;
    'DQ9_A':'(20,0,0)';$S;BIDI;
    'DQ10_A':'(163,0,0)';$S;BIDI;
    'DQ11_A':'(165,0,0)';$S;BIDI;
    'DQ12_A':'(25,0,0)';$S;BIDI;
    'DQ13_A':'(27,0,0)';$S;BIDI;
    'DQ14_A':'(170,0,0)';$S;BIDI;
    'DQ15_A':'(172,0,0)';$S;BIDI;
    'DQ16_A':'(29,0,0)';$S;BIDI;
    'DQ17_A':'(31,0,0)';$S;BIDI;
    'DQ18_A':'(174,0,0)';$S;BIDI;
    'DQ19_A':'(176,0,0)';$S;BIDI;
    'DQ20_A':'(36,0,0)';$S;BIDI;
    'DQ21_A':'(38,0,0)';$S;BIDI;
    'DQ22_A':'(181,0,0)';$S;BIDI;
    'DQ23_A':'(183,0,0)';$S;BIDI;
    'DQ24_A':'(40,0,0)';$S;BIDI;
    'DQ25_A':'(42,0,0)';$S;BIDI;
    'DQ26_A':'(185,0,0)';$S;BIDI;
    'DQ27_A':'(187,0,0)';$S;BIDI;
    'DQ28_A':'(47,0,0)';$S;BIDI;
    'DQ29_A':'(49,0,0)';$S;BIDI;
    'DQ30_A':'(192,0,0)';$S;BIDI;
    'CS1_B_N':'(229,0,0)';$S;IN;
    'CS1_A_N':'(209,0,0)';$S;IN;
    'CS0_B_N':'(84,0,0)';$S;IN;
    'CS0_A_N':'(64,0,0)';$S;IN;
    'CK_T':'(217,0,0)';$S;IN;
    'CK_C':'(218,0,0)';$S;IN;
    'CB0_B':'(96,0,0)';$S;BIDI;
    'CB1_B':'(98,0,0)';$S;BIDI;
    'CB2_B':'(241,0,0)';$S;BIDI;
    'CB3_B':'(243,0,0)';$S;BIDI;
    'CB4_B':'(89,0,0)';$S;BIDI;
    'CB5_B':'(91,0,0)';$S;BIDI;
    'CB6_B':'(234,0,0)';$S;BIDI;
    'CB0_A':'(51,0,0)';$S;BIDI;
    'CB2_A':'(196,0,0)';$S;BIDI;
    'CB3_A':'(198,0,0)';$S;BIDI;
    'CB5_A':'(60,0,0)';$S;BIDI;
    'CB6_A':'(203,0,0)';$S;BIDI;
    'CA6_B':'(82,0,0)';$S;IN;
    'CA6_A':'(72,0,0)';$S;IN;
    'CA5_B':'(225,0,0)';$S;IN;
    'CA5_A':'(215,0,0)';$S;IN;
    'CA4_B':'(80,0,0)';$S;IN;
    'CA4_A':'(70,0,0)';$S;IN;
    'CA3_B':'(223,0,0)';$S;IN;
    'CA3_A':'(213,0,0)';$S;IN;
    'CA2_B':'(78,0,0)';$S;IN;
    'CA2_A':'(68,0,0)';$S;IN;
    'CA1_B':'(221,0,0)';$S;IN;
    'CA1_A':'(211,0,0)';$S;IN;
    'CA0_B':'(76,0,0)';$S;IN;
    'CA0_A':'(66,0,0)';$S;IN;
    'ALERT_N':'(62,0,0)';$S;OUT;
    'CB7_B':'(236,0,0)';$S;BIDI;
    'CB1_A':'(53,0,0)';$S;BIDI;
    'CB4_A':'(58,0,0)';$S;BIDI;
    'CB7_A':'(205,0,0)';$S;BIDI;
    'DQ31_A':'(194,0,0)';$S;BIDI;
    'DQS9_B_T||TDQS9_B_T||DBI4_B_N':'(0,93,0)';$S;BIDI;
    'DQS9_B_C||TDQS9_B_C':'(0,94,0)';$S;BIDI;
    'DQS9_A_T||TDQS9_A_T':'(0,201,0)';$S;BIDI;
    'DQS9_A_C||TDQS9_A_C':'(0,200,0)';$S;BIDI;
    'DQS8_A_T||TDQS8_A_T':'(0,190,0)';$S;BIDI;
    'DQS8_A_C||TDQS8_A_C':'(0,189,0)';$S;BIDI;
    'DQS7_B_C||TDQS7_B_C':'(0,271,0)';$S;BIDI;
    'DQS7_A_T||TDQS7_A_T':'(0,179,0)';$S;BIDI;
    'DQS6_B_T||TDQS6_B_T':'(0,261,0)';$S;BIDI;
    'DQS6_B_C||TDQS6_B_C':'(0,260,0)';$S;BIDI;
    'DQS6_A_C||TDQS6_A_C||DQS6_A_T||TDQS6_A_T':'(0,167,0)';$S;BIDI;
    'DQS5_B_T||TDQS5_B_T':'(0,250,0)';$S;BIDI;
    'DQS5_B_C||TDQS5_B_C':'(0,249,0)';$S;BIDI;
    'DQS5_A_T||TDQS5_A_T':'(0,157,0)';$S;BIDI;
    'DQS5_A_C||TDQS5_A_C||DQS5_A_T||TDQS5_A_T':'(0,156,0)';$S;BIDI;
    'DQS4_B_T':'(0,239,0)';$S;BIDI;
    'DQS4_B_C':'(0,238,0)';$S;BIDI;
    'DQS4_A_T':'(0,55,0)';$S;BIDI;
    'DQS4_A_C':'(0,56,0)';$S;BIDI;
    'DQS3_B_T':'(0,137,0)';$S;BIDI;
    'DQS3_B_C':'(0,138,0)';$S;BIDI;
    'DQS3_A_T':'(0,44,0)';$S;BIDI;
    'DQS3_A_C':'(0,45,0)';$S;BIDI;
    'DQS2_B_T':'(0,126,0)';$S;BIDI;
    'DQS2_B_C':'(0,127,0)';$S;BIDI;
    'DQS2_A_T':'(0,33,0)';$S;BIDI;
    'DQS2_A_C':'(0,34,0)';$S;BIDI;
    'DQS1_B_T':'(0,115,0)';$S;BIDI;
    'DQS1_B_C':'(0,116,0)';$S;BIDI;
    'DQS1_A_T':'(0,22,0)';$S;BIDI;
    'DQS1_A_C':'(0,23,0)';$S;BIDI;
    'DQS0_B_T':'(0,104,0)';$S;BIDI;
    'DQS0_B_C':'(0,105,0)';$S;BIDI;
    'DQS0_A_T':'(0,11,0)';$S;BIDI;
    'DQS0_A_C':'(0,12,0)';$S;BIDI;
    'DQS7_B_T||TDQS7_B_T':'(0,272,0)';$S;BIDI;
    'DQS8_B_C||TDQS8_B_C':'(0,282,0)';$S;BIDI;
    'DQS8_B_T||TDQS8_B_T':'(0,283,0)';$S;BIDI;
    'DQS6_A_T||TDQS6_A_T':'(0,168,0)';$S;BIDI;
    'DQS7_A_C||TDQS7_A_C':'(0,178,0)';$S;BIDI;
    'VSS0':'(0,0,6)';$S;
    'VSS1':'(0,0,8)';$S;
    'VSS2':'(0,0,10)';$S;
    'VSS3':'(0,0,13)';$S;
    'VSS4':'(0,0,15)';$S;
    'VSS5':'(0,0,17)';$S;
    'VSS6':'(0,0,19)';$S;
    'VSS7':'(0,0,21)';$S;
    'VSS8':'(0,0,24)';$S;
    'VSS9':'(0,0,26)';$S;
    'VSS10':'(0,0,28)';$S;
    'VSS11':'(0,0,30)';$S;
    'VSS12':'(0,0,32)';$S;
    'VSS13':'(0,0,35)';$S;
    'VSS14':'(0,0,37)';$S;
    'VSS15':'(0,0,39)';$S;
    'VSS16':'(0,0,41)';$S;
    'VSS17':'(0,0,43)';$S;
    'VSS18':'(0,0,46)';$S;
    'VSS19':'(0,0,48)';$S;
    'VSS20':'(0,0,50)';$S;
    'VSS21':'(0,0,52)';$S;
    'VSS22':'(0,0,54)';$S;
    'VSS23':'(0,0,57)';$S;
    'VSS24':'(0,0,59)';$S;
    'VSS25':'(0,0,61)';$S;
    'VSS26':'(0,0,63)';$S;
    'VSS27':'(0,0,65)';$S;
    'VSS28':'(0,0,67)';$S;
    'VSS29':'(0,0,69)';$S;
    'VSS30':'(0,0,71)';$S;
    'VSS31':'(0,0,73)';$S;
    'VSS32':'(0,0,75)';$S;
    'VSS33':'(0,0,77)';$S;
    'VSS34':'(0,0,79)';$S;
    'VSS35':'(0,0,81)';$S;
    'VSS36':'(0,0,83)';$S;
    'VSS37':'(0,0,85)';$S;
    'VSS38':'(0,0,88)';$S;
    'VSS39':'(0,0,90)';$S;
    'VSS40':'(0,0,92)';$S;
    'VSS41':'(0,0,95)';$S;
    'VSS42':'(0,0,97)';$S;
    'VSS43':'(0,0,99)';$S;
    'VSS44':'(0,0,101)';$S;
    'VSS45':'(0,0,103)';$S;
    'VSS46':'(0,0,106)';$S;
    'VSS47':'(0,0,108)';$S;
    'VSS48':'(0,0,110)';$S;
    'VSS49':'(0,0,112)';$S;
    'VSS50':'(0,0,114)';$S;
    'VSS51':'(0,0,117)';$S;
    'VSS52':'(0,0,119)';$S;
    'VSS53':'(0,0,121)';$S;
    'VSS54':'(0,0,123)';$S;
    'VSS55':'(0,0,125)';$S;
    'VSS56':'(0,0,128)';$S;
    'VSS57':'(0,0,130)';$S;
    'VSS59':'(0,0,134)';$S;
    'VSS63':'(0,0,143)';$S;
    'VSS64':'(0,0,151)';$S;
    'VSS65':'(0,0,153)';$S;
    'VSS66':'(0,0,155)';$S;
    'VSS67':'(0,0,158)';$S;
    'VSS68':'(0,0,160)';$S;
    'VSS69':'(0,0,162)';$S;
    'VSS70':'(0,0,164)';$S;
    'VSS71':'(0,0,166)';$S;
    'VSS72':'(0,0,169)';$S;
    'VSS73':'(0,0,171)';$S;
    'VSS74':'(0,0,173)';$S;
    'VSS75':'(0,0,175)';$S;
    'VSS76':'(0,0,177)';$S;
    'VSS77':'(0,0,180)';$S;
    'VSS78':'(0,0,182)';$S;
    'VSS79':'(0,0,184)';$S;
    'VSS80':'(0,0,186)';$S;
    'VSS81':'(0,0,188)';$S;
    'VSS82':'(0,0,191)';$S;
    'VSS83':'(0,0,193)';$S;
    'VSS84':'(0,0,195)';$S;
    'VSS85':'(0,0,197)';$S;
    'VSS86':'(0,0,199)';$S;
    'VSS87':'(0,0,202)';$S;
    'VSS88':'(0,0,204)';$S;
    'VSS89':'(0,0,206)';$S;
    'VSS90':'(0,0,208)';$S;
    'VSS91':'(0,0,210)';$S;
    'VSS92':'(0,0,212)';$S;
    'VSS93':'(0,0,214)';$S;
    'VSS94':'(0,0,216)';$S;
    'VSS95':'(0,0,219)';$S;
    'VSS96':'(0,0,222)';$S;
    'VSS97':'(0,0,224)';$S;
    'VSS98':'(0,0,226)';$S;
    'VSS99':'(0,0,228)';$S;
    'VSS101':'(0,0,233)';$S;
    'VSS103':'(0,0,237)';$S;
    'VSS105':'(0,0,242)';$S;
    'VSS106':'(0,0,244)';$S;
    'VSS107':'(0,0,246)';$S;
    'VSS108':'(0,0,248)';$S;
    'VSS109':'(0,0,251)';$S;
    'VSS110':'(0,0,253)';$S;
    'VSS111':'(0,0,255)';$S;
    'VSS112':'(0,0,257)';$S;
    'VSS113':'(0,0,259)';$S;
    'VSS114':'(0,0,262)';$S;
    'VSS115':'(0,0,264)';$S;
    'VSS116':'(0,0,266)';$S;
    'VSS117':'(0,0,268)';$S;
    'VSS118':'(0,0,270)';$S;
    'VSS119':'(0,0,273)';$S;
    'VSS120':'(0,0,275)';$S;
    'VSS121':'(0,0,277)';$S;
    'VSS122':'(0,0,279)';$S;
    'VSS123':'(0,0,281)';$S;
    'VSS124':'(0,0,284)';$S;
    'VSS125':'(0,0,286)';$S;
    'VSS126':'(0,0,288)';$S;
    'VIN_BULK0':'(0,0,1)';$S;
    'VIN_BULK1':'(0,0,145)';$S;
    'VIN_BULK2':'(0,0,146)';$S;
    'VSS100':'(0,0,230)';$S;
    'VSS102':'(0,0,235)';$S;
    'VSS104':'(0,0,240)';$S;
    'VSS58':'(0,0,132)';$S;
    'VSS60':'(0,0,136)';$S;
    'VSS61':'(0,0,139)';$S;
    'VSS62':'(0,0,141)';$S;
    'G1':'(0,0,G1)';$S;
    'G2':'(0,0,G2)';$S;
    'G3':'(0,0,G3)';$S;
end_primitive;
primitive 'SCONN56_123276793-SCONN56_1-2327679-3,SMLF,IO,DFHSA';body 'SCONN56_123276793';
    'P12V_B1':'(B1)';
    'P12V_B2':'(B2)';
    'P12V_B3':'(B3)';
    'P12V_B4':'(B4)';
    'P12V_B5':'(B5)';
    'P12V_B6':'(B6)';
    'GND_A1':'(A1)';
    'GND_A2':'(A2)';
    'GND_A3':'(A3)';
    'GND_A4':'(A4)';
    'GND_A5':'(A5)';
    'GND_A6':'(A6)';
    'MFG':'(B7)';BIDI;
    'RFU':'(B8)';BIDI;
    'DUALPORTEN#':'(B9)';BIDI;
    'P3V3_AUX':'(B11)';
    'PWRDIS':'(B12)';BIDI;
    'GND_B13':'(B13)';
    'GND_B16':'(B16)';
    'GND_B19':'(B19)';
    'GND_B22':'(B22)';
    'GND_B25':'(B25)';
    'GND_B28':'(B28)';
    'REFCLK_N0':'(B14)';BIDI;
    'REFCLK_P0':'(B15)';BIDI;
    'PET_N0':'(B17)';BIDI;
    'PET_P0':'(B18)';BIDI;
    'PET_N1':'(B20)';BIDI;
    'PET_P1':'(B21)';BIDI;
    'PET_N2':'(B23)';BIDI;
    'PET_P2':'(B24)';BIDI;
    'PET_N3':'(B26)';BIDI;
    'PET_P3':'(B27)';BIDI;
    'SMBCLK':'(A7)';BIDI;
    'SMBDAT':'(A8)';BIDI;
    'SMBRST#':'(A9)';BIDI;
    'LED#_ACTIVITY':'(A10)';BIDI;
    'PERST0#':'(B10)';BIDI;
    'PERST1#_CLKREQ#':'(A11)';BIDI;
    'PRSNT0#':'(A12)';BIDI;
    'GND_A13':'(A13)';
    'GND_A16':'(A16)';
    'GND_A19':'(A19)';
    'GND_A22':'(A22)';
    'GND_A25':'(A25)';
    'GND_A28':'(A28)';
    'REFCLK_N1':'(A14)';BIDI;
    'REFCLK_P1':'(A15)';BIDI;
    'PER_N0':'(A17)';BIDI;
    'PER_P0':'(A18)';BIDI;
    'PER_N1':'(A20)';BIDI;
    'PER_P1':'(A21)';BIDI;
    'PER_N2':'(A23)';BIDI;
    'PER_P2':'(A24)';BIDI;
    'PER_N3':'(A26)';BIDI;
    'PER_P3':'(A27)';BIDI;
    'G2':'(G2)';
    'G1':'(G1)';
end_primitive;
primitive 'SCONN75K_APCI0155P004A-SCONN75K_APCI0155-P004A,SMLA';body 'SCONN75K_APCI0155P004A';
    '3.3V_1':'(2)';
    '3.3V_2':'(4)';
    'DAS_DSS#||LED1#':'(10)';BIDI;
    '3.3V_3':'(12)';
    '3.3V_4':'(14)';
    '3.3V_5':'(16)';
    '3.3V_6':'(18)';
    'DEVSLP':'(38)';IN;
    'PERST#':'(50)';IN;
    'CLKREQ#':'(52)';BIDI;
    'PEWAKE#':'(54)';BIDI;
    'NC18':'(58)';OUT;
    'SUSCLK':'(68)';IN;
    '3.3V_7':'(70)';
    '3.3V_8':'(72)';
    '3.3V_9':'(74)';
    'PERN0||SATA-B+':'(41)';BIDI;
    'PERP0||SATA-B-':'(43)';BIDI;
    'PETN0||SATA-A-':'(47)';BIDI;
    'PETP0||SATA-A+':'(49)';BIDI;
    'GND11':'(57)';
    'NC19':'(67)';OUT;
    'PEDET':'(69)';OUT;
    'GND12':'(71)';
    'GND13':'(73)';
    'GND14':'(75)';
    'G1':'(G1)';
    'G2':'(G2)';
    'NC1':'(6)';OUT;
    'NC2':'(8)';OUT;
    'NC3':'(20)';OUT;
    'NC10':'(34)';OUT;
    'NC17':'(56)';OUT;
    'NC16':'(48)';OUT;
    'NC15':'(46)';OUT;
    'NC14':'(44)';OUT;
    'NC13':'(42)';OUT;
    'NC12':'(40)';OUT;
    'NC11':'(36)';OUT;
    'NC9':'(32)';OUT;
    'NC8':'(30)';OUT;
    'NC7':'(28)';OUT;
    'NC6':'(26)';OUT;
    'NC5':'(24)';OUT;
    'NC4':'(22)';OUT;
    'GND1':'(1)';
    'GND2':'(3)';
    'GND3':'(9)';
    'GND4':'(15)';
    'GND5':'(21)';
    'GND6':'(27)';
    'GND7':'(33)';
    'GND8':'(39)';
    'GND9':'(45)';
    'GND10':'(51)';
    'PERN3':'(5)';BIDI;
    'PERP3':'(7)';BIDI;
    'PETN3':'(11)';BIDI;
    'PETP3':'(13)';BIDI;
    'PERN2':'(17)';BIDI;
    'PERP2':'(19)';BIDI;
    'PETN2':'(23)';BIDI;
    'PETP2':'(25)';BIDI;
    'PERN1':'(29)';BIDI;
    'PERP1':'(31)';BIDI;
    'PETN1':'(35)';BIDI;
    'PETP1':'(37)';BIDI;
    'REFCLKN':'(53)';IN;
    'REFCLKP':'(55)';IN;
end_primitive;
primitive 'SCONN8_G802M0083150RD3HR-SCONN8_G802M0083150RD3HR,A';body 'SCONN8_G802M0083150RD3HR';
    '1':'(1)';BIDI;
    '2':'(2)';BIDI;
    '3':'(3)';BIDI;
    '4':'(4)';BIDI;
    '5':'(5)';BIDI;
    '6':'(6)';BIDI;
    '7':'(7)';BIDI;
    '8':'(8)';BIDI;
end_primitive;
primitive 'SN74AUC2G66DCTR-SN74AUC2G66DCTR,SMLF,IC,AL2G0066C00';body 'SN74AUC2G66DCTR';
    '1A':'(1)';BIDI;
    '1C':'(7)';BIDI;
    '2A':'(5)';BIDI;
    '2C':'(3)';BIDI;
    'VCC':'(8)';
    'GND':'(4)';
    '1B':'(2)';BIDI;
    '2B':'(6)';BIDI;
end_primitive;
primitive 'SN74AVC2T245RSWR-SN74AVC2T245RSWR,SMLF,IC,AL02T245A';body 'SN74AVC2T245RSWR';
    'DIR2':'(1)';IN;
    'OE_#':'(2)';IN;
    'GND':'(3)';
    'B2':'(4)';OUT;
    'B1':'(5)';OUT;
    'VCCB':'(6)';
    'VCCA':'(7)';
    'A1':'(8)';IN;
    'A2':'(9)';IN;
    'DIR1':'(10)';IN;
end_primitive;
primitive 'SN74AVC4T774PWR-SN74AVC4T774PWR,SMLF,IC,AL04T774K00';body 'SN74AVC4T774PWR';
    'DIR1':'(1)';IN;
    'DIR2':'(2)';IN;
    'A1':'(3)';BIDI;
    'A2':'(4)';BIDI;
    'A3':'(5)';BIDI;
    'A4':'(6)';BIDI;
    'DIR3':'(7)';IN;
    'DIR4':'(8)';IN;
    'OE':'(9)';IN;
    'GND':'(10)';
    'B4':'(11)';BIDI;
    'B3':'(12)';BIDI;
    'B2':'(13)';BIDI;
    'B1':'(14)';BIDI;
    'VCCB':'(15)';
    'VCCA':'(16)';
end_primitive;
primitive 'SN74LVC1G07DBVR_SMLF-SN74LVC1G07DBVR,EMPTY,AL1G000A';body 'SN74LVC1G07DBVR';
    'A':'(2)';IN;
    'Y':'(4)';OUT;
    'NC':'(1)';OUT;
    'VCC':'(5)';
    'GND':'(3)';
end_primitive;
primitive 'SN74LVC1G07DBVR_SMLF-SN74LVC1G07DBVR,IC,AL1G0007024';body 'SN74LVC1G07DBVR';
    'A':'(2)';IN;
    'Y':'(4)';OUT;
    'NC':'(1)';OUT;
    'VCC':'(5)';
    'GND':'(3)';
end_primitive;
primitive 'SN74LVC1G11DCKR-SN74LVC1G11DCKR,SMLF,IC,ALLVC1G1000';body 'SN74LVC1G11DCKR';
    'A':'(1)';IN;
    'B':'(3)';IN;
    'C':'(6)';IN;
    'VCC':'(5)';
    'Y':'(4)';OUT;
    'GND':'(2)';
end_primitive;
primitive 'SN74LVC2G07DCKR_SMLF-SN74LVC2G07DCKR,IC,AL002G07006';body 'SN74LVC2G07DCKR';
    '1A':'(1)';IN;
    '2A':'(3)';IN;
    '1Y':'(6)';OUT;
    '2Y':'(4)';OUT;
    'GND':'(2)';
    'VCC':'(5)';
end_primitive;
primitive 'SS15P3SM386A-SS15P3S-M3/86A,SMLF,IC,BC015P3SZ00';body 'SS15P3SM386A';
    'ANODE_1':'(1)';IN;
    'CATHODE':'(K)';OUT;
    'ANODE_2':'(2)';IN;
end_primitive;
primitive 'SW20S_DHNF10FQTR-SW20S_DHNF-10F-Q-T/R,SMLF,MECH,DHA';body 'SW20S_DHNF10FQTR';
    '1':'(1)';BIDI;
    '2':'(2)';BIDI;
    '3':'(3)';BIDI;
    '4':'(4)';BIDI;
    '11':'(11)';BIDI;
    '12':'(12)';BIDI;
    '13':'(13)';BIDI;
    '14':'(14)';BIDI;
    '5':'(5)';BIDI;
    '6':'(6)';BIDI;
    '7':'(7)';BIDI;
    '8':'(8)';BIDI;
    '15':'(15)';BIDI;
    '16':'(16)';BIDI;
    '17':'(17)';BIDI;
    '18':'(18)';BIDI;
    '19':'(19)';BIDI;
    '20':'(20)';BIDI;
    '9':'(9)';BIDI;
    '10':'(10)';BIDI;
end_primitive;
primitive 'TCA9548APWR-TCA9548APWR,SMLF,IC,AL009548K02';body 'TCA9548APWR';
    'A0':'(1)';IN;
    'A1':'(2)';IN;
    'RESET#':'(3)';IN;
    'SD0':'(4)';BIDI;
    'SC0':'(5)';BIDI;
    'SD1':'(6)';BIDI;
    'SC1':'(7)';BIDI;
    'SD2':'(8)';BIDI;
    'SC2':'(9)';BIDI;
    'SD3':'(10)';BIDI;
    'SC3':'(11)';BIDI;
    'GND':'(12)';
    'VCC':'(24)';
    'SDA':'(23)';BIDI;
    'SCL':'(22)';BIDI;
    'A2':'(21)';IN;
    'SC7':'(20)';BIDI;
    'SD7':'(19)';BIDI;
    'SC6':'(18)';BIDI;
    'SD6':'(17)';BIDI;
    'SC5':'(16)';BIDI;
    'SD5':'(15)';BIDI;
    'SC4':'(14)';BIDI;
    'SD4':'(13)';BIDI;
end_primitive;
primitive 'TDR_3P_TH2-EMPTY,N_A';body 'TDR_3P';
    'GND':'(1)';
    'IO1':'(2)';
    'IO2':'(3)';
end_primitive;
primitive 'TPS71715DCKR-TPS71715DCKR,SMLF,EMPTY,AL071715001';body 'TPS71715DCKR';
    'GND':'(2)';
    'EN':'(3)';IN;
    'IN':'(1)';IN;
    'NR||FB':'(4)';OUT;
    'OUT':'(5)';OUT;
end_primitive;
primitive 'TP_TDR_4P_FTS_TH-TP_TDR_4P_DIP,EMPTY,TP15';body 'TP_TDR_4P_FTS';
    'P1':'(2)';BIDI;
    'P2':'(3)';BIDI;
    'S1':'(1)';BIDI;
    'S2':'(4)';BIDI;
end_primitive;
primitive 'TP_TP-NA,TP26';body 'TP';
    'TP':'(1)';
end_primitive;
primitive 'TP_TP-NA,TP30';body 'TP';
    'TP':'(1)';
end_primitive;
primitive 'TUSB211IRWBR-TUSB211IRWBR,SMLF,EMPTY,AL000211007';body 'TUSB211IRWBR';
    'RSTN':'(5)';IN;
    'D2M':'(8)';BIDI;
    'VREG':'(11)';OUT;
    'TEST':'(3)';IN;
    'VCC':'(12)';
    'ENA_HS':'(9)';OUT;
    'CD':'(4)';OUT;
    'D1M':'(1)';BIDI;
    'D1P':'(2)';BIDI;
    'D2P':'(7)';BIDI;
    'EQ':'(6)';IN;
    'GND':'(10)';
end_primitive;
primitive 'TUSB8042AIRGCR-TUSB8042AIRGCR,SMLF,IC,AL008042000';body 'TUSB8042AIRGCR';
    'USB_SSRXM_UP':'(59,0)';$S;IN;
    'USB_SSRXM_DN2':'(15,0)';$S;IN;
    'USB_SSRXP_DN2':'(14,0)';$S;IN;
    'USB_SSTXP_DN2':'(11,0)';$S;OUT;
    'USB_SSTXM_DN2':'(12,0)';$S;OUT;
    'USB_DM_DN3':'(18,0)';$S;BIDI;
    'USB_SSTXM_DN3':'(20,0)';$S;OUT;
    'USB_SSTXP_UP':'(55,0)';$S;OUT;
    'USB_DM_UP':'(54,0)';$S;BIDI;
    'USB_SSRXM_DN3':'(23,0)';$S;IN;
    'USB_DP_DN4':'(24,0)';$S;BIDI;
    'USB_DP_DN3':'(17,0)';$S;BIDI;
    'USB_SSRXP_UP':'(58,0)';$S;IN;
    'USB_DP_DN2':'(9,0)';$S;BIDI;
    'USB_SSRXP_DN1':'(6,0)';$S;IN;
    'USB_SSTXP_DN4':'(26,0)';$S;OUT;
    'USB_DM_DN1':'(2,0)';$S;BIDI;
    'USB_DM_DN4':'(25,0)';$S;BIDI;
    'USB_SSRXP_DN4':'(29,0)';$S;IN;
    'USB_SSRXM_DN4':'(30,0)';$S;IN;
    'USB_SSRXP_DN3':'(22,0)';$S;IN;
    'TH_VSS':'(TH,0)';$S;
    'USB_DP_UP':'(53,0)';$S;BIDI;
    'USB_SSTXM_UP':'(56,0)';$S;OUT;
    'USB_DP_DN1':'(1,0)';$S;BIDI;
    'USB_SSRXM_DN1':'(7,0)';$S;IN;
    'USB_SSTXP_DN1':'(3,0)';$S;OUT;
    'USB_SSTXM_DN1':'(4,0)';$S;OUT;
    'USB_DM_DN2':'(10,0)';$S;BIDI;
    'USB_SSTXP_DN3':'(19,0)';$S;OUT;
    'USB_SSTXM_DN4':'(27,0)';$S;OUT;
    'USB_VBUS':'(48,0)';$S;IN;
    'PWRCTL1||BATEN1':'(36,0)';$S;BIDI;
    'PWRCTL2||BATEN2':'(35,0)';$S;BIDI;
    'PWRCTL3||BATEN3':'(33,0)';$S;BIDI;
    'PWRCTL4||BATEN4':'(32,0)';$S;BIDI;
    'PWRCTL_POL':'(41,0)';$S;BIDI;
    'GRSTZ':'(50,0)';$S;IN;
    'OVERCUR1Z':'(46,0)';$S;IN;
    'OVERCUR2Z':'(47,0)';$S;IN;
    'OVERCUR3Z':'(44,0)';$S;IN;
    'OVERCUR4Z':'(43,0)';$S;IN;
    'TEST':'(49,0)';$S;IN;
    'USB_R1':'(64,0)';$S;IN;
    'NC_1':'(60,0)';$S;OUT;
    'VDD_13':'(0,13)';$S;
    'SDA||SMBDAT':'(0,37)';$S;BIDI;
    'VDD_28':'(0,28)';$S;
    'VDD33_16':'(0,16)';$S;
    'VDD33_34':'(0,34)';$S;
    'VDD33_52':'(0,52)';$S;
    'FULLPWRMGMTZ||FULLAUTOZ||SMBA1||SS_UP':'(0,40)';$S;BIDI;
    'GANGED||SMBA2||HS_UP':'(0,42)';$S;BIDI;
    'SCL||SMBCLK':'(0,38)';$S;BIDI;
    'SMBUSZ||SS_SUSPEND':'(0,39)';$S;BIDI;
    'VDD33_63':'(0,63)';$S;
    'VDD_51':'(0,51)';$S;
    'AUTOENZ||HS_SUSPEND':'(0,45)';$S;BIDI;
    'VDD_8':'(0,8)';$S;
    'VDD_5':'(0,5)';$S;
    'VDD_57':'(0,57)';$S;
    'VDD_21':'(0,21)';$S;
    'VDD_31':'(0,31)';$S;
    'XO':'(0,61)';$S;OUT;
    'XI':'(0,62)';$S;IN;
end_primitive;
primitive 'ZENER_AC-5.0SMDJ14A,SMLF,IC,BC0MDJ14000';body 'ZENER_AC';
    'A':'(A)';BIDI;
    'C':'(C)';BIDI;
end_primitive;
END.
